# ZAIUS-MB-PVT-X04-BOM_X31_20180131_Final.xls.xlsx — Changelist (bom)
| BOM Change List Date:Fri May 19 11:40:38 GMT+08:00 2017 |  |  |  |  |  |  |  |  |  |
| New BOM file : C:\<user>\ZAIUS-MB-DVT-X03-BOM_X23_20170516.xls |  |  |  |  |  |  |  |  |  |
| Old BOM file : C:\<user>\ZAIUS-MB-DVT-X03-BOM_X22_20170512.xls |  |  |  |  |  |  |  |  |  |
| ##### Add Parts |  |  |  |  |  |  |  |  |  |
| Item | Location | Qty | Foxconn P/N | Part Description | Manufacturer Full Name | Manufacturer P/N | RoHS | Sheet |  |
| 1 | R1848,R1849 | 2 | 610107A00-017-G | RES,0 Ohm,+/-5%,1/16W,G,SMD0402 | KOA SPEER ELECTRONICS, INC. | RK73Z1ETTP | N | PWA BOM |  |
|  |  |  | 610107A00-024-G | RES,0 Ohm,+/-5%,1/16W,G,SMD0402 | PANASONIC INDUSTRIAL CO.,LTD. | ERJ2GE0R00X | G | PWA BOM |  |
|  |  |  | 610107A00-029-G | RES,0 Ohm,+/-5%,1/16W,G,SMD0402 | VISHAY ENTER TECHNO LOGY.INC | CRCW04020000Z0ED | G | PWA BOM |  |
| 2 | R1558 | 1 | 61010LA00-017-G | RES,4.7KOhm,+/-1%,1/16W,G,SMD0402 | KOA SPEER ELECTRONICS, INC. | RK73H1ETTP4701F | N | PWA BOM |  |
|  |  |  | 61010LA00-029-G | RES,4.7KOhm,+/-1%,1/16W,G,SMD0402 | VISHAY ENTER TECHNO LOGY.INC | CRCW04024K70FKED | G | PWA BOM |  |
| 3 | Q15 | 1 | 510301N00-223-G | MOS N,2N7002LT1G,60V,0.115A,7.5ohm@5V,G,SOT23-3,SMD | ON SEMICONDUCTOR CORP | 2N7002LT1G | N | PWA BOM |  |
| ##### Remove Parts |  |  |  |  |  |  |  |  |  |
| Item | Location | Qty | Foxconn P/N | Part Description | Manufacturer Full Name | Manufacturer P/N | RoHS | Sheet |  |
| 1 | R1811 | 1 | 610102700-017-G | RES,49.9 Ohm,+/-1%,1/16W,G,SMD0402 | KOA SPEER ELECTRONICS, INC. | RK73H1ETTP49R9F | N | PWA BOM |  |
|  |  |  | 610102700-029-G | RES,49.9 Ohm,+/-1%,1/16W,G,SMD0402 | VISHAY ENTER TECHNO LOGY.INC | CRCW040249R9FKED | G | PWA BOM |  |
|  |  |  | 610102700-024-G | RES,49.9 Ohm,+/-1%,1/16W,G,SMD0402 | PANASONIC INDUSTRIAL CO.,LTD. | ERJ2RKF49R9X | G | PWA BOM |  |
| ##### Change Parts |  |  |  |  |  |  |  |  |  |
| Item | Location | Qty | Foxconn P/N | Part Description | Manufacturer Full Name | Manufacturer P/N | RoHS | Sheet | Remark |
| 1 | DN1 | 1 | 521803M00-227-G | Diode,Array-TVS,UCLAMP0508T.TCT,Level 4,5V,G,SLP,SMD-9 | SEMTECH CORPORATION. | UCLAMP0508T.TCT | Y | PWA BOM | In New BOM |
|  |  |  | 521802K00-223-G | Diode,Array-TVS,NUP8011MUTAG,UDFN,9P,G | ON SEMICONDUCTOR CORP | NUP8011MUTAG |  | PWA BOM | In New BOM |
|  | DN1 | 1 | 521803M00-227-G | Diode,Array-TVS,UCLAMP0508T.TCT,Level 4,5V,G,SLP,SMD-9 | SEMTECH CORPORATION. | UCLAMP0508T.TCT | Y | PWA BOM | In Old BOM |
| 2 | D33 | 1 | 520308D00-237-G | DIODE,Schottky Rectifier,1N5819HW-7-F,40V,1A,G,SOD123-2,SMD | DIODES INCORPORATION | 1N5819HW-7-F | N | PWA BOM | In New BOM |
|  |  |  | 520318S00-223-G | Diode,Schottky,MBR140SFT3G,40V,1A,SOD-123FL,2P,G | ON SEMICONDUCTOR CORP | MBR140SFT3G | G | PWA BOM | In New BOM |
|  |  |  | 52030P100-223-G | Diode,Schottky,MBR140SFT1G,40V,1A,SOD-123FL,2P,G | ON SEMICONDUCTOR CORP | MBR140SFT1G | G | PWA BOM | In New BOM |
|  | D33 | 1 | 520308D00-237-G | DIODE,Schottky Rectifier,1N5819HW-7-F,40V,1A,G,SOD123-2,SMD | DIODES INCORPORATION | 1N5819HW-7-F | N | PWA BOM | In Old BOM |
|  |  |  | MBR140SFT3G | Diode,Schottky,MBR140SFT3G,40V,1A,SOD-123FL,2P,G | ON SEMICONDUCTOR CORP | MBR140SFT3G | G | PWA BOM | In Old BOM |
|  |  |  | 52030P100-223-G | Diode,Schottky,MBR140SFT1G,40V,1A,SOD-123FL,2P,G | ON SEMICONDUCTOR CORP | MBR140SFT1G | G | PWA BOM | In Old BOM |
| 3 | FS4,FS9,FS12,FS15,FS16,FS21 | 6 | 730102701-086-G | Fuse,Fast acting,32V,7A,G,SMD1206 | LITTELFUSE FAR EAST PTE LTD | 0440007.WR |  | PWA BOM | In New BOM |
|  |  |  | 730102704-088-G | Fuse,Fast acting,32V,7A,G,SMD1206 | Cooper Bussmann | CC12H7A-TR |  | PWA BOM | In New BOM |
|  | FS4,FS9,FS12,FS15,FS16,FS21 | 6 | 730102701-086-G | Fuse,Fast acting,32V,7A,G,SMD1206 | LITTELFUSE FAR EAST PTE LTD | 0440007.WR |  | PWA BOM | In Old BOM |
| 4 | L22,L23,L24,L25 | 4 | 720105P00-016-G | FB,80 Ohm@100MHz,+/-25%,500mA,150mOhm,G,SMD0603 | TDK ELECTRONICS EUROPE GMBH | MMZ1608S800AT | N | PWA BOM | In New BOM |
|  |  |  | GMLB-160808-0080P-N8 | FB,80 Ohm@100MHz,+/-25%,500mA,150mOhm,G,SMD0603 | MAG.LAYERS, SCIENTIFIC-TECHNICS (KUNSHAN) CO., LTD. | GMLB-160808-0080P-N8 |  | PWA BOM | In New BOM |
|  | L22,L23,L24,L25 | 4 | 720105P00-016-G | FB,80 Ohm@100MHz,+/-25%,500mA,150mOhm,G,SMD0603 | TDK ELECTRONICS EUROPE GMBH | MMZ1608S800AT | N | PWA BOM | In Old BOM |
| 5 | L26,L28,L47 | 3 | 72010CB00-015-G | FB,22 Ohm@100MHz,+/-25%,6A,10mOhm,G,SMD0805 | MURATA ELEC. NORTH AMERICA | BLM21PG220SN1D | N | PWA BOM | In New BOM |
|  |  |  | 72010CB00-059-G | FB,22 Ohm@100MHz,+/-25%,6A,10mOhm,G,SMD0805 | TAI-TECH ADVANCED ELECTRONICS CO., LTD. | HCB2012KF-220T60 |  | PWA BOM | In New BOM |
|  |  |  | 72010Y600-174-G | FB,22 Ohm@100MHz,+/-25%,6A,8mOhm,G,SMD0805 | MAX ECHO TECHNOLOGIES CORP | BCMS201209A220 |  | PWA BOM | In New BOM |
|  | L26,L28,L47 | 3 | 72010CB00-015-G | FB,22 Ohm@100MHz,+/-25%,6A,10mOhm,G,SMD0805 | MURATA ELEC. NORTH AMERICA | BLM21PG220SN1D | N | PWA BOM | In Old BOM |
| 6 | L35,L37,L38,L39,L40,L41,L42 | 7 | 72010MK00-015-G | FB,80 Ohm@100MHz,+/-25%,1.5A,70mOhm,G,SMD0402 | MURATA ELEC. NORTH AMERICA | BLM15PD800SN1D | N | PWA BOM | In New BOM |
|  |  |  | 72010MK00-174-G | FB,80 Ohm@100MHz,+/-25%,1.5A,Multilayer,70mOhm,SMD0402,G | MAX ECHO TECHNOLOGIES CORP | ACMS100505A800 1.5A |  | PWA BOM | In New BOM |
|  | L35,L37,L38,L39,L40,L41,L42 | 7 | 72010MK00-015-G | FB,80 Ohm@100MHz,+/-25%,1.5A,70mOhm,G,SMD0402 | MURATA ELEC. NORTH AMERICA | BLM15PD800SN1D | N | PWA BOM | In Old BOM |
| 7 | PBMR113,PAMR113,PBER115,PAFR115,PAER115,PBFR116,PBAR119,PAAR119 | 8 | 61100RU00-017-G | RES,59 Ohm,+/-1%,1/16W,G,SMD0402 | KOA SPEER ELECTRONICS, INC. | RN731ETTP59R0F25 |  | PWA BOM | In New BOM |
|  | PBMR113,PAMR113,PBER115,PAFR115,PAER115,PBFR116,PBAR119,PAAR119 | 8 | 61100RU00-017-G | RES,59 Ohm,+/-1%,1/16W,G,SMD0402 | KOA SPEER ELECTRONICS, INC. | RN731ETTP59R0F25 |  | PWA BOM | In Old BOM |
|  |  |  | 61015NF00-024-G | RES,59 Ohm,+/-1%,1/10W,G,SMD0402 | PANASONIC INDUSTRIAL CO.,LTD. | ERJ2RKF59R0X | G | PWA BOM | In Old BOM |
| 8 | PBFFS1,PBEFS1,PAMFS1,PAFFS1,PAEFS1,PAMFS2 | 6 | 730100L00-086-G | Fuse,Very fast acting,125V,5A,G,SMD | LITTELFUSE FAR EAST PTE LTD | 0451005.MRL | N | PWA BOM | In New BOM |
|  |  |  | 730107B01-088-G | Fuse,Very fast acting,125V,5A,G,SMD | COOPER BUSSMANN, INC. | CB61F5A-TR2 |  | PWA BOM | In New BOM |
|  | PBFFS1,PBEFS1,PAMFS1,PAFFS1,PAEFS1,PAMFS2 | 6 | 730100L00-086-G | Fuse,Very fast acting,125V,5A,G,SMD | LITTELFUSE FAR EAST PTE LTD | 0451005.MRL | N | PWA BOM | In Old BOM |
| 9 | PSTL1,PSLL1,PSFL1,PSEL1,PSDL1,PQPL1,PFRL1,PEEL1,PEDL1,PBLL1,PALL1,PUAL2,PSIL2,PSAL2,PRAL2,PQAL2,PPAL2,PIAL2,PFAL2,PERL2,PEAL2,PQPL3 | 22 | 72010RE00-015-G | FB,26 Ohm@100MHz,+/-25%,6A,7mOhm,G,SMD0603 | MURATA ELEC. NORTH AMERICA | BLM18KG260TN1D | N | PWA BOM | In New BOM |
|  |  |  | 72010SJ00-059-G | FB,26 Ohm@100MHz,+/-25%,6A,10mOhm,G,SMD0603 | TAI-TECH ADVANCED ELECTRONICS CO., LTD. | HCB1608KF-260T60 |  | PWA BOM | In New BOM |
|  | PSTL1,PSLL1,PSFL1,PSEL1,PSDL1,PQPL1,PFRL1,PEEL1,PEDL1,PBLL1,PALL1,PUAL2,PSIL2,PSAL2,PRAL2,PQAL2,PPAL2,PIAL2,PFAL2,PERL2,PEAL2,PQPL3 | 22 | 72010RE00-015-G | FB,26 Ohm@100MHz,+/-25%,6A,7mOhm,G,SMD0603 | MURATA ELEC. NORTH AMERICA | BLM18KG260TN1D | N | PWA BOM | In Old BOM |
| 10 | PALL2,PBLL4 | 2 | 630351600-034-G | IND,470nH@100KHz,+/-20%,30A,1.68mOhm,SHLD,G,SMD | CYNTEC CO. LTD | PCMB104T-R47MS |  | PWA BOM | In New BOM |
|  |  |  | 63035YA00-051-G | IND,470nH@100KHz,+/-20%,28A,1.5mOhm,SHLD,G,SMD | PULSE ELECTRONICS (SINGAPORE) | PA4342.471NLT |  | PWA BOM | In New BOM |
|  |  |  | 63035Y900-129-G | IND,470nH@100KHz,+/-20%,30A,1.68mOhm,SHLD,G,SMD | MAG.LAYERS, SCIENTIFIC-TECHNICS (KUNSHAN) CO., LTD. | SPS-10DZ-R47M-X2 |  | PWA BOM | In New BOM |
|  | PALL2,PBLL4 | 2 | 630351600-034-G | IND,470nH@100KHz,+/-20%,30A,1.68mOhm,SHLD,G,SMD | CYNTEC CO. LTD | PCMB104T-R47MS |  | PWA BOM | In Old BOM |
| 11 | PBNL1,PANL1 | 2 | 630330G00-088-G | IND,300nH@100KHz,+/-10%,32.5A,304.5uOhm,SHLD,G,SMD | COOPER BUSSMANN, INC. | FP0906R1-R30-R |  | PWA BOM | In New BOM |
|  |  |  | 630332A01-051-G | Coil Ind,Shielded(SHLD),300nH@100KHz,+/-10%,34A,290uOhm,SMD,9.2*6.2*7.8,G | PULSE ELECTRONICS (SINGAPORE) | PA3288.301HLT |  | PWA BOM | In New BOM |
|  |  |  | MSI-900608-R30K-E | IND,300nH@100KHz,+/-10%,32.5A,290uOhm,SHLD,G,SMD | MAG.LAYERS, SCIENTIFIC-TECHNICS (KUNSHAN) CO., LTD. | MSI-900608-R30K-E |  | PWA BOM | In New BOM |
|  | PBNL1,PANL1 | 2 | 630330G00-088-G | IND,300nH@100KHz,+/-10%,32.5A,304.5uOhm,SHLD,G,SMD | COOPER BUSSMANN, INC. | FP0906R1-R30-R |  | PWA BOM | In Old BOM |
| 12 | PANR6,PBNR7,R355,R356,R361,R362 | 6 | 61011JH00-017-G | RES,19.1KOhm,+/-1%,1/16W,G,SMD0402 | KOA SPEER ELECTRONICS, INC. | RK73H1ETTP1912F | N | PWA BOM | In New BOM |
|  |  |  | 61011JH00-011-G | RES,19.1KOhm,+/-1%,1/16W,G,SMD0402 | YAGEO | RC0402FR-0719K1L |  | PWA BOM | In New BOM |
|  |  |  | 61011JH00-044-G | RES,19.1KOhm,+/-1%,1/16W,G,SMD0402 | TA-I | RM04FTN1912 |  | PWA BOM | In New BOM |
|  | PANR6,PBNR7,R355,R356,R361,R362 | 6 | 61011JH00-017-G | RES,19.1KOhm,+/-1%,1/16W,G,SMD0402 | KOA SPEER ELECTRONICS, INC. | RK73H1ETTP1912F | N | PWA BOM | In Old BOM |
| 13 | PUAL1,PSAL1,PRAL1,PQAL1,PPAL1,PIAL1,PFAL1,PEAL1 | 8 | 630335M00-088-G | IND,820nH@100KHz,+/-20%,13A,8mOhm,SHLD,G,SMD | COOPER BUSSMANN, INC. | HCM0703-R82-R |  | PWA BOM | In New BOM |
|  |  |  | 63035Y800-051-G | IND,820nH@100KHz,+/-20%,13A,8mOhm,SHLD,G,SMD | PULSE ELECTRONICS (SINGAPORE) | PA4341.821NLT |  | PWA BOM | In New BOM |
|  |  |  | 63032RP05-129-G | IND,820nH@100KHz,+/-20%,13A,8mOhm,SHLD,G,SMD | MAG.LAYERS, SCIENTIFIC-TECHNICS (KUNSHAN) CO., LTD. | SPS-06CZ-R82M-V1 |  | PWA BOM | In New BOM |
|  | PUAL1,PSAL1,PRAL1,PQAL1,PPAL1,PIAL1,PFAL1,PEAL1 | 8 | 630335M00-088-G | IND,820nH@100KHz,+/-20%,13A,8mOhm,SHLD,G,SMD | COOPER BUSSMANN, INC. | HCM0703-R82-R |  | PWA BOM | In Old BOM |
| 14 | PUAR4,PSAR4,PRAR4,PQAR4,PPAR4,PIAR4,PFAR4,PEAR4,PUAR6,PSAR6,PRAR6,PQAR6,PPAR6,PIAR6,PFAR6,PEAR6 | 16 | 611004D00-017-G | RES,1.5KOhm,+/-0.1%,1/16W,G,SMD0402 | KOA SPEER ELECTRONICS, INC. | RN731ETTP1501B25 |  | PWA BOM | In New BOM |
|  |  |  | 611004D00-029-G | RES,1.5KOhm,+/-0.1%,1/16W,G,SMD0402 | VISHAY ENTER TECHNO LOGY.INC | TNPW04021K50BEED |  | PWA BOM | In New BOM |
|  | PUAR4,PSAR4,PRAR4,PQAR4,PPAR4,PIAR4,PFAR4,PEAR4,PUAR6,PSAR6,PRAR6,PQAR6,PPAR6,PIAR6,PFAR6,PEAR6 | 16 | 611004D00-017-G | RES,1.5KOhm,+/-0.1%,1/16W,G,SMD0402 | KOA SPEER ELECTRONICS, INC. | RN731ETTP1501B25 |  | PWA BOM | In Old BOM |
| 15 | PUAR8,PSAR8,PRAR8,PQAR8,PPAR8,PIAR8,PFAR8,PEAR8,PUAR11,PSAR11,PRAR11,PQAR11,PPAR11,PIAR11,PFAR11,PEAR11 | 16 | 610117F00-017-G | RES,5.76KOhm,+/-1%,1/16W,G,SMD0402 | KOA SPEER ELECTRONICS, INC. | RK73H1ETTP5761F | N | PWA BOM | In New BOM |
|  |  |  | 610117F00-011-G | RES,5.76KOhm,+/-1%,1/16W,G,SMD0402 | YAGEO CORPORATION COMPONENT | RC0402FR-075K76L |  | PWA BOM | In New BOM |
|  |  |  | 610117F00-044-G | RES,5.76KOhm,+/-1%,1/16W,G,SMD0402 | TA-I TECHNOLOGY CO., LTD. | RM04FTN5761 |  | PWA BOM | In New BOM |
|  | PUAR8,PSAR8,PRAR8,PQAR8,PPAR8,PIAR8,PFAR8,PEAR8,PUAR11,PSAR11,PRAR11,PQAR11,PPAR11,PIAR11,PFAR11,PEAR11 | 16 | 610117F00-017-G | RES,5.76KOhm,+/-1%,1/16W,G,SMD0402 | KOA SPEER ELECTRONICS, INC. | RK73H1ETTP5761F | N | PWA BOM | In Old BOM |
| 16 | PSLR17,PSFR17,PSER17,PSDR17,PQPR17,PFRR17,PEER17,PEDR17,PEDR19 | 9 | 611004M00-017-G | RES,16.5KOhm,+/-0.1%,1/16W,G,SMD0402 | KOA SPEER ELECTRONICS, INC. | RN731ETTP1652B25 |  | PWA BOM | In New BOM |
|  |  |  | 611004M00-024-G | RES,16.5KOhm,+/-0.1%,1/16W,G,SMD0402 | PANASONIC INDUSTRIAL CO.,LTD. | ERA2AEB1652X |  | PWA BOM | In New BOM |
|  | PSLR17,PSFR17,PSER17,PSDR17,PQPR17,PFRR17,PEER17,PEDR17,PEDR19 | 9 | 611004M00-017-G | RES,16.5KOhm,+/-0.1%,1/16W,G,SMD0402 | KOA SPEER ELECTRONICS, INC. | RN731ETTP1652B25 |  | PWA BOM | In Old BOM |
| 17 | PEER19 | 1 | 611003400-017-G | RES,12.7KOhm,+/-0.1%,1/16W,G,SMD0402 | KOA SPEER ELECTRONICS, INC. | RN731ETTP1272B25 | Y | PWA BOM | In New BOM |
|  |  |  | 611003400-024-G | RES,12.7KOhm,+/-0.1%,1/16W,G,SMD0402 | PANASONIC INDUSTRIAL CO.,LTD. | ERA2AEB1272X |  | PWA BOM | In New BOM |
|  | PEER19 | 1 | 611003400-017-G | RES,12.7KOhm,+/-0.1%,1/16W,G,SMD0402 | KOA SPEER ELECTRONICS, INC. | RN731ETTP1272B25 | Y | PWA BOM | In Old BOM |
| 18 | PSPL2,PIPL2,PFPL2,PEPL2 | 4 | 630341400-088-G | IND,22nH@1MHz,+/-20%,19A,368uOhm,SHLD,G,SMD | COOPER BUSSMANN, INC. | FP0404R1-R022-R |  | PWA BOM | In New BOM |
|  |  |  | HCB0430-220 | IND,22nH@1MHz,+/-20%,19A,320uOhm,SHLD,G,SMD | Delta | HCB0430-220 |  | PWA BOM | In New BOM |
|  | PSPL2,PIPL2,PFPL2,PEPL2 | 4 | 630341400-088-G | IND,22nH@1MHz,+/-20%,19A,368uOhm,SHLD,G,SMD | COOPER BUSSMANN, INC. | FP0404R1-R022-R |  | PWA BOM | In Old BOM |
| 19 | PSPR10,PIPR10,PFPR10,PEPR10 | 4 | 61100QQ00-017-G | RES,9.76KOhm,+/-0.1%,1/16W,G,SMD0402 | KOA SPEER ELECTRONICS, INC. | RN731ETTP9761B25 | Y | PWA BOM | In New BOM |
|  |  |  | 61100QQ00-024-G | RES,9.76KOhm,+/-0.1%,1/16W,G,SMD0402 | PANASONIC INDUSTRIAL CO.,LTD. | ERA2AEB9761X |  | PWA BOM | In New BOM |
|  | PSPR10,PIPR10,PFPR10,PEPR10 | 4 | 61100QQ00-017-G | RES,9.76KOhm,+/-0.1%,1/16W,G,SMD0402 | KOA SPEER ELECTRONICS, INC. | RN731ETTP9761B25 | Y | PWA BOM | In Old BOM |
| 20 | PALR19,PALR20,PBLR23,PBLR24 | 4 | 61100LR00-017-G | RES,100 Ohm,+/-1%,1/16W,G,SMD0402 | KOA SPEER ELECTRONICS, INC. | RN731ETTP1000F50 |  | PWA BOM | In New BOM |
|  |  |  | 61100YS00-029-G | RES,thin film,100Ohm,+/-1%,1/10W,SMD0402,G | VISHAY ENTER TECHNO LOGY.INC | MCS04020C1000FE000 | G | PWA BOM | In New BOM |
|  | PALR19,PALR20,PBLR23,PBLR24 | 4 | 610113800-017-G | RES,10 Ohm,+/-1%,1/16W,G,SMD0402 | KOA SPEER ELECTRONICS, INC. | RK73H1ETTP10R0F | N | PWA BOM | In Old BOM |
|  |  |  | 610113800-029-G | RES,thick film,10Ohm,+/-1%,1/16W,SMD0402,G | VISHAY ENTER TECHNO LOGY.INC | CRCW040210R0FKED | G | PWA BOM | In Old BOM |
| 21 | PBMR57,PAMR57 | 2 | 610119U00-017-G | RES,133 Ohm,+/-1%,1/16W,G,SMD0402 | KOA SPEER ELECTRONICS, INC. | RK73H1ETTP1330F | N | PWA BOM | In New BOM |
|  | PBMR57,PAMR57 | 2 | 610123T00-017-G | RES,232 Ohm,+/-1%,1/16W,G,SMD0402 | KOA SPEER ELECTRONICS, INC. | RK73H1ETTP2320F | N | PWA BOM | In Old BOM |
| 22 | PSUU1 | 1 | 880302300-065-G | Converter,input 40V~60V,600W,G,Q54SJ12050NNDH,OVAL | DELTA ELECTRONICS INDUSTRIAL CO.,LTD | Q54SJ12050NNDH |  | PWA BOM | In New BOM |
|  |  |  | 880302100-065-G | Converter,input 40V~60V,600W,G,Q54SH12050NNDH | DELTA ELECTRONICS INDUSTRIAL CO.,LTD | Q54SH12050NNDH | G | PWA BOM | In New BOM |
|  |  |  | BMR458 2130/004 | Ericsson,BMR458 2130/004 | Ericsson | BMR458 2130/004 | G | PWA BOM | In New BOM |
|  | PSUU1 | 1 | 880302300-065-G | Converter,input 40V~60V,600W,G,Q54SJ12050NNDH,OVAL | DELTA ELECTRONICS INDUSTRIAL CO.,LTD | Q54SH12050NNDH |  | PWA BOM | In Old BOM |
|  |  |  | 880302100-065-G | Converter,input 40V~60V,600W,G,Q54SH12050NNDH | DELTA ELECTRONICS INDUSTRIAL CO.,LTD | Q54SH12050NNDH | G | PWA BOM | In Old BOM |
|  |  |  | BMR458 2130/004 | Ericsson,BMR458 2130/004 | Ericsson | BMR458 2130/004 | G | PWA BOM | In Old BOM |
| 23 | PBMR34,PAMR34 | 2 | RN731ETTP3160B25 | RES,316 Ohm,+/-0.1%,1/16W,G,SMD0402 | KOA SPEER ELECTRONICS, INC. | RN731ETTP3160B25 | N | PWA BOM | In New BOM |
|  | PBMR34,PAMR34 | 2 | 61100RF00-017-G | RES,402 Ohm,+/-0.1%,1/16W,G,SMD0402 | KOA SPEER ELECTRONICS, INC. | RN731ETTP4020B25 | N | PWA BOM | In Old BOM |
| ##### Change Revision |  |  |  |  |  |  |  |  |  |
| Sheet | REV OF BOM | CUSTOMER | CUSTOMER P/N | PWA PN | PWA DESCRIPTION | PWA REV | DATE | Remark |  |
| PWA BOM |  | Customer |  |  |  |  |  | In New BOM |  |
| PWA BOM | X22 | Customer |  |  |  | X03 | 5/12/17 | In Old BOM |  |
| OOOOOOOOOOOOOOOOOOOOOOOOOOOOOOOOOOOOOOOOOOOOOOOOOOOOOOOOOOOOOOOOOOOOOOOOOOOOOOOOOOOOOOOOOO | OOOOOOOOOOOOOOOOOOOOOOOOOOOOOOOOOOOOOOOOOOOOOOOOOOOOOOOOOOOOOOOOOOOOOOOOOOOOOOOOOOOOOOOOOO | OOOOOOOOOOOOOOOOOOOOOOOOOOOOOOOOOOOOOOOOOOOOOOOOOOOOOOOOOOOOOOOOOOOOOOOOOOOOOOOOOOOOOOOOOO | OOOOOOOOOOOOOOOOOOOOOOOOOOOOOOOOOOOOOOOOOOOOOOOOOOOOOOOOOOOOOOOOOOOOOOOOOOOOOOOOOOOOOOOOOO | OOOOOOOOOOOOOOOOOOOOOOOOOOOOOOOOOOOOOOOOOOOOOOOOOOOOOOOOOOOOOOOOOOOOOOOOOOOOOOOOOOOOOOOOOO | OOOOOOOOOOOOOOOOOOOOOOOOOOOOOOOOOOOOOOOOOOOOOOOOOOOOOOOOOOOOOOOOOOOOOOOOOOOOOOOOOOOOOOOOOO | OOOOOOOOOOOOOOOOOOOOOOOOOOOOOOOOOOOOOOOOOOOOOOOOOOOOOOOOOOOOOOOOOOOOOOOOOOOOOOOOOOOOOOOOOO | OOOOOOOOOOOOOOOOOOOOOOOOOOOOOOOOOOOOOOOOOOOOOOOOOOOOOOOOOOOOOOOOOOOOOOOOOOOOOOOOOOOOOOOOOO | OOOOOOOOOOOOOOOOOOOOOOOOOOOOOOOOOOOOOOOOOOOOOOOOOOOOOOOOOOOOOOOOOOOOOOOOOOOOOOOOOOOOOOOOOO | OOOOOOOOOOOOOOOOOOOOOOOOOOOOOOOOOOOOOOOOOOOOOOOOOOOOOOOOOOOOOOOOOOOOOOOOOOOOOOOOOOOOOOOOOO |
| Second Source Change |  |  |  |  |  |  |  |  |  |
| Item | Location | Change Type | Foxconn P/N | Part Description | Manufacturer Full Name | Manufacturer P/N | RoHS | Sheet |  |
| 1 | DN1 |  | 521803M00-227-G | Diode,Array-TVS,UCLAMP0508T.TCT,Level 4,5V,G,SLP,SMD-9 | SEMTECH CORPORATION. | UCLAMP0508T.TCT | Y | PWA BOM |  |
|  |  | ADD | 521802K00-223-G | Diode,Array-TVS,NUP8011MUTAG,UDFN,9P,G | ON SEMICONDUCTOR CORP | NUP8011MUTAG |  | PWA BOM |  |
| 2 | D33 |  | 520308D00-237-G | DIODE,Schottky Rectifier,1N5819HW-7-F,40V,1A,G,SOD123-2,SMD | DIODES INCORPORATION | 1N5819HW-7-F | N | PWA BOM |  |
|  |  | ADD | 520318S00-223-G | Diode,Schottky,MBR140SFT3G,40V,1A,SOD-123FL,2P,G | ON SEMICONDUCTOR CORP | MBR140SFT3G | G | PWA BOM |  |
|  |  | NO | 52030P100-223-G | Diode,Schottky,MBR140SFT1G,40V,1A,SOD-123FL,2P,G | ON SEMICONDUCTOR CORP | MBR140SFT1G | G | PWA BOM |  |
|  |  | Delete | MBR140SFT3G | Diode,Schottky,MBR140SFT3G,40V,1A,SOD-123FL,2P,G | ON SEMICONDUCTOR CORP | MBR140SFT3G | G | PWA BOM |  |
| 3 | FS4,FS9,FS12,FS15,FS16,FS21 |  | 730102701-086-G | Fuse,Fast acting,32V,7A,G,SMD1206 | LITTELFUSE FAR EAST PTE LTD | 0440007.WR |  | PWA BOM |  |
|  |  | ADD | 730102704-088-G | Fuse,Fast acting,32V,7A,G,SMD1206 | Cooper Bussmann | CC12H7A-TR |  | PWA BOM |  |
| 4 | L22,L23,L24,L25 |  | 720105P00-016-G | FB,80 Ohm@100MHz,+/-25%,500mA,150mOhm,G,SMD0603 | TDK ELECTRONICS EUROPE GMBH | MMZ1608S800AT | N | PWA BOM |  |
|  |  | ADD | GMLB-160808-0080P-N8 | FB,80 Ohm@100MHz,+/-25%,500mA,150mOhm,G,SMD0603 | MAG.LAYERS, SCIENTIFIC-TECHNICS (KUNSHAN) CO., LTD. | GMLB-160808-0080P-N8 |  | PWA BOM |  |
| 5 | L26,L28,L47 |  | 72010CB00-015-G | FB,22 Ohm@100MHz,+/-25%,6A,10mOhm,G,SMD0805 | MURATA ELEC. NORTH AMERICA | BLM21PG220SN1D | N | PWA BOM |  |
|  |  | ADD | 72010CB00-059-G | FB,22 Ohm@100MHz,+/-25%,6A,10mOhm,G,SMD0805 | TAI-TECH ADVANCED ELECTRONICS CO., LTD. | HCB2012KF-220T60 |  | PWA BOM |  |
|  |  | ADD | 72010Y600-174-G | FB,22 Ohm@100MHz,+/-25%,6A,8mOhm,G,SMD0805 | MAX ECHO TECHNOLOGIES CORP | BCMS201209A220 |  | PWA BOM |  |
| 6 | L35,L37,L38,L39,L40,L41,L42 |  | 72010MK00-015-G | FB,80 Ohm@100MHz,+/-25%,1.5A,70mOhm,G,SMD0402 | MURATA ELEC. NORTH AMERICA | BLM15PD800SN1D | N | PWA BOM |  |
|  |  | ADD | 72010MK00-174-G | FB,80 Ohm@100MHz,+/-25%,1.5A,Multilayer,70mOhm,SMD0402,G | MAX ECHO TECHNOLOGIES CORP | ACMS100505A800 1.5A |  | PWA BOM |  |
| 7 | PBMR113,PAMR113,PBER115,PAFR115,PAER115,PBFR116,PBAR119,PAAR119 |  | 61100RU00-017-G | RES,59 Ohm,+/-1%,1/16W,G,SMD0402 | KOA SPEER ELECTRONICS, INC. | RN731ETTP59R0F25 |  | PWA BOM |  |
|  |  | Delete | 61015NF00-024-G | RES,59 Ohm,+/-1%,1/10W,G,SMD0402 | PANASONIC INDUSTRIAL CO.,LTD. | ERJ2RKF59R0X | G | PWA BOM |  |
| 8 | PBFFS1,PBEFS1,PAMFS1,PAFFS1,PAEFS1,PAMFS2 |  | 730100L00-086-G | Fuse,Very fast acting,125V,5A,G,SMD | LITTELFUSE FAR EAST PTE LTD | 0451005.MRL | N | PWA BOM |  |
|  |  | ADD | 730107B01-088-G | Fuse,Very fast acting,125V,5A,G,SMD | COOPER BUSSMANN, INC. | CB61F5A-TR2 |  | PWA BOM |  |
| 9 | PSTL1,PSLL1,PSFL1,PSEL1,PSDL1,PQPL1,PFRL1,PEEL1,PEDL1,PBLL1,PALL1,PUAL2,PSIL2,PSAL2,PRAL2,PQAL2,PPAL2,PIAL2,PFAL2,PERL2,PEAL2,PQPL3 |  | 72010RE00-015-G | FB,26 Ohm@100MHz,+/-25%,6A,7mOhm,G,SMD0603 | MURATA ELEC. NORTH AMERICA | BLM18KG260TN1D | N | PWA BOM |  |
|  |  | ADD | 72010SJ00-059-G | FB,26 Ohm@100MHz,+/-25%,6A,10mOhm,G,SMD0603 | TAI-TECH ADVANCED ELECTRONICS CO., LTD. | HCB1608KF-260T60 |  | PWA BOM |  |
| 10 | PALL2,PBLL4 |  | 630351600-034-G | IND,470nH@100KHz,+/-20%,30A,1.68mOhm,SHLD,G,SMD | CYNTEC CO. LTD | PCMB104T-R47MS |  | PWA BOM |  |
|  |  | ADD | 63035YA00-051-G | IND,470nH@100KHz,+/-20%,28A,1.5mOhm,SHLD,G,SMD | PULSE ELECTRONICS (SINGAPORE) | PA4342.471NLT |  | PWA BOM |  |
|  |  | ADD | 63035Y900-129-G | IND,470nH@100KHz,+/-20%,30A,1.68mOhm,SHLD,G,SMD | MAG.LAYERS, SCIENTIFIC-TECHNICS (KUNSHAN) CO., LTD. | SPS-10DZ-R47M-X2 |  | PWA BOM |  |
| 11 | PBNL1,PANL1 |  | 630330G00-088-G | IND,300nH@100KHz,+/-10%,32.5A,304.5uOhm,SHLD,G,SMD | COOPER BUSSMANN, INC. | FP0906R1-R30-R |  | PWA BOM |  |
|  |  | ADD | 630332A01-051-G | Coil Ind,Shielded(SHLD),300nH@100KHz,+/-10%,34A,290uOhm,SMD,9.2*6.2*7.8,G | PULSE ELECTRONICS (SINGAPORE) | PA3288.301HLT |  | PWA BOM |  |
|  |  | ADD | MSI-900608-R30K-E | IND,300nH@100KHz,+/-10%,32.5A,290uOhm,SHLD,G,SMD | MAG.LAYERS, SCIENTIFIC-TECHNICS (KUNSHAN) CO., LTD. | MSI-900608-R30K-E |  | PWA BOM |  |
| 12 | PANR6,PBNR7,R355,R356,R361,R362 |  | 61011JH00-017-G | RES,19.1KOhm,+/-1%,1/16W,G,SMD0402 | KOA SPEER ELECTRONICS, INC. | RK73H1ETTP1912F | N | PWA BOM |  |
|  |  | ADD | 61011JH00-011-G | RES,19.1KOhm,+/-1%,1/16W,G,SMD0402 | YAGEO | RC0402FR-0719K1L |  | PWA BOM |  |
|  |  | ADD | 61011JH00-044-G | RES,19.1KOhm,+/-1%,1/16W,G,SMD0402 | TA-I | RM04FTN1912 |  | PWA BOM |  |
| 13 | PUAL1,PSAL1,PRAL1,PQAL1,PPAL1,PIAL1,PFAL1,PEAL1 |  | 630335M00-088-G | IND,820nH@100KHz,+/-20%,13A,8mOhm,SHLD,G,SMD | COOPER BUSSMANN, INC. | HCM0703-R82-R |  | PWA BOM |  |
|  |  | ADD | 63035Y800-051-G | IND,820nH@100KHz,+/-20%,13A,8mOhm,SHLD,G,SMD | PULSE ELECTRONICS (SINGAPORE) | PA4341.821NLT |  | PWA BOM |  |
|  |  | ADD | 63032RP05-129-G | IND,820nH@100KHz,+/-20%,13A,8mOhm,SHLD,G,SMD | MAG.LAYERS, SCIENTIFIC-TECHNICS (KUNSHAN) CO., LTD. | SPS-06CZ-R82M-V1 |  | PWA BOM |  |
| 14 | PUAR4,PSAR4,PRAR4,PQAR4,PPAR4,PIAR4,PFAR4,PEAR4,PUAR6,PSAR6,PRAR6,PQAR6,PPAR6,PIAR6,PFAR6,PEAR6 |  | 611004D00-017-G | RES,1.5KOhm,+/-0.1%,1/16W,G,SMD0402 | KOA SPEER ELECTRONICS, INC. | RN731ETTP1501B25 |  | PWA BOM |  |
|  |  | ADD | 611004D00-029-G | RES,1.5KOhm,+/-0.1%,1/16W,G,SMD0402 | VISHAY ENTER TECHNO LOGY.INC | TNPW04021K50BEED |  | PWA BOM |  |
| 15 | PUAR8,PSAR8,PRAR8,PQAR8,PPAR8,PIAR8,PFAR8,PEAR8,PUAR11,PSAR11,PRAR11,PQAR11,PPAR11,PIAR11,PFAR11,PEAR11 |  | 610117F00-017-G | RES,5.76KOhm,+/-1%,1/16W,G,SMD0402 | KOA SPEER ELECTRONICS, INC. | RK73H1ETTP5761F | N | PWA BOM |  |
|  |  | ADD | 610117F00-011-G | RES,5.76KOhm,+/-1%,1/16W,G,SMD0402 | YAGEO CORPORATION COMPONENT | RC0402FR-075K76L |  | PWA BOM |  |
|  |  | ADD | 610117F00-044-G | RES,5.76KOhm,+/-1%,1/16W,G,SMD0402 | TA-I TECHNOLOGY CO., LTD. | RM04FTN5761 |  | PWA BOM |  |
| 16 | PSLR17,PSFR17,PSER17,PSDR17,PQPR17,PFRR17,PEER17,PEDR17,PEDR19 |  | 611004M00-017-G | RES,16.5KOhm,+/-0.1%,1/16W,G,SMD0402 | KOA SPEER ELECTRONICS, INC. | RN731ETTP1652B25 |  | PWA BOM |  |
|  |  | ADD | 611004M00-024-G | RES,16.5KOhm,+/-0.1%,1/16W,G,SMD0402 | PANASONIC INDUSTRIAL CO.,LTD. | ERA2AEB1652X |  | PWA BOM |  |
| 17 | PEER19 |  | 611003400-017-G | RES,12.7KOhm,+/-0.1%,1/16W,G,SMD0402 | KOA SPEER ELECTRONICS, INC. | RN731ETTP1272B25 | Y | PWA BOM |  |
|  |  | ADD | 611003400-024-G | RES,12.7KOhm,+/-0.1%,1/16W,G,SMD0402 | PANASONIC INDUSTRIAL CO.,LTD. | ERA2AEB1272X |  | PWA BOM |  |
| 18 | PSPL2,PIPL2,PFPL2,PEPL2 |  | 630341400-088-G | IND,22nH@1MHz,+/-20%,19A,368uOhm,SHLD,G,SMD | COOPER BUSSMANN, INC. | FP0404R1-R022-R |  | PWA BOM |  |
|  |  | ADD | HCB0430-220 | IND,22nH@1MHz,+/-20%,19A,320uOhm,SHLD,G,SMD | Delta | HCB0430-220 |  | PWA BOM |  |
| 19 | PSPR10,PIPR10,PFPR10,PEPR10 |  | 61100QQ00-017-G | RES,9.76KOhm,+/-0.1%,1/16W,G,SMD0402 | KOA SPEER ELECTRONICS, INC. | RN731ETTP9761B25 | Y | PWA BOM |  |
|  |  | ADD | 61100QQ00-024-G | RES,9.76KOhm,+/-0.1%,1/16W,G,SMD0402 | PANASONIC INDUSTRIAL CO.,LTD. | ERA2AEB9761X |  | PWA BOM |  |
| OOOOOOOOOOOOOOOOOOOOOOOOOOOOOOOOOOOOOOOOOOOOOOOOOOOOOOOOOOOOOOOOOOOOOOOOOOOOOOOOOOOOOOOOOO | OOOOOOOOOOOOOOOOOOOOOOOOOOOOOOOOOOOOOOOOOOOOOOOOOOOOOOOOOOOOOOOOOOOOOOOOOOOOOOOOOOOOOOOOOO | OOOOOOOOOOOOOOOOOOOOOOOOOOOOOOOOOOOOOOOOOOOOOOOOOOOOOOOOOOOOOOOOOOOOOOOOOOOOOOOOOOOOOOOOOO | OOOOOOOOOOOOOOOOOOOOOOOOOOOOOOOOOOOOOOOOOOOOOOOOOOOOOOOOOOOOOOOOOOOOOOOOOOOOOOOOOOOOOOOOOO | OOOOOOOOOOOOOOOOOOOOOOOOOOOOOOOOOOOOOOOOOOOOOOOOOOOOOOOOOOOOOOOOOOOOOOOOOOOOOOOOOOOOOOOOOO | OOOOOOOOOOOOOOOOOOOOOOOOOOOOOOOOOOOOOOOOOOOOOOOOOOOOOOOOOOOOOOOOOOOOOOOOOOOOOOOOOOOOOOOOOO | OOOOOOOOOOOOOOOOOOOOOOOOOOOOOOOOOOOOOOOOOOOOOOOOOOOOOOOOOOOOOOOOOOOOOOOOOOOOOOOOOOOOOOOOOO | OOOOOOOOOOOOOOOOOOOOOOOOOOOOOOOOOOOOOOOOOOOOOOOOOOOOOOOOOOOOOOOOOOOOOOOOOOOOOOOOOOOOOOOOOO | OOOOOOOOOOOOOOOOOOOOOOOOOOOOOOOOOOOOOOOOOOOOOOOOOOOOOOOOOOOOOOOOOOOOOOOOOOOOOOOOOOOOOOOOOO | OOOOOOOOOOOOOOOOOOOOOOOOOOOOOOOOOOOOOOOOOOOOOOOOOOOOOOOOOOOOOOOOOOOOOOOOOOOOOOOOOOOOOOOOOO |
| Master Materials Change |  |  |  |  |  |  |  |  |  |
| Item | Foxconn P/N | Orig._Usage | New_Usage | Part Description | Manufacturer Full Name | Manufacturer P/N | RoHS | Location | Sheet |
| 1 | 610107A00-017-G | 713 | 715 | RES,0 Ohm,+/-5%,1/16W,G,SMD0402 | KOA SPEER ELECTRONICS, INC. | RK73Z1ETTP | N | (+)R1848,R1849 | PWA BOM |
|  | 610107A00-024-G |  |  | RES,0 Ohm,+/-5%,1/16W,G,SMD0402 | PANASONIC INDUSTRIAL CO.,LTD. | ERJ2GE0R00X |  |  | PWA BOM |
|  | 610107A00-029-G |  |  | RES,0 Ohm,+/-5%,1/16W,G,SMD0402 | VISHAY ENTER TECHNO LOGY.INC | CRCW04020000Z0ED |  |  | PWA BOM |
| 2 | 610113800-017-G | 31 | 27 | RES,10 Ohm,+/-1%,1/16W,G,SMD0402 | KOA SPEER ELECTRONICS, INC. | RK73H1ETTP10R0F | N | (-)PALR19,PALR20,PBLR23,PBLR24 | PWA BOM |
|  | 610113800-029-G |  |  | RES,thick film,10Ohm,+/-1%,1/16W,SMD0402,G | VISHAY ENTER TECHNO LOGY.INC | CRCW040210R0FKED |  |  | PWA BOM |
| 3 | 61100LR00-017-G | 30 | 34 | RES,100 Ohm,+/-1%,1/16W,G,SMD0402 | KOA SPEER ELECTRONICS, INC. | RN731ETTP1000F50 |  | (+)PALR19,PALR20,PBLR23,PBLR24 | PWA BOM |
|  | 61100YS00-029-G |  |  | RES,thin film,100Ohm,+/-1%,1/10W,SMD0402,G | VISHAY ENTER TECHNO LOGY.INC | MCS04020C1000FE000 |  |  | PWA BOM |
| 4 | 610119U00-017-G | 0 | 2 | RES,133 Ohm,+/-1%,1/16W,G,SMD0402 | KOA SPEER ELECTRONICS, INC. | RK73H1ETTP1330F | N | (+)PBMR57,PAMR57 | PWA BOM |
| 5 | 61010LA00-017-G | 149 | 150 | RES,4.7KOhm,+/-1%,1/16W,G,SMD0402 | KOA SPEER ELECTRONICS, INC. | RK73H1ETTP4701F | N | (+)R1558 | PWA BOM |
|  | 61010LA00-029-G |  |  | RES,4.7KOhm,+/-1%,1/16W,G,SMD0402 | VISHAY ENTER TECHNO LOGY.INC | CRCW04024K70FKED |  |  | PWA BOM |
| 6 | 510301N00-223-G | 2 | 3 | MOS N,2N7002LT1G,60V,0.115A,7.5ohm@5V,G,SOT23-3,SMD | ON SEMICONDUCTOR CORP | 2N7002LT1G | N | (+)Q15 | PWA BOM |
| 7 | 610102700-017-G | 203 | 202 | RES,49.9 Ohm,+/-1%,1/16W,G,SMD0402 | KOA SPEER ELECTRONICS, INC. | RK73H1ETTP49R9F | N | (-)R1811 | PWA BOM |
|  | 610102700-029-G |  |  | RES,49.9 Ohm,+/-1%,1/16W,G,SMD0402 | VISHAY ENTER TECHNO LOGY.INC | CRCW040249R9FKED |  |  | PWA BOM |
|  | 610102700-024-G |  |  | RES,49.9 Ohm,+/-1%,1/16W,G,SMD0402 | PANASONIC INDUSTRIAL CO.,LTD. | ERJ2RKF49R9X |  |  | PWA BOM |
| 8 | RN731ETTP3160B25 | 0 | 2 | RES,316 Ohm,+/-0.1%,1/16W,G,SMD0402 | KOA SPEER ELECTRONICS, INC. | RN731ETTP3160B25 | N | (+)PBMR34,PAMR34 | PWA BOM |
| 9 | 61100RF00-017-G | 2 | 0 | RES,402 Ohm,+/-0.1%,1/16W,G,SMD0402 | KOA SPEER ELECTRONICS, INC. | RN731ETTP4020B25 | N | (-)PBMR34,PAMR34 | PWA BOM |
| 10 | 610123T00-017-G | 2 | 0 | RES,232 Ohm,+/-1%,1/16W,G,SMD0402 | KOA SPEER ELECTRONICS, INC. | RK73H1ETTP2320F | N | (-)PBMR57,PAMR57 | PWA BOM |
| OOOOOOOOOOOOOOOOOOOOOOOOOOOOOOOOOOOOOOOOOOOOOOOOOOOOOOOOOOOOOOOOOOOOOOOOOOOOOOOOOOOOOOOOOO | OOOOOOOOOOOOOOOOOOOOOOOOOOOOOOOOOOOOOOOOOOOOOOOOOOOOOOOOOOOOOOOOOOOOOOOOOOOOOOOOOOOOOOOOOO | OOOOOOOOOOOOOOOOOOOOOOOOOOOOOOOOOOOOOOOOOOOOOOOOOOOOOOOOOOOOOOOOOOOOOOOOOOOOOOOOOOOOOOOOOO | OOOOOOOOOOOOOOOOOOOOOOOOOOOOOOOOOOOOOOOOOOOOOOOOOOOOOOOOOOOOOOOOOOOOOOOOOOOOOOOOOOOOOOOOOO | OOOOOOOOOOOOOOOOOOOOOOOOOOOOOOOOOOOOOOOOOOOOOOOOOOOOOOOOOOOOOOOOOOOOOOOOOOOOOOOOOOOOOOOOOO | OOOOOOOOOOOOOOOOOOOOOOOOOOOOOOOOOOOOOOOOOOOOOOOOOOOOOOOOOOOOOOOOOOOOOOOOOOOOOOOOOOOOOOOOOO | OOOOOOOOOOOOOOOOOOOOOOOOOOOOOOOOOOOOOOOOOOOOOOOOOOOOOOOOOOOOOOOOOOOOOOOOOOOOOOOOOOOOOOOOOO | OOOOOOOOOOOOOOOOOOOOOOOOOOOOOOOOOOOOOOOOOOOOOOOOOOOOOOOOOOOOOOOOOOOOOOOOOOOOOOOOOOOOOOOOOO | OOOOOOOOOOOOOOOOOOOOOOOOOOOOOOOOOOOOOOOOOOOOOOOOOOOOOOOOOOOOOOOOOOOOOOOOOOOOOOOOOOOOOOOOOO | OOOOOOOOOOOOOOOOOOOOOOOOOOOOOOOOOOOOOOOOOOOOOOOOOOOOOOOOOOOOOOOOOOOOOOOOOOOOOOOOOOOOOOOOOO |
| TLA Parts Change |  |  |  |  |  |  |  |  |  |
| Item | Foxconn P/N | Qty | Part Description | Manufacturer Full Name | Manufacturer P/N | RoHS | Location | Remark | BOM |
| BOM Change List Date:Fri May 19 12:00:59 GMT+08:00 2017 |  |  |  |  |  |  |  |  |  |
| New BOM file : C:\<user>\ZAIUS-MB-DVT-X03-BOM_X23_20170518.xls |  |  |  |  |  |  |  |  |  |
| Old BOM file : C:\<user>\ZAIUS-MB-DVT-X03-BOM_X23_20170516.xls |  |  |  |  |  |  |  |  |  |
| ##### Add Parts |  |  |  |  |  |  |  |  |  |
| Item | Location | Qty | Foxconn P/N | Part Description | Manufacturer Full Name | Manufacturer P/N | RoHS | Sheet |  |
| 1 | R1519 | 1 | 610107A00-017-G | RES,0 Ohm,+/-5%,1/16W,G,SMD0402 | KOA SPEER ELECTRONICS, INC. | RK73Z1ETTP | G | PWA BOM |  |
|  |  |  | 610107A00-024-G | RES,0 Ohm,+/-5%,1/16W,G,SMD0402 | PANASONIC INDUSTRIAL CO.,LTD. | ERJ2GE0R00X | G | PWA BOM |  |
|  |  |  | 610107A00-029-G | RES,0 Ohm,+/-5%,1/16W,G,SMD0402 | VISHAY ENTER TECHNO LOGY.INC | CRCW04020000Z0ED | G | PWA BOM |  |
| 2 | R1559 | 1 | 61010L100-017-G | RES,100KOhm,+/-1%,1/16W,G,SMD0402 | KOA SPEER ELECTRONICS, INC. | RK73H1ETTP1003F | G | PWA BOM |  |
|  |  |  | 61010L106-029-G | RES,100KOhm,+/-1%,1/16W,G,SMD0402 | VISHAY ENTER TECHNO LOGY.INC | CRCW0402100KFKEDC | G | PWA BOM |  |
|  |  |  | 61010L100-024-G | RES,100KOhm,+/-1%,1/16W,G,SMD0402 | PANASONIC INDUSTRIAL CO.,LTD. | ERJ2RKF1003X | G | PWA BOM |  |
| ##### Remove Parts |  |  |  |  |  |  |  |  |  |
| Item | Location | Qty | Foxconn P/N | Part Description | Manufacturer Full Name | Manufacturer P/N | RoHS | Sheet |  |
| 1 | R1845 | 1 | 610108300-017-G | RES,0 Ohm,+/-5%,1/10W,G,SMD0603 | KOA SPEER ELECTRONICS, INC. | RK73Z1JTTD | G | PWA BOM |  |
|  |  |  | 610108300-024-G | RES,0 Ohm,+/-5%,1/10W,G,SMD0603 | PANASONIC INDUSTRIAL CO.,LTD. | ERJ3GEY0R00V | G | PWA BOM |  |
| ##### Change Parts |  |  |  |  |  |  |  |  |  |
| Item | Location | Qty | Foxconn P/N | Part Description | Manufacturer Full Name | Manufacturer P/N | RoHS | Sheet | Remark |
| 1 | PHAD6,D20,D21,D29,D30,D31,D32 | 7 | 520100200-237-G | DIODE,Switching,1N4148W-7-F,100V,0.15A,G,SOD123-2,SMD | DIODES INEORPORATION | 1N4148W-7-F | G | PWA BOM | In New BOM |
|  |  |  | 520102P00-031-G | DIODE,Switching,BAS16H,100V,0.5A,G,SOD123F-2,SMD | NXP SEMICONDUCTORS | BAS16H | G | PWA BOM | In New BOM |
|  | PHAD6,D20,D21,D29,D30,D31,D32 | 7 | 520100200-237-G | DIODE,Switching,1N4148W-7-F,100V,0.15A,G,SOD123-2,SMD | DIODES INEORPORATION | 1N4148W-7-F | G | PWA BOM | In Old BOM |
| 2 | ED1,ED2,ED3 | 3 | 521800900-227-G | DIODE,Array-TVS,SRV05-4.TCT,5V,12A,G,SOT23-6,SMD | SEMTECH CORPORATION. | SRV05-4.TCT | G | PWA BOM | In New BOM |
|  |  |  | 52180H500-086-G | DIODE,Array-TVS,SRV05-4.TCT,5V,12A,G,SOT23-6,SMD | LITTELFUSE FAR EAST PTE LTD | SRV05-04HTG | G | PWA BOM | In New BOM |
|  | ED1,ED2,ED3 | 3 | 521800900-227-G | DIODE,Array-TVS,SRV05-4.TCT,5V,12A,G,SOT23-6,SMD | SEMTECH CORPORATION. | SRV05-4.TCT | G | PWA BOM | In Old BOM |
| 3 | FL1,FL4,FL10 | 3 | 720406E00-015-G | Common Choke,90Ohm@100MHz,+/-25%,220mA,G,SMD0805 | MURATA ELEC. NORTH AMERICA | DLW21HN900HQ2L | G | PWA BOM | In New BOM |
|  |  |  | 720405D00-016-G | Common Choke,90 Ohm@100MHz,Type,200mA,G,SMD0805 | TDK | ACM2012E-900-2P-T01 | G | PWA BOM | In New BOM |
|  |  |  | 720402300-129-G | Common Choke,90 Ohm@100MHz,Type,200mA,G,SMD0805 | MagLayers | MCI-2012H-900 | G | PWA BOM | In New BOM |
|  | FL1,FL4,FL10 | 3 | 720406E00-015-G | Common Choke,90Ohm@100MHz,+/-25%,220mA,G,SMD0805 | MURATA ELEC. NORTH AMERICA | DLW21HN900HQ2L | G | PWA BOM | In Old BOM |
| 4 | FL2,FL3,FL5,FL6,FL7,FL8,FL9 | 7 | 720400201-015-G | Filter,Common Mode,90Ohm@100MHz,+/-25%,330mA,G,SMD0805 | MURATA ELEC. NORTH AMERICA | DLW21HN900SQ2L | G | PWA BOM | In New BOM |
|  |  |  | 720400M00-059-G | Common Choke,90 Ohm@100MHz,+/-25%,400mA,G,SMD0805 | TAI-TECH ADVANCED ELECTRONICS CO., LTD. | WCM2012F2SF-900T04 | G | PWA BOM | In New BOM |
|  |  |  | 720400800-016-G | Common Choke,90 Ohm@100MHz,+/-25%,400mA,190mOhm,2L,G,SMD0805 | TDK | ACM2012-900-2P-T | G | PWA BOM | In New BOM |
|  |  |  | 720400200-129-G | Common Choke,90 Ohm@100MHz,+/-25%,400mA,190mOhm,2L,G,SMD0805 | Maglayers | MCI-2012-900 | G | PWA BOM | In New BOM |
|  | FL2,FL3,FL5,FL6,FL7,FL8,FL9 | 7 | 720400201-015-G | Filter,Common Mode,90Ohm@100MHz,+/-25%,330mA,G,SMD0805 | MURATA ELEC. NORTH AMERICA | DLW21HN900SQ2L | G | PWA BOM | In Old BOM |
| 5 | FS5,FS8,FS11,FS14,FS17,FS19,FS20,FS23,FS24,FS25,FS26 | 11 | 730103M00-086-G | Fuse,Fast acting,32V,5A,G,SMD0603 | LITTELFUSE FAR EAST PTE LTD | 0438005.WR | G | PWA BOM | In New BOM |
|  |  |  | 730103M00-088-G | Fuse,Fast acting,32V,5A,SMD0603,G | COOPER BUSSMANN, INC. | CC06H5A-TR | G | PWA BOM | In New BOM |
|  | FS5,FS8,FS11,FS14,FS17,FS19,FS20,FS23,FS24,FS25,FS26 | 11 | 730103M00-086-G | Fuse,Fast acting,32V,5A,G,SMD0603 | LITTELFUSE FAR EAST PTE LTD | 0438005.WR | G | PWA BOM | In Old BOM |
| 6 | FS6,FS7,FS10,FS13,FS18 | 5 | 730102B01-086-G | Fuse,Fast acting,32V,1A,G,SMD0603 | LITTELFUSE FAR EAST PTE LTD | 0438001.WR | G | PWA BOM | In New BOM |
|  |  |  | 730102B03-088-G | Fuse,Fast acting,32V,1A,SMD0603,G | COOPER BUSSMANN, INC. | CC06H1A-TR | G | PWA BOM | In New BOM |
|  | FS6,FS7,FS10,FS13,FS18 | 5 | 730102B01-086-G | Fuse,Fast acting,32V,1A,G,SMD0603 | LITTELFUSE FAR EAST PTE LTD | 0438001.WR | G | PWA BOM | In Old BOM |
| 7 | LED1 | 1 | 52112H800-289-G | LED,Blu,LTST-C193TBKT-LO,5V,20mA,G,SMD | LITE-ON TECHNOLOGY CORPORATION | LTST-C193TBKT-LO | G | PWA BOM | In New BOM |
|  |  |  | 52112H900-354-G | LED LAMP,LG-192DBK-CT/T-SD,Blue,24mcd@IF=5mA,475nm,999.9999V,20mA,N/A,,SMD0603,2P,G | Ligitek Electronics Co., Ltd. | LG-192DBK-CT/T-SD | G | PWA BOM | In New BOM |
|  | LED1 | 1 | 52112H800-289-G | LED,Blu,LTST-C193TBKT-LO,5V,20mA,G,SMD | LITE-ON TECHNOLOGY CORPORATION | LTST-C193TBKT-LO | G | PWA BOM | In Old BOM |
| 8 | LED2,LED6 | 2 | 52111AE00-289-G | LED,Ora,LTST-C281KFKT-5A,5V,30mA,G,SMD0402 | LITE-ON TECHNOLOGY CORPORATION | LTST-C281KFKT-5A | G | PWA BOM | In New BOM |
|  |  |  | 52113GM00-290-G | LED LAMP,B1851UD--05D-000214,Orange,28.5mcd@IF=20mA,605nm,5V,20mA,N/A,,SMD0402,2P,G | HARVATEK | B1851UD--05D-000214 | G | PWA BOM | In New BOM |
|  | LED2,LED6 | 2 | 52111AE00-289-G | LED,Ora,LTST-C281KFKT-5A,5V,30mA,G,SMD0402 | LITE-ON TECHNOLOGY CORPORATION | LTST-C281KFKT-5A | G | PWA BOM | In Old BOM |
| 9 | LED3,LED7 | 2 | 52111J100-289-G | LED,Gre,LTST-C281KGKT-5A,2.3V,30mA,G,SMD0402 | LITE-ON TECHNOLOGY CORPORATION | LTST-C281KGKT-5A | G | PWA BOM | In New BOM |
|  |  |  | 52113AE00-290-G | LED LAMP,B1851UYG-05D-000114,Ultra Bright Yellow Green,11.25mcd@IF=5mA,571nm,5V,20mA,N/A,,SMD0402,2P,G | HARVATEK | B1851UYG-05D-000114 | G | PWA BOM | In New BOM |
|  | LED3,LED7 | 2 | 52111J100-289-G | LED,Gre,LTST-C281KGKT-5A,2.3V,30mA,G,SMD0402 | LITE-ON TECHNOLOGY CORPORATION | LTST-C281KGKT-5A | G | PWA BOM | In Old BOM |
| 10 | LED10,LED14 | 2 | 52113B000-289-G | LED,Yellow,LTL-42NSV8DH184P,5V,20mA,G,DIP-2 | LITE-ON TECHNOLOGY CORPORATION | LTL-42NSV8DH184P | G | PWA BOM | In New BOM |
|  |  |  | L-7104ADFX012-TW | LED,Yellow,LTL-42NSV8DH184P,5V,20mA,G,DIP-2 | Kingbright | L-7104ADFX012-TW | G | PWA BOM | In New BOM |
|  | LED10,LED14 | 2 | 52113B000-289-G | LED,Yellow,LTL-42NSV8DH184P,5V,20mA,G,DIP-2 | LITE-ON TECHNOLOGY CORPORATION | LTL-42NSV8DH184P | G | PWA BOM | In Old BOM |
| 11 | LED13 | 1 | 52113B100-289-G | LED,Blue,LTL42TB6NH184P,5V,30mA,G,DIP-2 | LITE-ON TECHNOLOGY CORPORATION | LTL42TB6NH184P | G | PWA BOM | In New BOM |
|  |  |  | L-7104ADFX010-TW | LED,Blue,LTL42TB6NH184P,5V,30mA,G,DIP-2 | Kingbright | L-7104ADFX010-TW | G | PWA BOM | In New BOM |
|  | LED13 | 1 | 52113B100-289-G | LED,Blue,LTL42TB6NH184P,5V,30mA,G,DIP-2 | LITE-ON TECHNOLOGY CORPORATION | LTL42TB6NH184P | G | PWA BOM | In Old BOM |
| 12 | L13,L14,L15,L16 | 4 | 720108301-015-G | FB,600 Ohm@100MHz,+/-25%,500mA,350mOhm,G,SMD0603 | MURATA ELEC. NORTH AMERICA | BLM18EG601SN1D | G | PWA BOM | In New BOM |
|  |  |  | 720105E00-059-G | FB,600 Ohm@100MHz,+/-25%,500mA,400mOhm,G,SMD0603 | TAI-TECH ADVANCED ELECTRONICS CO., LTD. | FCM1608KF-601T05 | G | PWA BOM | In New BOM |
|  |  |  | 720105E00-016-G | FB,600 Ohm@100MHz,+/-25%,500mA,400mOhm,G,SMD0603 | TDK | MMZ1608S601AT | G | PWA BOM | In New BOM |
|  | L13,L14,L15,L16 | 4 | 720108301-015-G | FB,600 Ohm@100MHz,+/-25%,500mA,350mOhm,G,SMD0603 | MURATA ELEC. NORTH AMERICA | BLM18EG601SN1D | G | PWA BOM | In Old BOM |
| 13 | L34,L36 | 2 | 72010A400-023-G | FB,80Ohm@100MHz,+/-25%,4A,10mOhm,G,SMD1206 | TAIYO ELECTRIC IND.CO.LTD | FBMJ3216HS800-T | G | PWA BOM | In New BOM |
|  |  |  | Z1206C800APWST | FB,80Ohm@100MHz,+/-25%,4A,10mOhm,G,SMD1206 | KEMET | Z1206C800APWST | G | PWA BOM | In New BOM |
|  | L34,L36 | 2 | 72010A400-023-G | FB,80Ohm@100MHz,+/-25%,4A,10mOhm,G,SMD1206 | TAIYO ELECTRIC IND.CO.LTD | FBMJ3216HS800-T | G | PWA BOM | In Old BOM |
| 14 | PSUCE1,PBACE1,PAACE1,PSUCE2,PBACE2,PAACE2 | 6 | 62111CS00-024-G | ECAP,68uF,+/-20%,100V,105C,G,SMD12.5*13.5,ESR<=320mOhm | PANASONIC INDUSTRIAL CO.,LTD. | EEVFK2A680Q | G | PWA BOM | In New BOM |
|  |  |  | 62111RR00-025-G | ECAP,68uF,+/-20%,100V,105C,G,SMD12.5*13.5,ESR<=320mOhm | KEMET ELECTRONICS CORPORATION | EXV686M100A9RAA | G | PWA BOM | In New BOM |
|  |  |  | 62111SK00-021-G | ECAP,68uF,+/-20%,100V,105C,G,SMD12.5*13.5,ESR<=320mOhm | NIPPON CHEMI-CON CORPORATION | EMVY101ARA680MKE0S | G | PWA BOM | In New BOM |
|  | PSUCE1,PBACE1,PAACE1,PSUCE2,PBACE2,PAACE2 | 6 | 62111CS00-024-G | ECAP,68uF,+/-20%,100V,105C,G,SMD12.5*13.5,ESR<=320mOhm | PANASONIC INDUSTRIAL CO.,LTD. | EEVFK2A680Q | G | PWA BOM | In Old BOM |
| 15 | PEER19 | 1 | 611003400-017-G | RES,12.7KOhm,+/-0.1%,1/16W,G,SMD0402 | KOA SPEER ELECTRONICS, INC. | RN731ETTP1272B25 | G | PWA BOM | In New BOM |
|  |  |  | 611003400-024-G | RES,12.7KOhm,+/-0.1%,1/16W,G,SMD0402 | PANASONIC INDUSTRIAL CO.,LTD. | ERA2AEB1272X | G | PWA BOM | In New BOM |
|  |  |  | 611003400-029-G | RES,12.7KOhm,+/-0.1%,1/16W,G,SMD0402 | VISHAY ENTER TECHNO LOGY.INC | TNPW040212K7BEED | G | PWA BOM | In New BOM |
|  | PEER19 | 1 | 611003400-017-G | RES,12.7KOhm,+/-0.1%,1/16W,G,SMD0402 | KOA SPEER ELECTRONICS, INC. | RN731ETTP1272B25 | G | PWA BOM | In Old BOM |
|  |  |  | 611003400-024-G | RES,12.7KOhm,+/-0.1%,1/16W,G,SMD0402 | PANASONIC INDUSTRIAL CO.,LTD. | ERA2AEB1272X | G | PWA BOM | In Old BOM |
| 16 | PERR2,PHAR35 | 2 | 61011PE00-017-G | RES,8.87KOhm,+/-1%,1/16W,G,SMD0402 | KOA SPEER ELECTRONICS, INC. | RK73H1ETTP8871F | G | PWA BOM | In New BOM |
|  |  |  | 61011PE00-024-G | RES,8.87KOhm,+/-1%,1/16W,G,SMD0402 | PANASONIC | ERJ2RKF8871X | G | PWA BOM | In New BOM |
|  |  |  | 61011PE00-029-G | RES,8.87KOhm,+/-1%,1/16W,G,SMD0402 | PANASONIC INDUSTRIAL CO.,LTD. | CRCW04028K87FKEDC | G | PWA BOM | In New BOM |
|  | PERR2,PHAR35 | 2 | 61011PE00-017-G | RES,8.87KOhm,+/-1%,1/16W,G,SMD0402 | KOA SPEER ELECTRONICS, INC. | RK73H1ETTP8871F | G | PWA BOM | In Old BOM |
|  |  |  | 61011PE00-024-G | RES,8.87KOhm,+/-1%,1/16W,G,SMD0402 | VISHAY ENTER TECHNO LOGY.INC | ERJ2RKF8871X | G | PWA BOM | In Old BOM |
|  |  |  | 61011PE00-029-G | RES,8.87KOhm,+/-1%,1/16W,G,SMD0402 | PANASONIC INDUSTRIAL CO.,LTD. | CRCW04028K87FKEDC | G | PWA BOM | In Old BOM |
| 17 | PQPL2,PFRL2 | 2 | 63032PP00-088-G | IND,4.7uH@100KHz,+/-20%,5.5A,40mOhm,SHLD,G,SMD | COOPER BUSSMANN, INC. | HCM0703-4R7-R | G | PWA BOM | In New BOM |
|  |  |  | 63030PW00-034-G | Coil Ind,Shielded(SHLD),4.7uH@100KHz,+/-20%,5.5A,40mOhm,SMD,7.3*6.6*3.0,G | CYNTEC CO. LTD | PCMC063T-4R7MN | G | PWA BOM | In New BOM |
|  |  |  | SPS-06CZ-4R7M-V1 | IND,4.7uH@100KHz,+/-20%,5.5A,40mOhm,SHLD,G,SMD | MAG.LAYERS, SCIENTIFIC-TECHNICS (KUNSHAN) CO., LTD. | SPS-06CZ-4R7M-V1 |  | PWA BOM | In New BOM |
|  | PQPL2,PFRL2 | 2 | 63032PP00-088-G | IND,4.7uH@100KHz,+/-20%,5.5A,40mOhm,SHLD,G,SMD | COOPER BUSSMANN, INC. | HCM0703-4R7-R | G | PWA BOM | In Old BOM |
| 18 | PFRR19 | 1 | 61100YB00-017-G | RES,2.94KOhm,+/-0.1%,1/16W,G,SMD0402 | KOA SPEER ELECTRONICS, INC. | RN731ETTP2941B25 | G | PWA BOM | In New BOM |
|  |  |  | 61100YB00-011-G | RES,2.94KOhm,+/-0.1%,1/16W,SMD0402,G | YAGEO CORPORATION COMPONENT | RT0402BRD072K94L | G | PWA BOM | In New BOM |
|  |  |  | RB04BTP2941B | RES,2.94KOhm,+/-0.1%,1/16W,SMD0402,G | TA-I | RM04BTN2941 | G | PWA BOM | In New BOM |
|  | PFRR19 | 1 | 61100YB00-017-G | RES,2.94KOhm,+/-0.1%,1/16W,G,SMD0402 | KOA SPEER ELECTRONICS, INC. | RN731ETTP2941B25 | G | PWA BOM | In Old BOM |
|  |  |  | 61100YB00-011-G | RES,2.94KOhm,+/-0.1%,1/16W,SMD0402,G | YAGEO CORPORATION COMPONENT | RT0402BRD072K94L | G | PWA BOM | In Old BOM |
|  |  |  | RB04BTP2941B | RES,2.94KOhm,+/-0.1%,1/16W,SMD0402,G | TA-I TECHNOLOGY CO., LTD. | RB04BTP2941B | G | PWA BOM | In Old BOM |
| 19 | PSIL1,PSEL2 | 2 | 63032A900-088-G | IND,1.5uH@100KHz,+/-20%,9A,15mOhm,SHLD,G,SMD | COOPER BUSSMANN, INC. | HCM0703-1R5-R | G | PWA BOM | In New BOM |
|  |  |  | 63032BW00-034-G | IND,1.5uH@100KHz,+/-20%,9A,15mOhm,SHLD,G,SMD | CYNTEC CO. LTD | PCMC063T-1R5MN | G | PWA BOM | In New BOM |
|  |  |  | 63030HW00-051-G | IND,1.5uH@100KHz,+/-20%,9A,11.8mOhm,SHLD,G,SMD | PULSE ELECTRONICS (SINGAPORE) | PG0426.152NLT |  | PWA BOM | In New BOM |
|  | PSIL1,PSEL2 | 2 | 63032A900-088-G | IND,1.5uH@100KHz,+/-20%,9A,15mOhm,SHLD,G,SMD | COOPER BUSSMANN, INC. | HCM0703-1R5-R | G | PWA BOM | In Old BOM |
| 20 | PSUQ1 | 1 | 51030CQ00-185-G | MOS N,2N7002,60V,115mA,7.5ohm@5V,G,SOT23-3,SMD | FAIRCHILD SEMICONDUCTOR CORP | 2N7002 | G | PWA BOM | In New BOM |
|  |  |  | 510301N00-223-G1 | MOS N,2N7002LT1G,60V,0.115A,7.5ohm@5V,G,SOT23-3,SMD | ON SEMICONDUCTOR CORP | 2N7002LT1G | G | PWA BOM | In New BOM |
|  | PSUQ1 | 1 | 51030CQ00-185-G | MOS N,2N7002,60V,115mA,7.5ohm@5V,G,SOT23-3,SMD | FAIRCHILD SEMICONDUCTOR CORP | 2N7002 | G | PWA BOM | In Old BOM |
| 21 | Q1,Q9,Q10,Q11,Q13,Q14,Q24,Q25,Q26,Q27,Q28,Q29,Q30,Q31,Q32,Q33,Q34,Q35,Q36,Q37,Q38,Q39,Q40,Q41,Q42,Q43,Q44,Q45,Q46,Q47,Q48,Q49,Q50,Q51,Q52,Q53,Q54,Q55,Q56,Q57,Q58,Q59,Q60,Q93 | 44 | 51030QP00-237-G | MOS N,BSS138W-7-F,50V,0.2A,3.5ohm@10V,G,SOT323-3,SMD | DIODES INEORPORATION | BSS138W-7-F | G | PWA BOM | In New BOM |
|  |  |  | 51031KA00-031-G | MOS N,BSS138PW,60V,320mA, 2ohm@5V,G,SC70-3,SMD | NXP SEMICONDUCTORS | BSS138PW | G | PWA BOM | In New BOM |
|  |  |  | 51031WU00-221-G | MOS N,BSS138W H6327,60V,280mA,3.5m@10V,G,SOT323-3,SMD | INFINEON TECHNOLOGIES CORP. | BSS138W H6327 | G | PWA BOM | In New BOM |
|  | Q1,Q9,Q10,Q11,Q13,Q14,Q24,Q25,Q26,Q27,Q28,Q29,Q30,Q31,Q32,Q33,Q34,Q35,Q36,Q37,Q38,Q39,Q40,Q41,Q42,Q43,Q44,Q45,Q46,Q47,Q48,Q49,Q50,Q51,Q52,Q53,Q54,Q55,Q56,Q57,Q58,Q59,Q60,Q93 | 44 | 51030QP00-237-G | MOS N,BSS138W-7-F,50V,0.2A,3.5ohm@10V,G,SOT323-3,SMD | DIODES INEORPORATION | BSS138W-7-F | G | PWA BOM | In Old BOM |
| 22 | R1756 | 1 | 61010KR00-017-G | RES,4.99 Ohm,+/-1%,1/10W,G,SMD0603 | KOA SPEER ELECTRONICS, INC. | RK73H1JTTD4R99F | G | PWA BOM | In New BOM |
|  |  |  | 61015JL00-029-G | RES,4.99 Ohm,+/-1%,1/4W,G,SMD0603 | VISHAY ENTER TECHNO LOGY.INC | CRCW06034R99FKEA | G | PWA BOM | In New BOM |
|  |  |  | 61010KR00-011-G | RES,4.99 Ohm,+/-1%,1/10W,G,SMD0603 | YAGEO | RC0603FR-074R99L | G | PWA BOM | In New BOM |
|  | R1756 | 1 | 61010KR00-017-G | RES,4.99 Ohm,+/-1%,1/10W,G,SMD0603 | KOA SPEER ELECTRONICS, INC. | RK73H1JTTD4R99F | G | PWA BOM | In Old BOM |
|  |  |  | 61015JL00-029-G | RES,4.99 Ohm,+/-1%,1/4W,G,SMD0603 | VISHAY ENTER TECHNO LOGY.INC | CRCW06034R99FKEA | G | PWA BOM | In Old BOM |
| 23 | U30 | 1 | 41040BT00-191-G | EEPROM,AT24C64D-SSHM-T,1.7~5.5V,64K,I2C,G,SOIC-8,SMD | ATMEL CORPORATION | AT24C64D-SSHM-T | G | PWA BOM | In New BOM |
|  |  |  | 410405H00-214-G | EEPROM,M24C64-RMN6TP,1.8~5.5V,64K,I2C,G,SO-8,SMD | ST MICRO ELECTRONICS,INC | M24C64-RMN6TP | G | PWA BOM | In New BOM |
|  |  |  | 410409E00-223-G | EEPROM,CAT24C64WI-GT3,1.8~5.5V,64K,I2C,G,SOIC-8,SMD | ON SEMICONDUCTOR CORP | CAT24C64WI-GT3 | G | PWA BOM | In New BOM |
|  | U30 | 1 | 41040BT00-191-G | EEPROM,AT24C64D-SSHM-T,1.7~5.5V,64K,I2C,G,SOIC-8,SMD | ATMEL CORPORATION | AT24C64D-SSHM-T | G | PWA BOM | In Old BOM |
| 24 | U46 | 1 | 41050K700-233-G | Flash,MX25L4006EM2I-12G,2.7V~3.6V,4M,SPI,G,SOP-8,SMD | MACRONIX INTERNATIONAL CO.,LTD. | MX25L4006EM2I-12G | G | PWA BOM | In New BOM |
|  |  |  | 41050RL00-205-G | NOR Flash,W25X40CLSSIG,2.3V,N/A,3.6V,4M,SPI,-40_x0003_~85_x0003_,SOIC,8P,G | WINBOND | W25X40CLSSIG | G | PWA BOM | In New BOM |
|  | U46 | 1 | 41050K700-233-G | Flash,MX25L4006EM2I-12G,2.7V~3.6V,4M,SPI,G,SOP-8,SMD | MACRONIX INTERNATIONAL CO.,LTD. | MX25L4006EM2I-12G | G | PWA BOM | In Old BOM |
| 25 | U90,U91,U112 | 3 | 310201900-031-G | IC,Gate&Inverter,74LVC2G14GW,1.65~5.5V,G,SOT363-6,SMD | NXP SEMICONDUCTORS | 74LVC2G14GW | G | PWA BOM | In New BOM |
|  |  |  | 310203300-223-G | Logic IC,Trigger,NL27WZ14DFT2G,1.65V~5.5V,7.4ns,SC-70/SOT-323,6P,G | ON SEMICONDUCTOR CORP | NL27WZ14DFT2G | G | PWA BOM | In New BOM |
|  | U90,U91,U112 | 3 | 310201900-031-G | IC,Gate&Inverter,74LVC2G14GW,1.65~5.5V,G,SOT363-6,SMD | NXP SEMICONDUCTORS | 74LVC2G14GW | G | PWA BOM | In Old BOM |
| 26 | U98 | 1 | 410403P00-214-G | EEPROM,M24512-WMN6TP,2.5~5.5V,512K,I2C,G,SO-8,SMD | ST MICRO ELECTRONICS,INC | M24512-WMN6TP | G | PWA BOM | In New BOM |
|  |  |  | 41040D200-191-G | EEP Memory,AT24C512C-SSHM-T,1.7V,N/A,3.6V,512K,I2C,-40_x0003_~85_x0003_,SOIC,8P,G | ATMEL | AT24C512C-SSHM-T | G | PWA BOM | In New BOM |
|  |  |  | 410406K00-214-G | EEP Memory,M24512-RMN6TP,1.8V,N/A,5.5V,512K,I2C,-40_x0003_~85_x0003_,SO,8P,G | ST | M24512-RMN6TP | G | PWA BOM | In New BOM |
|  | U98 | 1 | 410403P00-214-G | EEPROM,M24512-WMN6TP,2.5~5.5V,512K,I2C,G,SO-8,SMD | ST MICRO ELECTRONICS,INC | M24512-WMN6TP | G | PWA BOM | In Old BOM |
| 27 | U110 | 1 | 330103N00-426-G | IC,Optocoupler,PS2811-1-F3-A,G,SSOP-4,SMD | RENESAS TECHNOLOGY AMERICA INC | PS2811-1-F3-A | G | PWA BOM | In New BOM |
|  |  |  | 330102900-289-G | OPTO-IC,ISOL,LTV-217-G,SSOP,4P,G | LITE-ON TECHNOLOGY CORPORATION | LTV-217-G | G | PWA BOM | In New BOM |
|  |  |  | VOS618A-3T | OPTO-IC,VOS618A-3T,SSOP,4P,G | VISHAY ENTER TECHNO LOGY.INC | VOS618A-3T | G | PWA BOM | In New BOM |
|  | U110 | 1 | 330103N00-426-G | IC,Optocoupler,PS2811-1-F3-A,G,SSOP-4,SMD | RENESAS TECHNOLOGY AMERICA INC | PS2811-1-F3-A | G | PWA BOM | In Old BOM |
| 28 | U167 | 1 | 310203U00-223-G | IC,Trigger,NL17SZ14DFT2G,1.65~5.5V,G,SOT353-5,SMD | ON SEMICONDUCTOR CORP | NL17SZ14DFT2G | G | PWA BOM | In New BOM |
|  |  |  | 310107000-031-G | Logic IC,Gate&Inverter,74LVC1G14GW,1.65V~5.5V,14ns,TSSOP,5P,G | NXP SEMICONDUCTORS | 74LVC1G14GW | G | PWA BOM | In New BOM |
|  |  |  | 310200900-185-G | IC,Trigger,NC7SZ14P5X,1.65-5.5V,G,SC70-5P,SMD | Fairchild | NC7SZ14P5X | G | PWA BOM | In New BOM |
|  | U167 | 1 | 310203U00-223-G | IC,Trigger,NL17SZ14DFT2G,1.65~5.5V,G,SOT353-5,SMD | ON SEMICONDUCTOR CORP | NL17SZ14DFT2G | G | PWA BOM | In Old BOM |
| 29 | JP1(2-3),JP4(2-3),JP5(2-3),JP6(1-2) | 4 | 340612R00-309-G | CONN,Jumper,Bla,2.54mm,G,DIP-2 | SAMTEC INC. | SNT-100-BK-G | G | PWA BOM | In New BOM |
|  |  |  | 34065L900-GRT-G | CONN,jumper,Bla,2.54mm,30u,G,DIP-2 | PINREX TECHNOLOGY CORP. | 201-71-01DB00 | G | PWA BOM | In New BOM |
|  |  |  | 34066N500-600-G | CONN,Header,Jumper,1X2,V/T,Bla,2.54mm,G/F,G,DIP-2 | FOXCONN TECHNOLOGY CO.,LTD. | SJ0520F-A0 | G | PWA BOM | In New BOM |
|  | JP1(2-3),JP4(2-3),JP5(2-3),JP6(1-2) | 4 | 340612R00-309-G | CONN,Jumper,Bla,2.54mm,G,DIP-2 | SAMTEC INC. | SNT-100-BK-G | G | PWA BOM | In Old BOM |
| 30 | J_BMC_DEBUG1,J1,J3,J4,J5,J36,J41,J43,J48,J147,J149 | 11 | 34068LN00-317-G | CONN,Header,Pin Header,1X3,V/T,2.54mm,30u,G,SMD-3 | MOLEX INCORPORATED | 87898-0315 | G | PWA BOM | In New BOM |
|  |  |  | 34068HT00-245-G | CONN,Header,Pin Header,1X3,V/T,Bla,2.54mm,30u,SMD-3 | AMPHENOL SHANGHAI CORP. | G800MU305010EU | G | PWA BOM | In New BOM |
|  |  |  | 34068GU00-309-G | CONN,Header,Pin Header,1X3,V/T,Bla,2.54mm,30u,SMD-3 | SAMTEC INC. | TSM-103-01-S-SV-P-TR | G | PWA BOM | In New BOM |
|  | J_BMC_DEBUG1,J1,J3,J4,J5,J36,J41,J43,J48,J147,J149 | 11 | 34068LN00-317-G | CONN,Header,Pin Header,1X3,V/T,2.54mm,30u,G,SMD-3 | MOLEX INCORPORATED | 87898-0315 | G | PWA BOM | In Old BOM |
| 31 | PBMJ1,PBEJ1,PBAJ1,PAMJ1,PAEJ1,PAAJ1 | 6 | 340634U00-600-G | CONN,Pin Header,2X3,V/T,Bla,2.54mm,30u,G,SMD-6 | FOXCONN TECHNOLOGY CO.,LTD. | HS1103H-RN | G | PWA BOM | In New BOM |
|  |  |  | 34065EA00-317-G | CONN,Header,Pin Header,2X3,V/T,Bla,2.54mm,30u,G,SMD-6 | MOLEX INCORPORATED | 015-91-3060 | G | PWA BOM | In New BOM |
|  |  |  | 3406AY700-637-G | Header&Socket Connector,11006A5807,Pin Header,6,SMD,NY6T,2.54mm,30u",Black,G | LONG SHOUNG CO.,LTD. | 11006A5807 | G | PWA BOM | In New BOM |
|  |  |  | 34068GJ00-GRT-G | CONN,Header,Pin Header,2X3,V/T,Bla,2.54mm,30u,SMD-6 | PINREX TECHNOLOGY CORP. | 212-92-03SBEL | G | PWA BOM | In New BOM |
|  | PBMJ1,PBEJ1,PBAJ1,PAMJ1,PAEJ1,PAAJ1 | 6 | 340634U00-600-G | CONN,Pin Header,2X3,V/T,Bla,2.54mm,30u,G,SMD-6 | FOXCONN TECHNOLOGY CO.,LTD. | HS1103H-RN | G | PWA BOM | In Old BOM |
|  |  |  | 34065EA00-317-G | CONN,Header,Pin Header,2X3,V/T,Bla,2.54mm,30u,G,SMD-6 | MOLEX INCORPORATED | 015-91-3060 | G | PWA BOM | In Old BOM |
|  |  |  | 34068GJ00-GRT-G | CONN,Header,Pin Header,2X3,V/T,Bla,2.54mm,30u,SMD-6 | PINREX TECHNOLOGY CORP. | 212-92-03SBEL | G | PWA BOM | In Old BOM |
| 32 | PBAR65,PAAR65 | 2 | TLRH3APTTE20L0F | RES,20mOhm,+/-1%,2W,G,SMD2512 | KOA SPEER ELECTRONICS, INC. | TLRH3APTTE20L0F | G | PWA BOM | In New BOM |
|  |  |  | LRMAP2512-R01FT4 | RES,20mOhm,+/-1%,2W,G,SMD2512 | INTERNATIONAL RESISTIVE COMPANY, INC. | LRMAP2512-R01FT4 | G | PWA BOM | In New BOM |
|  | PBAR65,PAAR65 | 2 | TLRH3APTTE20L0F | RES,20mOhm,+/-1%,2W,G,SMD2512 | KOA SPEER ELECTRONICS, INC. | TLRH3APTTE20L0F | G | PWA BOM | In Old BOM |
| 33 | PBER65,PAFR65,PAER65,PBFR66 | 4 | SLW1TTE50L0F | RES,50mOhm,+/-1%,1.5W,G,SMD2512 | KOA | SLW1TTE50L0F | G | PWA BOM | In New BOM |
|  |  |  | LRMAP2512-R05FT4 | RES,50mOhm,+/-1%,1.5W,G,SMD2512 | INTERNATIONAL RESISTIVE COMPANY, INC. | LRMAP2512-R05FT4 | G | PWA BOM | In New BOM |
|  | PBER65,PAFR65,PAER65,PBFR66 | 4 | SLW1TTE50L0F | RES,50mOhm,+/-1%,1.5W,G,SMD2512 | KOA | SLW1TTE50L0F | G | PWA BOM | In Old BOM |
| 34 | PBMR65,PAMR65 | 2 | SLW1TTE75L0F | RES,75mOhm,+/-1%,1.5W,G,SMD2512 | KOA | SLW1TTE75L0F | G | PWA BOM | In New BOM |
|  |  |  | LRMAP2512-R075FT4 | RES,75mOhm,+/-1%,1.5W,G,SMD2512 | INTERNATIONAL RESISTIVE COMPANY, INC. | LRMAP2512-R075FT4 | G | PWA BOM | In New BOM |
|  | PBMR65,PAMR65 | 2 | SLW1TTE75L0F | RES,75mOhm,+/-1%,1.5W,G,SMD2512 | KOA | SLW1TTE75L0F | G | PWA BOM | In Old BOM |
| 35 | PCB | 1 | 0101EW800-000-G | PCB,Zaius-MB DVT-X03,OSP,Blu,22L,22.20*13.00,G | 0101EW800-000-G | 0101EW800-000-G | G | PWA BOM | In New BOM |
|  |  |  | 0101EW800-000-G | PCB,Zaius-MB DVT-X03,OSP,Blu,22L,22.20*13.00,G | ISUPETASYS CO., LTD | 0101EW800-000-G | G | PWA BOM | In New BOM |
|  | PCB | 1 | 0101EW800-000-G | PCB,Zaius-MB DVT-X03,OSP,Blu,22L,22.20*13.00,G | GOLD CIRCUIT ELECTRONICS LTD. | 0101EW800-000-G | G | PWA BOM | In Old BOM |
|  |  |  | 0101EW800-000-G | PCB,Zaius-MB DVT-X03,OSP,Blu,22L,22.20*13.00,G | ISUPETASYS CO., LTD | 0101EW800-000-G | G | PWA BOM | In Old BOM |
| 36 | FS29 | 1 | 730100L00-086-G | Fuse,Very fast acting,125V,5A,G,SMD | LITTELFUSE FAR EAST PTE LTD | 0451005.MRL | G | PWA BOM | In New BOM |
|  |  |  | 730107B01-088-G | Fuse,Very fast acting,125V,5A,G,SMD | COOPER BUSSMANN, INC. | CB61F5A-TR2 | G | PWA BOM | In New BOM |
|  | FS29 | 1 | 730106S00-088-G | Fuse,Fast acting,125V,15A,G,SMD2010 | COOPER BUSSMANN, INC. | CB61F15A-TR2 | G | PWA BOM | In Old BOM |
| ##### Change Revision |  |  |  |  |  |  |  |  |  |
| Sheet | REV OF BOM | CUSTOMER | CUSTOMER P/N | PWA PN | PWA DESCRIPTION | PWA REV | DATE | Remark |  |
| OOOOOOOOOOOOOOOOOOOOOOOOOOOOOOOOOOOOOOOOOOOOOOOOOOOOOOOOOOOOOOOOOOOOOOOOOOOOOOOOOOOOOOOOOO | OOOOOOOOOOOOOOOOOOOOOOOOOOOOOOOOOOOOOOOOOOOOOOOOOOOOOOOOOOOOOOOOOOOOOOOOOOOOOOOOOOOOOOOOOO | OOOOOOOOOOOOOOOOOOOOOOOOOOOOOOOOOOOOOOOOOOOOOOOOOOOOOOOOOOOOOOOOOOOOOOOOOOOOOOOOOOOOOOOOOO | OOOOOOOOOOOOOOOOOOOOOOOOOOOOOOOOOOOOOOOOOOOOOOOOOOOOOOOOOOOOOOOOOOOOOOOOOOOOOOOOOOOOOOOOOO | OOOOOOOOOOOOOOOOOOOOOOOOOOOOOOOOOOOOOOOOOOOOOOOOOOOOOOOOOOOOOOOOOOOOOOOOOOOOOOOOOOOOOOOOOO | OOOOOOOOOOOOOOOOOOOOOOOOOOOOOOOOOOOOOOOOOOOOOOOOOOOOOOOOOOOOOOOOOOOOOOOOOOOOOOOOOOOOOOOOOO | OOOOOOOOOOOOOOOOOOOOOOOOOOOOOOOOOOOOOOOOOOOOOOOOOOOOOOOOOOOOOOOOOOOOOOOOOOOOOOOOOOOOOOOOOO | OOOOOOOOOOOOOOOOOOOOOOOOOOOOOOOOOOOOOOOOOOOOOOOOOOOOOOOOOOOOOOOOOOOOOOOOOOOOOOOOOOOOOOOOOO | OOOOOOOOOOOOOOOOOOOOOOOOOOOOOOOOOOOOOOOOOOOOOOOOOOOOOOOOOOOOOOOOOOOOOOOOOOOOOOOOOOOOOOOOOO | OOOOOOOOOOOOOOOOOOOOOOOOOOOOOOOOOOOOOOOOOOOOOOOOOOOOOOOOOOOOOOOOOOOOOOOOOOOOOOOOOOOOOOOOOO |
| Second Source Change |  |  |  |  |  |  |  |  |  |
| Item | Location | Change Type | Foxconn P/N | Part Description | Manufacturer Full Name | Manufacturer P/N | RoHS | Sheet |  |
| 1 | PHAD6,D20,D21,D29,D30,D31,D32 |  | 520100200-237-G | DIODE,Switching,1N4148W-7-F,100V,0.15A,G,SOD123-2,SMD | DIODES INEORPORATION | 1N4148W-7-F | G | PWA BOM |  |
|  |  | ADD | 520102P00-031-G | DIODE,Switching,BAS16H,100V,0.5A,G,SOD123F-2,SMD | NXP SEMICONDUCTORS | BAS16H | G | PWA BOM |  |
| 2 | ED1,ED2,ED3 |  | 521800900-227-G | DIODE,Array-TVS,SRV05-4.TCT,5V,12A,G,SOT23-6,SMD | SEMTECH CORPORATION. | SRV05-4.TCT | G | PWA BOM |  |
|  |  | ADD | 52180H500-086-G | DIODE,Array-TVS,SRV05-4.TCT,5V,12A,G,SOT23-6,SMD | LITTELFUSE FAR EAST PTE LTD | SRV05-04HTG | G | PWA BOM |  |
| 3 | FL1,FL4,FL10 |  | 720406E00-015-G | Common Choke,90Ohm@100MHz,+/-25%,220mA,G,SMD0805 | MURATA ELEC. NORTH AMERICA | DLW21HN900HQ2L | G | PWA BOM |  |
|  |  | ADD | 720405D00-016-G | Common Choke,90 Ohm@100MHz,Type,200mA,G,SMD0805 | TDK | ACM2012E-900-2P-T01 | G | PWA BOM |  |
|  |  | ADD | 720402300-129-G | Common Choke,90 Ohm@100MHz,Type,200mA,G,SMD0805 | MagLayers | MCI-2012H-900 | G | PWA BOM |  |
| 4 | FL2,FL3,FL5,FL6,FL7,FL8,FL9 |  | 720400201-015-G | Filter,Common Mode,90Ohm@100MHz,+/-25%,330mA,G,SMD0805 | MURATA ELEC. NORTH AMERICA | DLW21HN900SQ2L | G | PWA BOM |  |
|  |  | ADD | 720400M00-059-G | Common Choke,90 Ohm@100MHz,+/-25%,400mA,G,SMD0805 | TAI-TECH ADVANCED ELECTRONICS CO., LTD. | WCM2012F2SF-900T04 | G | PWA BOM |  |
|  |  | ADD | 720400800-016-G | Common Choke,90 Ohm@100MHz,+/-25%,400mA,190mOhm,2L,G,SMD0805 | TDK | ACM2012-900-2P-T | G | PWA BOM |  |
|  |  | ADD | 720400200-129-G | Common Choke,90 Ohm@100MHz,+/-25%,400mA,190mOhm,2L,G,SMD0805 | Maglayers | MCI-2012-900 | G | PWA BOM |  |
| 5 | FS5,FS8,FS11,FS14,FS17,FS19,FS20,FS23,FS24,FS25,FS26 |  | 730103M00-086-G | Fuse,Fast acting,32V,5A,G,SMD0603 | LITTELFUSE FAR EAST PTE LTD | 0438005.WR | G | PWA BOM |  |
|  |  | ADD | 730103M00-088-G | Fuse,Fast acting,32V,5A,SMD0603,G | COOPER BUSSMANN, INC. | CC06H5A-TR | G | PWA BOM |  |
| 6 | FS6,FS7,FS10,FS13,FS18 |  | 730102B01-086-G | Fuse,Fast acting,32V,1A,G,SMD0603 | LITTELFUSE FAR EAST PTE LTD | 0438001.WR | G | PWA BOM |  |
|  |  | ADD | 730102B03-088-G | Fuse,Fast acting,32V,1A,SMD0603,G | COOPER BUSSMANN, INC. | CC06H1A-TR | G | PWA BOM |  |
| 7 | LED1 |  | 52112H800-289-G | LED,Blu,LTST-C193TBKT-LO,5V,20mA,G,SMD | LITE-ON TECHNOLOGY CORPORATION | LTST-C193TBKT-LO | G | PWA BOM |  |
|  |  | ADD | 52112H900-354-G | LED LAMP,LG-192DBK-CT/T-SD,Blue,24mcd@IF=5mA,475nm,999.9999V,20mA,N/A,,SMD0603,2P,G | Ligitek Electronics Co., Ltd. | LG-192DBK-CT/T-SD | G | PWA BOM |  |
| 8 | LED2,LED6 |  | 52111AE00-289-G | LED,Ora,LTST-C281KFKT-5A,5V,30mA,G,SMD0402 | LITE-ON TECHNOLOGY CORPORATION | LTST-C281KFKT-5A | G | PWA BOM |  |
|  |  | ADD | 52113GM00-290-G | LED LAMP,B1851UD--05D-000214,Orange,28.5mcd@IF=20mA,605nm,5V,20mA,N/A,,SMD0402,2P,G | HARVATEK | B1851UD--05D-000214 | G | PWA BOM |  |
| 9 | LED3,LED7 |  | 52111J100-289-G | LED,Gre,LTST-C281KGKT-5A,2.3V,30mA,G,SMD0402 | LITE-ON TECHNOLOGY CORPORATION | LTST-C281KGKT-5A | G | PWA BOM |  |
|  |  | ADD | 52113AE00-290-G | LED LAMP,B1851UYG-05D-000114,Ultra Bright Yellow Green,11.25mcd@IF=5mA,571nm,5V,20mA,N/A,,SMD0402,2P,G | HARVATEK | B1851UYG-05D-000114 | G | PWA BOM |  |
| 10 | LED10,LED14 |  | 52113B000-289-G | LED,Yellow,LTL-42NSV8DH184P,5V,20mA,G,DIP-2 | LITE-ON TECHNOLOGY CORPORATION | LTL-42NSV8DH184P | G | PWA BOM |  |
|  |  | ADD | L-7104ADFX012-TW | LED,Yellow,LTL-42NSV8DH184P,5V,20mA,G,DIP-2 | Kingbright | L-7104ADFX012-TW | G | PWA BOM |  |
| 11 | LED13 |  | 52113B100-289-G | LED,Blue,LTL42TB6NH184P,5V,30mA,G,DIP-2 | LITE-ON TECHNOLOGY CORPORATION | LTL42TB6NH184P | G | PWA BOM |  |
|  |  | ADD | L-7104ADFX010-TW | LED,Blue,LTL42TB6NH184P,5V,30mA,G,DIP-2 | Kingbright | L-7104ADFX010-TW | G | PWA BOM |  |
| 12 | L13,L14,L15,L16 |  | 720108301-015-G | FB,600 Ohm@100MHz,+/-25%,500mA,350mOhm,G,SMD0603 | MURATA ELEC. NORTH AMERICA | BLM18EG601SN1D | G | PWA BOM |  |
|  |  | ADD | 720105E00-059-G | FB,600 Ohm@100MHz,+/-25%,500mA,400mOhm,G,SMD0603 | TAI-TECH ADVANCED ELECTRONICS CO., LTD. | FCM1608KF-601T05 | G | PWA BOM |  |
|  |  | ADD | 720105E00-016-G | FB,600 Ohm@100MHz,+/-25%,500mA,400mOhm,G,SMD0603 | TDK | MMZ1608S601AT | G | PWA BOM |  |
| 13 | L34,L36 |  | 72010A400-023-G | FB,80Ohm@100MHz,+/-25%,4A,10mOhm,G,SMD1206 | TAIYO ELECTRIC IND.CO.LTD | FBMJ3216HS800-T | G | PWA BOM |  |
|  |  | ADD | Z1206C800APWST | FB,80Ohm@100MHz,+/-25%,4A,10mOhm,G,SMD1206 | KEMET | Z1206C800APWST | G | PWA BOM |  |
| 14 | PSUCE1,PBACE1,PAACE1,PSUCE2,PBACE2,PAACE2 |  | 62111CS00-024-G | ECAP,68uF,+/-20%,100V,105C,G,SMD12.5*13.5,ESR<=320mOhm | PANASONIC INDUSTRIAL CO.,LTD. | EEVFK2A680Q | G | PWA BOM |  |
|  |  | ADD | 62111RR00-025-G | ECAP,68uF,+/-20%,100V,105C,G,SMD12.5*13.5,ESR<=320mOhm | KEMET ELECTRONICS CORPORATION | EXV686M100A9RAA | G | PWA BOM |  |
|  |  | ADD | 62111SK00-021-G | ECAP,68uF,+/-20%,100V,105C,G,SMD12.5*13.5,ESR<=320mOhm | NIPPON CHEMI-CON CORPORATION | EMVY101ARA680MKE0S | G | PWA BOM |  |
| 15 | PEER19 |  | 611003400-017-G | RES,12.7KOhm,+/-0.1%,1/16W,G,SMD0402 | KOA SPEER ELECTRONICS, INC. | RN731ETTP1272B25 | G | PWA BOM |  |
|  |  | NO | 611003400-024-G | RES,12.7KOhm,+/-0.1%,1/16W,G,SMD0402 | PANASONIC INDUSTRIAL CO.,LTD. | ERA2AEB1272X | G | PWA BOM |  |
|  |  | ADD | 611003400-029-G | RES,12.7KOhm,+/-0.1%,1/16W,G,SMD0402 | VISHAY ENTER TECHNO LOGY.INC | TNPW040212K7BEED | G | PWA BOM |  |
| 16 | PQPL2,PFRL2 |  | 63032PP00-088-G | IND,4.7uH@100KHz,+/-20%,5.5A,40mOhm,SHLD,G,SMD | COOPER BUSSMANN, INC. | HCM0703-4R7-R | G | PWA BOM |  |
|  |  | ADD | 63030PW00-034-G | Coil Ind,Shielded(SHLD),4.7uH@100KHz,+/-20%,5.5A,40mOhm,SMD,7.3*6.6*3.0,G | CYNTEC CO. LTD | PCMC063T-4R7MN | G | PWA BOM |  |
|  |  | ADD | SPS-06CZ-4R7M-V1 | IND,4.7uH@100KHz,+/-20%,5.5A,40mOhm,SHLD,G,SMD | MAG.LAYERS, SCIENTIFIC-TECHNICS (KUNSHAN) CO., LTD. | SPS-06CZ-4R7M-V1 |  | PWA BOM |  |
| 17 | PSIL1,PSEL2 |  | 63032A900-088-G | IND,1.5uH@100KHz,+/-20%,9A,15mOhm,SHLD,G,SMD | COOPER BUSSMANN, INC. | HCM0703-1R5-R | G | PWA BOM |  |
|  |  | ADD | 63032BW00-034-G | IND,1.5uH@100KHz,+/-20%,9A,15mOhm,SHLD,G,SMD | CYNTEC CO. LTD | PCMC063T-1R5MN | G | PWA BOM |  |
|  |  | ADD | 63030HW00-051-G | IND,1.5uH@100KHz,+/-20%,9A,11.8mOhm,SHLD,G,SMD | PULSE ELECTRONICS (SINGAPORE) | PG0426.152NLT |  | PWA BOM |  |
| 18 | PSUQ1 |  | 51030CQ00-185-G | MOS N,2N7002,60V,115mA,7.5ohm@5V,G,SOT23-3,SMD | FAIRCHILD SEMICONDUCTOR CORP | 2N7002 | G | PWA BOM |  |
|  |  | ADD | 510301N00-223-G1 | MOS N,2N7002LT1G,60V,0.115A,7.5ohm@5V,G,SOT23-3,SMD | ON SEMICONDUCTOR CORP | 2N7002LT1G | G | PWA BOM |  |
| 19 | Q1,Q9,Q10,Q11,Q13,Q14,Q24,Q25,Q26,Q27,Q28,Q29,Q30,Q31,Q32,Q33,Q34,Q35,Q36,Q37,Q38,Q39,Q40,Q41,Q42,Q43,Q44,Q45,Q46,Q47,Q48,Q49,Q50,Q51,Q52,Q53,Q54,Q55,Q56,Q57,Q58,Q59,Q60,Q93 |  | 51030QP00-237-G | MOS N,BSS138W-7-F,50V,0.2A,3.5ohm@10V,G,SOT323-3,SMD | DIODES INEORPORATION | BSS138W-7-F | G | PWA BOM |  |
|  |  | ADD | 51031KA00-031-G | MOS N,BSS138PW,60V,320mA, 2ohm@5V,G,SC70-3,SMD | NXP SEMICONDUCTORS | BSS138PW | G | PWA BOM |  |
|  |  | ADD | 51031WU00-221-G | MOS N,BSS138W H6327,60V,280mA,3.5m@10V,G,SOT323-3,SMD | INFINEON TECHNOLOGIES CORP. | BSS138W H6327 | G | PWA BOM |  |
| 20 | R1756 |  | 61010KR00-017-G | RES,4.99 Ohm,+/-1%,1/10W,G,SMD0603 | KOA SPEER ELECTRONICS, INC. | RK73H1JTTD4R99F | G | PWA BOM |  |
|  |  | NO | 61015JL00-029-G | RES,4.99 Ohm,+/-1%,1/4W,G,SMD0603 | VISHAY ENTER TECHNO LOGY.INC | CRCW06034R99FKEA | G | PWA BOM |  |
|  |  | ADD | 61010KR00-011-G | RES,4.99 Ohm,+/-1%,1/10W,G,SMD0603 | YAGEO | RC0603FR-074R99L | G | PWA BOM |  |
| 21 | U30 |  | 41040BT00-191-G | EEPROM,AT24C64D-SSHM-T,1.7~5.5V,64K,I2C,G,SOIC-8,SMD | ATMEL CORPORATION | AT24C64D-SSHM-T | G | PWA BOM |  |
|  |  | ADD | 410405H00-214-G | EEPROM,M24C64-RMN6TP,1.8~5.5V,64K,I2C,G,SO-8,SMD | ST MICRO ELECTRONICS,INC | M24C64-RMN6TP | G | PWA BOM |  |
|  |  | ADD | 410409E00-223-G | EEPROM,CAT24C64WI-GT3,1.8~5.5V,64K,I2C,G,SOIC-8,SMD | ON SEMICONDUCTOR CORP | CAT24C64WI-GT3 | G | PWA BOM |  |
| 22 | U46 |  | 41050K700-233-G | Flash,MX25L4006EM2I-12G,2.7V~3.6V,4M,SPI,G,SOP-8,SMD | MACRONIX INTERNATIONAL CO.,LTD. | MX25L4006EM2I-12G | G | PWA BOM |  |
|  |  | ADD | 41050RL00-205-G | NOR Flash,W25X40CLSSIG,2.3V,N/A,3.6V,4M,SPI,-40_x0003_~85_x0003_,SOIC,8P,G | WINBOND | W25X40CLSSIG | G | PWA BOM |  |
| 23 | U90,U91,U112 |  | 310201900-031-G | IC,Gate&Inverter,74LVC2G14GW,1.65~5.5V,G,SOT363-6,SMD | NXP SEMICONDUCTORS | 74LVC2G14GW | G | PWA BOM |  |
|  |  | ADD | 310203300-223-G | Logic IC,Trigger,NL27WZ14DFT2G,1.65V~5.5V,7.4ns,SC-70/SOT-323,6P,G | ON SEMICONDUCTOR CORP | NL27WZ14DFT2G | G | PWA BOM |  |
| 24 | U98 |  | 410403P00-214-G | EEPROM,M24512-WMN6TP,2.5~5.5V,512K,I2C,G,SO-8,SMD | ST MICRO ELECTRONICS,INC | M24512-WMN6TP | G | PWA BOM |  |
|  |  | ADD | 41040D200-191-G | EEP Memory,AT24C512C-SSHM-T,1.7V,N/A,3.6V,512K,I2C,-40_x0003_~85_x0003_,SOIC,8P,G | ATMEL | AT24C512C-SSHM-T | G | PWA BOM |  |
|  |  | ADD | 410406K00-214-G | EEP Memory,M24512-RMN6TP,1.8V,N/A,5.5V,512K,I2C,-40_x0003_~85_x0003_,SO,8P,G | ST | M24512-RMN6TP | G | PWA BOM |  |
| 25 | U110 |  | 330103N00-426-G | IC,Optocoupler,PS2811-1-F3-A,G,SSOP-4,SMD | RENESAS TECHNOLOGY AMERICA INC | PS2811-1-F3-A | G | PWA BOM |  |
|  |  | ADD | 330102900-289-G | OPTO-IC,ISOL,LTV-217-G,SSOP,4P,G | LITE-ON TECHNOLOGY CORPORATION | LTV-217-G | G | PWA BOM |  |
|  |  | ADD | VOS618A-3T | OPTO-IC,VOS618A-3T,SSOP,4P,G | VISHAY ENTER TECHNO LOGY.INC | VOS618A-3T | G | PWA BOM |  |
| 26 | U167 |  | 310203U00-223-G | IC,Trigger,NL17SZ14DFT2G,1.65~5.5V,G,SOT353-5,SMD | ON SEMICONDUCTOR CORP | NL17SZ14DFT2G | G | PWA BOM |  |
|  |  | ADD | 310107000-031-G | Logic IC,Gate&Inverter,74LVC1G14GW,1.65V~5.5V,14ns,TSSOP,5P,G | NXP SEMICONDUCTORS | 74LVC1G14GW | G | PWA BOM |  |
|  |  | ADD | 310200900-185-G | IC,Trigger,NC7SZ14P5X,1.65-5.5V,G,SC70-5P,SMD | Fairchild | NC7SZ14P5X | G | PWA BOM |  |
| 27 | JP1(2-3),JP4(2-3),JP5(2-3),JP6(1-2) |  | 340612R00-309-G | CONN,Jumper,Bla,2.54mm,G,DIP-2 | SAMTEC INC. | SNT-100-BK-G | G | PWA BOM |  |
|  |  | ADD | 34065L900-GRT-G | CONN,jumper,Bla,2.54mm,30u,G,DIP-2 | PINREX TECHNOLOGY CORP. | 201-71-01DB00 | G | PWA BOM |  |
|  |  | ADD | 34066N500-600-G | CONN,Header,Jumper,1X2,V/T,Bla,2.54mm,G/F,G,DIP-2 | FOXCONN TECHNOLOGY CO.,LTD. | SJ0520F-A0 | G | PWA BOM |  |
| 28 | J_BMC_DEBUG1,J1,J3,J4,J5,J36,J41,J43,J48,J147,J149 |  | 34068LN00-317-G | CONN,Header,Pin Header,1X3,V/T,2.54mm,30u,G,SMD-3 | MOLEX INCORPORATED | 87898-0315 | G | PWA BOM |  |
|  |  | ADD | 34068HT00-245-G | CONN,Header,Pin Header,1X3,V/T,Bla,2.54mm,30u,SMD-3 | AMPHENOL SHANGHAI CORP. | G800MU305010EU | G | PWA BOM |  |
|  |  | ADD | 34068GU00-309-G | CONN,Header,Pin Header,1X3,V/T,Bla,2.54mm,30u,SMD-3 | SAMTEC INC. | TSM-103-01-S-SV-P-TR | G | PWA BOM |  |
| 29 | PBMJ1,PBEJ1,PBAJ1,PAMJ1,PAEJ1,PAAJ1 |  | 340634U00-600-G | CONN,Pin Header,2X3,V/T,Bla,2.54mm,30u,G,SMD-6 | FOXCONN TECHNOLOGY CO.,LTD. | HS1103H-RN | G | PWA BOM |  |
|  |  | NO | 34065EA00-317-G | CONN,Header,Pin Header,2X3,V/T,Bla,2.54mm,30u,G,SMD-6 | MOLEX INCORPORATED | 015-91-3060 | G | PWA BOM |  |
|  |  | ADD | 3406AY700-637-G | Header&Socket Connector,11006A5807,Pin Header,6,SMD,NY6T,2.54mm,30u",Black,G | LONG SHOUNG CO.,LTD. | 11006A5807 | G | PWA BOM |  |
|  |  | NO | 34068GJ00-GRT-G | CONN,Header,Pin Header,2X3,V/T,Bla,2.54mm,30u,SMD-6 | PINREX TECHNOLOGY CORP. | 212-92-03SBEL | G | PWA BOM |  |
| 30 | PBAR65,PAAR65 |  | TLRH3APTTE20L0F | RES,20mOhm,+/-1%,2W,G,SMD2512 | KOA SPEER ELECTRONICS, INC. | TLRH3APTTE20L0F | G | PWA BOM |  |
|  |  | ADD | LRMAP2512-R01FT4 | RES,20mOhm,+/-1%,2W,G,SMD2512 | INTERNATIONAL RESISTIVE COMPANY, INC. | LRMAP2512-R01FT4 | G | PWA BOM |  |
| 31 | PBER65,PAFR65,PAER65,PBFR66 |  | SLW1TTE50L0F | RES,50mOhm,+/-1%,1.5W,G,SMD2512 | KOA | SLW1TTE50L0F | G | PWA BOM |  |
|  |  | ADD | LRMAP2512-R05FT4 | RES,50mOhm,+/-1%,1.5W,G,SMD2512 | INTERNATIONAL RESISTIVE COMPANY, INC. | LRMAP2512-R05FT4 | G | PWA BOM |  |
| 32 | PBMR65,PAMR65 |  | SLW1TTE75L0F | RES,75mOhm,+/-1%,1.5W,G,SMD2512 | KOA | SLW1TTE75L0F | G | PWA BOM |  |
|  |  | ADD | LRMAP2512-R075FT4 | RES,75mOhm,+/-1%,1.5W,G,SMD2512 | INTERNATIONAL RESISTIVE COMPANY, INC. | LRMAP2512-R075FT4 | G | PWA BOM |  |
| OOOOOOOOOOOOOOOOOOOOOOOOOOOOOOOOOOOOOOOOOOOOOOOOOOOOOOOOOOOOOOOOOOOOOOOOOOOOOOOOOOOOOOOOOO | OOOOOOOOOOOOOOOOOOOOOOOOOOOOOOOOOOOOOOOOOOOOOOOOOOOOOOOOOOOOOOOOOOOOOOOOOOOOOOOOOOOOOOOOOO | OOOOOOOOOOOOOOOOOOOOOOOOOOOOOOOOOOOOOOOOOOOOOOOOOOOOOOOOOOOOOOOOOOOOOOOOOOOOOOOOOOOOOOOOOO | OOOOOOOOOOOOOOOOOOOOOOOOOOOOOOOOOOOOOOOOOOOOOOOOOOOOOOOOOOOOOOOOOOOOOOOOOOOOOOOOOOOOOOOOOO | OOOOOOOOOOOOOOOOOOOOOOOOOOOOOOOOOOOOOOOOOOOOOOOOOOOOOOOOOOOOOOOOOOOOOOOOOOOOOOOOOOOOOOOOOO | OOOOOOOOOOOOOOOOOOOOOOOOOOOOOOOOOOOOOOOOOOOOOOOOOOOOOOOOOOOOOOOOOOOOOOOOOOOOOOOOOOOOOOOOOO | OOOOOOOOOOOOOOOOOOOOOOOOOOOOOOOOOOOOOOOOOOOOOOOOOOOOOOOOOOOOOOOOOOOOOOOOOOOOOOOOOOOOOOOOOO | OOOOOOOOOOOOOOOOOOOOOOOOOOOOOOOOOOOOOOOOOOOOOOOOOOOOOOOOOOOOOOOOOOOOOOOOOOOOOOOOOOOOOOOOOO | OOOOOOOOOOOOOOOOOOOOOOOOOOOOOOOOOOOOOOOOOOOOOOOOOOOOOOOOOOOOOOOOOOOOOOOOOOOOOOOOOOOOOOOOOO | OOOOOOOOOOOOOOOOOOOOOOOOOOOOOOOOOOOOOOOOOOOOOOOOOOOOOOOOOOOOOOOOOOOOOOOOOOOOOOOOOOOOOOOOOO |
| Master Materials Change |  |  |  |  |  |  |  |  |  |
| Item | Foxconn P/N | Orig._Usage | New_Usage | Part Description | Manufacturer Full Name | Manufacturer P/N | RoHS | Location | Sheet |
| 1 | 730100L00-086-G | 6 | 7 | Fuse,Very fast acting,125V,5A,G,SMD | LITTELFUSE FAR EAST PTE LTD | 0451005.MRL | G | (+)FS29 | PWA BOM |
|  | 730107B01-088-G |  |  | Fuse,Very fast acting,125V,5A,G,SMD | COOPER BUSSMANN, INC. | CB61F5A-TR2 |  |  | PWA BOM |
| 2 | 610108300-017-G | 109 | 108 | RES,0 Ohm,+/-5%,1/10W,G,SMD0603 | KOA SPEER ELECTRONICS, INC. | RK73Z1JTTD | G | (-)R1845 | PWA BOM |
|  | 610108300-024-G |  |  | RES,0 Ohm,+/-5%,1/10W,G,SMD0603 | PANASONIC INDUSTRIAL CO.,LTD. | ERJ3GEY0R00V |  |  | PWA BOM |
| 3 | 610107A00-017-G | 715 | 716 | RES,0 Ohm,+/-5%,1/16W,G,SMD0402 | KOA SPEER ELECTRONICS, INC. | RK73Z1ETTP | G | (+)R1519 | PWA BOM |
|  | 610107A00-024-G |  |  | RES,0 Ohm,+/-5%,1/16W,G,SMD0402 | PANASONIC INDUSTRIAL CO.,LTD. | ERJ2GE0R00X |  |  | PWA BOM |
|  | 610107A00-029-G |  |  | RES,0 Ohm,+/-5%,1/16W,G,SMD0402 | VISHAY ENTER TECHNO LOGY.INC | CRCW04020000Z0ED |  |  | PWA BOM |
| 4 | 61010L100-017-G | 16 | 17 | RES,100KOhm,+/-1%,1/16W,G,SMD0402 | KOA SPEER ELECTRONICS, INC. | RK73H1ETTP1003F | G | (+)R1559 | PWA BOM |
|  | 61010L106-029-G |  |  | RES,100KOhm,+/-1%,1/16W,G,SMD0402 | VISHAY ENTER TECHNO LOGY.INC | CRCW0402100KFKEDC |  |  | PWA BOM |
|  | 61010L100-024-G |  |  | RES,100KOhm,+/-1%,1/16W,G,SMD0402 | PANASONIC INDUSTRIAL CO.,LTD. | ERJ2RKF1003X |  |  | PWA BOM |
| 5 | 730106S00-088-G | 1 | 0 | Fuse,Fast acting,125V,15A,G,SMD2010 | COOPER BUSSMANN, INC. | CB61F15A-TR2 | G | (-)FS29 | PWA BOM |
| OOOOOOOOOOOOOOOOOOOOOOOOOOOOOOOOOOOOOOOOOOOOOOOOOOOOOOOOOOOOOOOOOOOOOOOOOOOOOOOOOOOOOOOOOO | OOOOOOOOOOOOOOOOOOOOOOOOOOOOOOOOOOOOOOOOOOOOOOOOOOOOOOOOOOOOOOOOOOOOOOOOOOOOOOOOOOOOOOOOOO | OOOOOOOOOOOOOOOOOOOOOOOOOOOOOOOOOOOOOOOOOOOOOOOOOOOOOOOOOOOOOOOOOOOOOOOOOOOOOOOOOOOOOOOOOO | OOOOOOOOOOOOOOOOOOOOOOOOOOOOOOOOOOOOOOOOOOOOOOOOOOOOOOOOOOOOOOOOOOOOOOOOOOOOOOOOOOOOOOOOOO | OOOOOOOOOOOOOOOOOOOOOOOOOOOOOOOOOOOOOOOOOOOOOOOOOOOOOOOOOOOOOOOOOOOOOOOOOOOOOOOOOOOOOOOOOO | OOOOOOOOOOOOOOOOOOOOOOOOOOOOOOOOOOOOOOOOOOOOOOOOOOOOOOOOOOOOOOOOOOOOOOOOOOOOOOOOOOOOOOOOOO | OOOOOOOOOOOOOOOOOOOOOOOOOOOOOOOOOOOOOOOOOOOOOOOOOOOOOOOOOOOOOOOOOOOOOOOOOOOOOOOOOOOOOOOOOO | OOOOOOOOOOOOOOOOOOOOOOOOOOOOOOOOOOOOOOOOOOOOOOOOOOOOOOOOOOOOOOOOOOOOOOOOOOOOOOOOOOOOOOOOOO | OOOOOOOOOOOOOOOOOOOOOOOOOOOOOOOOOOOOOOOOOOOOOOOOOOOOOOOOOOOOOOOOOOOOOOOOOOOOOOOOOOOOOOOOOO | OOOOOOOOOOOOOOOOOOOOOOOOOOOOOOOOOOOOOOOOOOOOOOOOOOOOOOOOOOOOOOOOOOOOOOOOOOOOOOOOOOOOOOOOOO |
| TLA Parts Change |  |  |  |  |  |  |  |  |  |
| Item | Foxconn P/N | Qty | Part Description | Manufacturer Full Name | Manufacturer P/N | RoHS | Location | Remark | BOM |
| BOM Change List Date:Tue May 23 16:09:48 CST 2017 |  |  |  |  |  |  |  |  |  |
| New BOM file : C:\<user>\ZAIUS-MB-DVT-X03-BOM_X23_20170523.xls |  |  |  |  |  |  |  |  |  |
| Old BOM file : C:\<user>\ZAIUS-MB-DVT-X03-BOM_X23_20170522.xls |  |  |  |  |  |  |  |  |  |
| ##### Add Parts |  |  |  |  |  |  |  |  |  |
| Item | Location | Qty | Foxconn P/N | Part Description | Manufacturer Full Name | Manufacturer P/N | RoHS | Sheet |  |
| ##### Remove Parts |  |  |  |  |  |  |  |  |  |
| Item | Location | Qty | Foxconn P/N | Part Description | Manufacturer Full Name | Manufacturer P/N | RoHS | Sheet |  |
| ##### Change Parts |  |  |  |  |  |  |  |  |  |
| Item | Location | Qty | Foxconn P/N | Part Description | Manufacturer Full Name | Manufacturer P/N | RoHS | Sheet | Remark |
| 1 | PSTC5,PSLC5,PSFC5,PSEC5,PSDC5,PQPC5,PFRC5,PEEC5,PEDC5,C46,C63,C69,C79,C142,C144,C157,C167,C226,C234,C774,C781,C785,C813,C856,C864,C873,C883 | 27 | 62012P100-015-G | CAP,2.2uF,+/-20%,X7S,10V,G,SMD0402 | MURATA ELEC. NORTH AMERICA | GRM155C71A225M | G | PWA BOM | In New BOM |
|  | PSTC5,PSLC5,PSFC5,PSEC5,PSDC5,PQPC5,PFRC5,PEEC5,PEDC5,C46,C63,C69,C79,C142,C144,C157,C167,C226,C234,C774,C781,C785,C813,C856,C864,C873,C883 | 27 | 62012P100-015-G | CAP,2.2uF,+/-20%,X7S,10V,G,SMD0402 | MURATA ELEC. NORTH AMERICA | GRM155C71A225M | G | PWA BOM | In Old BOM |
|  |  |  | 62012P000-023-G | CAP,2.2uF,+/-10%,X7R,16V,G,SMD0603 | TAIYO ELECTRIC IND.CO.LTD | EMK107BB7225KA-T | G | PWA BOM | In Old BOM |
| 2 | D57 | 1 | 52030NP00-185-G | DIODE,Schottky,RB521S30,30V,200mA,G,SOD523-2,SMD | FAIRCHILD SEMICONDUCTOR CORP | RB521S30 | G | PWA BOM | In New BOM |
|  |  |  | 52030NP00-031-G | DIODE,Schottky,SDM20U30-7,30V,0.2A,G,SOD523-2,SMD | NXP SEMICONDUCTORS | RB521S30 | G | PWA BOM | In New BOM |
|  |  |  | 52030AG00-237-G | DIODE,Schottky,SDM20U30-7,30V,0.2A,G,SOD523-2,SMD | DIODES INCORPORATION | SDM20U30-7 | G | PWA BOM | In New BOM |
|  | D57 | 1 | 52030NP00-185-G | DIODE,Schottky,RB521S30,30V,200mA,G,SOD523-2,SMD | FAIRCHILD SEMICONDUCTOR CORP | RB521S30 | G | PWA BOM | In Old BOM |
| 3 | LED2,LED6 | 2 | 52111AE00-289-G | LED,Ora,LTST-C281KFKT-5A,5V,30mA,G,SMD0402 | LITE-ON TECHNOLOGY CORPORATION | LTST-C281KFKT-5A | G | PWA BOM | In New BOM |
|  |  |  | 52113GM00-290-G | LED LAMP,B1851UD--05D-000214,Orange,28.5mcd@IF=20mA,605nm,5V,20mA,N/A,,SMD0402,2P,G | HARVATEK CORPORATION | B1851UD--05D-000214 | G | PWA BOM | In New BOM |
|  | LED2,LED6 | 2 | 52111AE00-289-G | LED,Ora,LTST-C281KFKT-5A,5V,30mA,G,SMD0402 | LITE-ON TECHNOLOGY CORPORATION | LTST-C281KFKT-5A | G | PWA BOM | In Old BOM |
|  |  |  | 52113GM00-290-G | LED LAMP,B1851UD--05D-000214,Orange,28.5mcd@IF=20mA,605nm,5V,20mA,N/A,,SMD0402,2P,G | HARVATEK | B1851UD--05D-000214 | G | PWA BOM | In Old BOM |
| 4 | LED3,LED7 | 2 | 52111J100-289-G | LED,Gre,LTST-C281KGKT-5A,2.3V,30mA,G,SMD0402 | LITE-ON TECHNOLOGY CORPORATION | LTST-C281KGKT-5A | G | PWA BOM | In New BOM |
|  |  |  | 52113AE00-290-G | LED LAMP,B1851UYG-05D-000114,Ultra Bright Yellow Green,11.25mcd@IF=5mA,571nm,5V,20mA,N/A,,SMD0402,2P,G | HARVATEK CORPORATION | B1851UYG-05D-000114 | G | PWA BOM | In New BOM |
|  | LED3,LED7 | 2 | 52111J100-289-G | LED,Gre,LTST-C281KGKT-5A,2.3V,30mA,G,SMD0402 | LITE-ON TECHNOLOGY CORPORATION | LTST-C281KGKT-5A | G | PWA BOM | In Old BOM |
|  |  |  | 52113AE00-290-G | LED LAMP,B1851UYG-05D-000114,Ultra Bright Yellow Green,11.25mcd@IF=5mA,571nm,5V,20mA,N/A,,SMD0402,2P,G | HARVATEK | B1851UYG-05D-000114 | G | PWA BOM | In Old BOM |
| 5 | LED10,LED14 | 2 | 52113B000-289-G | LED,Yellow,LTL-42NSV8DH184P,5V,20mA,G,DIP-2 | LITE-ON TECHNOLOGY CORPORATION | LTL-42NSV8DH184P | G | PWA BOM | In New BOM |
|  |  |  | L-7104ADFX012-TW | LED,Yellow,LTL-42NSV8DH184P,5V,20mA,G,DIP-2 | KINGBRIGHT ELECTRONIC CO., LTD. | L-7104ADFX012-TW | G | PWA BOM | In New BOM |
|  | LED10,LED14 | 2 | 52113B000-289-G | LED,Yellow,LTL-42NSV8DH184P,5V,20mA,G,DIP-2 | LITE-ON TECHNOLOGY CORPORATION | LTL-42NSV8DH184P | G | PWA BOM | In Old BOM |
|  |  |  | L-7104ADFX012-TW | LED,Yellow,LTL-42NSV8DH184P,5V,20mA,G,DIP-2 | Kingbright | L-7104ADFX012-TW | G | PWA BOM | In Old BOM |
| 6 | LED11,LED12 | 2 | 52113AW00-289-G | LED,Green,LTL-42NGY8DH184P,5V,20mA,G,DIP-2 | LITE-ON TECHNOLOGY CORPORATION | LTL-42NGY8DH184P | G | PWA BOM | In New BOM |
|  |  |  | SSF-LXH303SUGD | LED,Green,LTL-42NGY8DH184P,5V,20mA,G,DIP-2 | LUEMX INC,TAIWAN BRANCH | SSF-LXH303SUGD | G | PWA BOM | In New BOM |
|  | LED11,LED12 | 2 | 52113AW00-289-G | LED,Green,LTL-42NGY8DH184P,5V,20mA,G,DIP-2 | LITE-ON TECHNOLOGY CORPORATION | LTL-42NGY8DH184P | G | PWA BOM | In Old BOM |
| 7 | LED13 | 1 | 52113B100-289-G | LED,Blue,LTL42TB6NH184P,5V,30mA,G,DIP-2 | LITE-ON TECHNOLOGY CORPORATION | LTL42TB6NH184P | G | PWA BOM | In New BOM |
|  |  |  | L-7104ADFX010-TW | LED,Blue,LTL42TB6NH184P,5V,30mA,G,DIP-2 | KINGBRIGHT ELECTRONIC CO., LTD. | L-7104ADFX010-TW | G | PWA BOM | In New BOM |
|  | LED13 | 1 | 52113B100-289-G | LED,Blue,LTL42TB6NH184P,5V,30mA,G,DIP-2 | LITE-ON TECHNOLOGY CORPORATION | LTL42TB6NH184P | G | PWA BOM | In Old BOM |
|  |  |  | L-7104ADFX010-TW | LED,Blue,LTL42TB6NH184P,5V,30mA,G,DIP-2 | Kingbright | L-7104ADFX010-TW | G | PWA BOM | In Old BOM |
| 8 | L17 | 1 | 720106E00-015-G | FB,330 Ohm@100MHz,+/-25%,500mA,300mOhm,G,SMD0603 | MURATA ELEC. NORTH AMERICA | BLM18EG331TN1D | G | PWA BOM | In New BOM |
|  |  |  | 72010YW01-129-G | FB,Multilayer,100mOhm,330Ohm@100MHz,+/-25%,2A,,SMD0603,G | MAG.LAYERS, SCIENTIFIC-TECHNICS (KUNSHAN) CO., LTD. | GMLB-160808-0330P-N8 | G | PWA BOM | In New BOM |
|  | L17 | 1 | 720106E00-015-G | FB,330 Ohm@100MHz,+/-25%,500mA,300mOhm,G,SMD0603 | MURATA ELEC. NORTH AMERICA | BLM18EG331TN1D | G | PWA BOM | In Old BOM |
| 9 | L22,L23,L24,L25 | 4 | 720105P00-016-G | FB,80 Ohm@100MHz,+/-25%,500mA,150mOhm,G,SMD0603 | TDK ELECTRONICS EUROPE GMBH | MMZ1608S800AT | G | PWA BOM | In New BOM |
|  |  |  | 72010WQ00-129-G | FB,Multilayer,40mOhm,80Ohm@100MHz,+/-25%,3A,,SMD0603,G | MAG.LAYERS, SCIENTIFIC-TECHNICS (KUNSHAN) CO., LTD. | GMLB-160808-0080P-N8 | G | PWA BOM | In New BOM |
|  | L22,L23,L24,L25 | 4 | 720105P00-016-G | FB,80 Ohm@100MHz,+/-25%,500mA,150mOhm,G,SMD0603 | TDK ELECTRONICS EUROPE GMBH | MMZ1608S800AT | G | PWA BOM | In Old BOM |
|  |  |  | GMLB-160808-0080P-N8 | FB,80 Ohm@100MHz,+/-25%,500mA,150mOhm,G,SMD0603 | MAG.LAYERS, SCIENTIFIC-TECHNICS (KUNSHAN) CO., LTD. | GMLB-160808-0080P-N8 | G | PWA BOM | In Old BOM |
| 10 | L45 | 1 | 720101M00-015-G | FB,600 Ohm@100MHz,+/-25%,200mA,650mOhm,G,SMD0603 | MURATA ELEC. NORTH AMERICA | BLM18BD601SN1D | G | PWA BOM | In New BOM |
|  |  |  | 720103000-023-G | FB,600 Ohm@100MHz,+/-25%,250mA,600mOhm,G,SMD0603 | TAIYO ELECTRIC IND.CO.LTD | BK1608HM601-T | G | PWA BOM | In New BOM |
|  | L45 | 1 | 720101M00-015-G | FB,600 Ohm@100MHz,+/-25%,200mA,650mOhm,G,SMD0603 | MURATA ELEC. NORTH AMERICA | BLM18BD601SN1D | G | PWA BOM | In Old BOM |
| 11 | PBMC6,PBFC6,PBEC6,PBAC6,PAMC6,PAFC6,PAEC6,PAAC6 | 8 | 62011DQ00-015-G | CAP,27nF,+/-10%,X7R,25V,G,SMD0402 | MURATA ELEC. NORTH AMERICA | GRM155R71E273KA88D | G | PWA BOM | In New BOM |
|  |  |  | C0402C273K3RAC | CAP,27nF,+/-10%,X7R,25V,G,SMD0402 | KEMET ELECTRONICS CORPORATION | C0402C273K3RAC | G | PWA BOM | In New BOM |
|  | PBMC6,PBFC6,PBEC6,PBAC6,PAMC6,PAFC6,PAEC6,PAAC6 | 8 | 62011DQ00-015-G | CAP,27nF,+/-10%,X7R,25V,G,SMD0402 | MURATA ELEC. NORTH AMERICA | GRM155R71E273KA88D | G | PWA BOM | In Old BOM |
| 12 | PBMD1,PBFD1,PBED1,PBAD1,PAMD1,PAFD1,PAED1,PAAD1 | 8 | 520103B00-185-G | Diode,Rectifier&Switching,MMBD1205,100V,200mA,G,SOT-23-3,SMD | FAIRCHILD SEMICONDUCTOR CORP | MMBD1205 | G | PWA BOM | In New BOM |
|  |  |  | MMBD3004A | Diode,Rectifier&Switching,100V,200mA,G,SOT-23-3,SMD | DIODES INCORPORATION | MMBD3004A | G | PWA BOM | In New BOM |
|  | PBMD1,PBFD1,PBED1,PBAD1,PAMD1,PAFD1,PAED1,PAAD1 | 8 | 520103B00-185-G | Diode,Rectifier&Switching,MMBD1205,100V,200mA,G,SOT-23-3,SMD | FAIRCHILD SEMICONDUCTOR CORP | MMBD1205 | G | PWA BOM | In Old BOM |
| 13 | PSUFS1,PBAFS1,PAAFS1,PSUFS2 | 4 | 730100M00-086-G | Fuse,Very fast acting,125V,10A,G,SMD | LITTELFUSE FAR EAST PTE LTD | 0451010.MRL | G | PWA BOM | In New BOM |
|  |  |  | CB61F10A-TR2 | Fuse,CB61F10A-TR2 | COOPER BUSSMANN, INC. | CB61F10A-TR2 | G | PWA BOM | In New BOM |
|  | PSUFS1,PBAFS1,PAAFS1,PSUFS2 | 4 | 730100M00-086-G | Fuse,Very fast acting,125V,10A,G,SMD | LITTELFUSE FAR EAST PTE LTD | 0451010.MRL | G | PWA BOM | In Old BOM |
| 14 | PBML1,PBAL1,PAML1,PAAL1,PBFL2,PBEL2,PAFL2,PAEL2,PBML3,PBFL3,PBEL3,PBAL3,PAML3,PAFL3,PAEL3,PAAL3,PBAL5,PAAL5 | 18 | 63035NQ00-029-G | IND,0.1uH@100KHz,+/-20%,11.5A,6mOhm,SHLD,G,SMD | VISHAY ENTER TECHNO LOGY.INC | IHLP1616ABERR10M01 | G | PWA BOM | In New BOM |
|  |  |  | 63032QU00-034-G | Coil Ind,Shielded(SHLD),100nH@100KHz,+/-20%,12A,4mOhm,SMD,4.15*4.0*1.8,G | CYNTEC CO. LTD | PCMB042T-R10MS | G | PWA BOM | In New BOM |
|  | PBML1,PBAL1,PAML1,PAAL1,PBFL2,PBEL2,PAFL2,PAEL2,PBML3,PBFL3,PBEL3,PBAL3,PAML3,PAFL3,PAEL3,PAAL3,PBAL5,PAAL5 | 18 | 63035NQ00-029-G | IND,0.1uH@100KHz,+/-20%,11.5A,6mOhm,SHLD,G,SMD | VISHAY ENTER TECHNO LOGY.INC | IHLP1616ABERR10M01 | G | PWA BOM | In Old BOM |
| 15 | PHAR4,PBMR90,PAMR90,PBER92,PBAR92,PAFR92,PAER92,PAAR92,PBFR93,PBAR102,PAAR102 | 11 | 610130Y00-017-G | RES,1 Ohm,+/-1%,1/3W,G,SMD1206 | KOA SPEER ELECTRONICS, INC. | SR732BTTD1R00F | G | PWA BOM | In New BOM |
|  |  |  | L1206K1R00FNT | RES,1 Ohm,+/-1%,1/3W,G,SMD1206 | VISHAY ENTER TECHNO LOGY.INC | L1206K1R00FNT | G | PWA BOM | In New BOM |
|  | PHAR4,PBMR90,PAMR90,PBER92,PBAR92,PAFR92,PAER92,PAAR92,PBFR93,PBAR102,PAAR102 | 11 | 610130Y00-017-G | RES,1 Ohm,+/-1%,1/3W,G,SMD1206 | KOA SPEER ELECTRONICS, INC. | SR732BTTD1R00F | G | PWA BOM | In Old BOM |
| 16 | PBMR113,PAMR113,PBER115,PAFR115,PAER115,PBFR116,PBAR119,PAAR119 | 8 | 61100RU00-017-G | RES,59 Ohm,+/-1%,1/16W,G,SMD0402 | KOA SPEER ELECTRONICS, INC. | RN731ETTP59R0F25 | G | PWA BOM | In New BOM |
|  |  |  | TNPW040259R0FEEP | RES,59 Ohm,+/-1%,1/10W,G,SMD0402 | VISHAY ENTER TECHNO LOGY.INC | TNPW040259R0FEEP | G | PWA BOM | In New BOM |
|  | PBMR113,PAMR113,PBER115,PAFR115,PAER115,PBFR116,PBAR119,PAAR119 | 8 | 61100RU00-017-G | RES,59 Ohm,+/-1%,1/16W,G,SMD0402 | KOA SPEER ELECTRONICS, INC. | RN731ETTP59R0F25 | G | PWA BOM | In Old BOM |
| 17 | PBFL1,PBEL1,PAFL1,PAEL1,PBML2,PAML2 | 6 | 63035NF00-57M-G | IND,1.5uH@100KHz,+/-10%,12A,6mOhm,SHLD,G,SMD | Eaton Corporation | HCV1206-1R5-R | G | PWA BOM | In New BOM |
|  |  |  | HMS1360-1R5 | IND,1.5uH@100KHz,+/-10%,12A,6mOhm,SHLD,G,SMD | DELTA ELECTRONICS INDUSTRIAL CO.,LTD | HMS1360-1R5 | G | PWA BOM | In New BOM |
|  | PBFL1,PBEL1,PAFL1,PAEL1,PBML2,PAML2 | 6 | 63035NF00-57M-G | IND,1.5uH@100KHz,+/-10%,12A,6mOhm,SHLD,G,SMD | Eaton Corporation | HCV1206-1R5-R | G | PWA BOM | In Old BOM |
| 18 | PCIE1,PCIE5 | 2 | 10061913-102HLF | CONN,PCIE-8X,V/T,Bla,1mm,30u,G,SMD-98 | FCI CONNECTORS HONGKONG LTD. | 10061913-102HLF | G | PWA BOM | In New BOM |
|  |  |  | 2041366-4 | CONN,PCIE-8X,V/T,Bla,1mm,30u,G,SMD-98 | TYCO ELECTRONICS CORPORATION | 2041366-4 | G | PWA BOM | In New BOM |
|  | PCIE1,PCIE5 | 2 | 10061913-102HLF | CONN,PCIE-8X,V/T,Bla,1mm,30u,G,SMD-98 | FCI CONNECTORS HONGKONG LTD. | 10061913-102HLF | G | PWA BOM | In Old BOM |
| 19 | PCIE2,PCIE3,PCIE4 | 3 | 10061913-103HLF | CONN,PCIE-16X,V/T,Bla,1mm,30u,G,SMD-164 | FCI CONNECTORS HONGKONG LTD. | 10061913-103HLF | G | PWA BOM | In New BOM |
|  |  |  | 2041366-6 | CONN,PCIE-16X,V/T,Bla,1mm,30u,G,SMD-164 | TYCO ELECTRONICS CORPORATION | 2041366-6 | G | PWA BOM | In New BOM |
|  | PCIE2,PCIE3,PCIE4 | 3 | 10061913-103HLF | CONN,PCIE-16X,V/T,Bla,1mm,30u,G,SMD-164 | FCI CONNECTORS HONGKONG LTD. | 10061913-103HLF | G | PWA BOM | In Old BOM |
| 20 | PETL1,PERL1,PSFL2,PEEL2,PEDL2 | 5 | 63032CD00-088-G | IND,2.2uH@100KHz,+/-20%,8A,20mOhm,SHLD,G,SMD | COOPER BUSSMANN, INC. | HCM0703-2R2-R | G | PWA BOM | In New BOM |
|  |  |  | CMLE063T-2R2MS | IND,CMLE063T-2R2MS | CYNTEC CO. LTD | CMLE063T-2R2MS | G | PWA BOM | In New BOM |
|  | PETL1,PERL1,PSFL2,PEEL2,PEDL2 | 5 | 63032CD00-088-G | IND,2.2uH@100KHz,+/-20%,8A,20mOhm,SHLD,G,SMD | COOPER BUSSMANN, INC. | HCM0703-2R2-R | G | PWA BOM | In Old BOM |
| 21 | PSPCE1,PIPCE1,PFPCE1,PEPCE1,PSUCE4 | 5 | 62120HJ00-022-G | ECAP,SPEA,270uF,+/-20%,16V,105C,G,SMD6.3X9.9,ESR<=8mOhm | SANYO ELECTRIC CO., LTD. | 16SVPG270M | G | PWA BOM | In New BOM |
|  |  |  | 62120LS00-021-G | ECAP,Solid Polymer Electrolytic Aluminium Capacitor (SPEA),Low ESR(LESR),270uF,+/-20%,16V,105℃,10mOhm,SMD,6.3*7.7,G | NIPPON CHEMI-CON CORPORATION | APXJ160ARA271MF80J | G | PWA BOM | In New BOM |
|  | PSPCE1,PIPCE1,PFPCE1,PEPCE1,PSUCE4 | 5 | 62120HJ00-022-G | ECAP,SPEA,270uF,+/-20%,16V,105C,G,SMD6.3X9.9,ESR<=8mOhm | SANYO ELECTRIC CO., LTD. | 16SVPG270M | G | PWA BOM | In Old BOM |
| 22 | PSPL1,PIPL1,PFPL1,PEPL1 | 4 | 63032CC00-088-G | IND,1uH@100KHz,+/-20%,11A,10mOhm,SHLD,G,SMD | COOPER BUSSMANN, INC. | HCM0703-1R0-R | G | PWA BOM | In New BOM |
|  |  |  | CMMS063T1R0MS | IND,CMMS063T1R0MS | CYNTEC CO. LTD | CMMS063T1R0MS | G | PWA BOM | In New BOM |
|  |  |  | PA4341.102NLT | IND,PA4341.102NLT | PULSE ELECTRONICS (SINGAPORE) | PA4341.102NLT | G | PWA BOM | In New BOM |
|  | PSPL1,PIPL1,PFPL1,PEPL1 | 4 | 63032CC00-088-G | IND,1uH@100KHz,+/-20%,11A,10mOhm,SHLD,G,SMD | COOPER BUSSMANN, INC. | HCM0703-1R0-R | G | PWA BOM | In Old BOM |
| 23 | PQPL2,PFRL2 | 2 | 63032PP00-088-G | IND,4.7uH@100KHz,+/-20%,5.5A,40mOhm,SHLD,G,SMD | COOPER BUSSMANN, INC. | HCM0703-4R7-R | G | PWA BOM | In New BOM |
|  |  |  | 63030PW00-034-G | Coil Ind,Shielded(SHLD),4.7uH@100KHz,+/-20%,5.5A,40mOhm,SMD,7.3*6.6*3.0,G | CYNTEC CO. LTD | PCMC063T-4R7MN | G | PWA BOM | In New BOM |
|  |  |  | SPS-06CZ-4R7M-V1 | IND,4.7uH@100KHz,+/-20%,5.5A,40mOhm,SHLD,G,SMD | MAG.LAYERS, SCIENTIFIC-TECHNICS (KUNSHAN) CO., LTD. | SPS-06CZ-4R7M-V1 | G | PWA BOM | In New BOM |
|  | PQPL2,PFRL2 | 2 | 63032PP00-088-G | IND,4.7uH@100KHz,+/-20%,5.5A,40mOhm,SHLD,G,SMD | COOPER BUSSMANN, INC. | HCM0703-4R7-R | G | PWA BOM | In Old BOM |
|  |  |  | 63030PW00-034-G | Coil Ind,Shielded(SHLD),4.7uH@100KHz,+/-20%,5.5A,40mOhm,SMD,7.3*6.6*3.0,G | CYNTEC CO. LTD | PCMC063T-4R7MN | G | PWA BOM | In Old BOM |
|  |  |  | SPS-06CZ-4R7M-V1 | IND,4.7uH@100KHz,+/-20%,5.5A,40mOhm,SHLD,G,SMD | MAG.LAYERS, SCIENTIFIC-TECHNICS (KUNSHAN) CO., LTD. | SPS-06CZ-4R7M-V1 |  | PWA BOM | In Old BOM |
| 24 | PHAQ4 | 1 | 51020A000-031-G | TRANS P,PBHV9115T,150V,1A,G,SOT23-3,SMD | NXP SEMICONDUCTORS | PBHV9115T | G | PWA BOM | In New BOM |
|  |  |  | MMBT5401 | TRANS P,150V,1A,G,SOT23-3,SMD | FAIRCHILD SEMICONDUCTOR CORP | MMBT5401 | G | PWA BOM | In New BOM |
|  |  |  | MMBT5401-1 | TRANS P,150V,1A,G,SOT23-3,SMD | DIODES INCORPORATION | MMBT5401-1 | G | PWA BOM | In New BOM |
|  | PHAQ4 | 1 | 51020A000-031-G | TRANS P,PBHV9115T,150V,1A,G,SOT23-3,SMD | NXP SEMICONDUCTORS | PBHV9115T | G | PWA BOM | In Old BOM |
| 25 | PHAQ5,PHAQ6 | 2 | 51032D100-237-G | MOS N,DMN10H220L-7,100V,1.6A,220m@10V,G,SOT-23-3,SMD | DIODES INCORPORATION | DMN10H220L-7 | G | PWA BOM | In New BOM |
|  |  |  | FQT7N10LTF | MOS N,FQT7N10LTF,100V,1.7A,220m@10V,G,SOT-23-3,SMD | FAIRCHILD SEMICONDUCTOR CORP | FQT7N10LTF | G | PWA BOM | In New BOM |
|  | PHAQ5,PHAQ6 | 2 | 51032D100-237-G | MOS N,DMN10H220L-7,100V,1.6A,220m@10V,G,SOT-23-3,SMD | DIODES INCORPORATION | DMN10H220L-7 | G | PWA BOM | In Old BOM |
|  |  |  | FQT7N10L | MOS N,FQT7N10L,100V,1.7A,220m@10V,G,SOT-23-3,SMD | FAIRCHILD SEMICONDUCTOR CORP | FQT7N10L | G | PWA BOM | In Old BOM |
| 26 | PSTL2,PSLL2,PSDL2 | 3 | 630328U00-088-G | IND,3.3uH@100KHz,+/-20%,6A,30mOhm,SHLD,G,SMD | COOPER BUSSMANN, INC. | HCM0703-3R3-R | G | PWA BOM | In New BOM |
|  |  |  | 63034QP00-034-G | IND,3.3uH@100KHz,+/-20%,6.5A,21mOhm,SHLD,G,SMD | CYNTEC CO. LTD | PCME063T-3R3MS | G | PWA BOM | In New BOM |
|  | PSTL2,PSLL2,PSDL2 | 3 | 630328U00-088-G | IND,3.3uH@100KHz,+/-20%,6A,30mOhm,SHLD,G,SMD | COOPER BUSSMANN, INC. | HCM0703-3R3-R | G | PWA BOM | In Old BOM |
| 27 | PSIL1,PSEL2 | 2 | 63032A900-088-G | IND,1.5uH@100KHz,+/-20%,9A,15mOhm,SHLD,G,SMD | COOPER BUSSMANN, INC. | HCM0703-1R5-R | G | PWA BOM | In New BOM |
|  |  |  | 63032BW00-034-G | IND,1.5uH@100KHz,+/-20%,9A,15mOhm,SHLD,G,SMD | CYNTEC CO. LTD | PCMC063T-1R5MN | G | PWA BOM | In New BOM |
|  |  |  | 63030HW00-051-G | IND,1.5uH@100KHz,+/-20%,9A,11.8mOhm,SHLD,G,SMD | PULSE ELECTRONICS (SINGAPORE) | PG0426.152NLT | G | PWA BOM | In New BOM |
|  | PSIL1,PSEL2 | 2 | 63032A900-088-G | IND,1.5uH@100KHz,+/-20%,9A,15mOhm,SHLD,G,SMD | COOPER BUSSMANN, INC. | HCM0703-1R5-R | G | PWA BOM | In Old BOM |
|  |  |  | 63032BW00-034-G | IND,1.5uH@100KHz,+/-20%,9A,15mOhm,SHLD,G,SMD | CYNTEC CO. LTD | PCMC063T-1R5MN | G | PWA BOM | In Old BOM |
|  |  |  | 63030HW00-051-G | IND,1.5uH@100KHz,+/-20%,9A,11.8mOhm,SHLD,G,SMD | PULSE ELECTRONICS (SINGAPORE) | PG0426.152NLT |  | PWA BOM | In Old BOM |
| 28 | PSRL1 | 1 | 63033PG00-15A-G | IND,22nH@100KHz,+/-15%,22A,249.55uOhm,SHLD,G,SMD | The Inter-Technical Group, Inc. | SLC1615A-R022LHF | G | PWA BOM | In New BOM |
|  |  |  | 63035Y500-129-G | IND,22nH@100KHz,+/-15%,22A,249.55uOhm,SHLD,G,SMD | MAG.LAYERS, SCIENTIFIC-TECHNICS (KUNSHAN) CO., LTD. | MSI-400404-22NL-I | G | PWA BOM | In New BOM |
|  |  |  | 630352U00-034-G | IND,22nH@100KHz,+/-15%,22A,249.55uOhm,SHLD,G,SMD | CYNTEC CO. LTD | HCB0439-220 | G | PWA BOM | In New BOM |
|  | PSRL1 | 1 | 63033PG00-15A-G | IND,22nH@100KHz,+/-15%,22A,249.55uOhm,SHLD,G,SMD | The Inter-Technical Group, Inc. | SLC1615A-R022LHF | G | PWA BOM | In Old BOM |
| 29 | PSRL2 | 1 | 63034GW00-088-G | IND,680nH@100KHz,+/-20%,34A,1.33mOhm,SHLD,G,SMD | COOPER BUSSMANN, INC. | HCM1305-R68-R | G | PWA BOM | In New BOM |
|  |  |  | CMLB135T-R68MS | IND,680nH@100KHz,+/-20%,34A,1.33mOhm,SHLD,G,SMD | CYNTEC CO. LTD | CMLB135T-R68MS | G | PWA BOM | In New BOM |
|  | PSRL2 | 1 | 63034GW00-088-G | IND,680nH@100KHz,+/-20%,34A,1.33mOhm,SHLD,G,SMD | COOPER BUSSMANN, INC. | HCM1305-R68-R | G | PWA BOM | In Old BOM |
| 30 | QN2,QN3 | 2 | 510503B00-223-G | MOS N/N,NTZD3154NT1G,20V,0.54A,550m24.5V,G,SOT563-6,SMD | ON SEMICONDUCTOR CORP | NTZD3154NT1G | G | PWA BOM | In New BOM |
|  |  |  | Si1034CX-T1-GE3 | MOS N/N,EM6K6T2R,20V,0.3A,1ohm@4V,G,EMT-6,SMD | VISHAY ENTER TECHNO LOGY.INC | Si1034CX-T1-GE3 | G | PWA BOM | In New BOM |
|  |  |  | SSM6N36FE | MOS N/N,20V,0.54A,550m24.5V,G,SOT563-6,SMD | TOSHIBA ELECTRONICS ASIA LTD | SSM6N36FE | G | PWA BOM | In New BOM |
|  | QN2,QN3 | 2 | 510503B00-223-G | MOS N/N,NTZD3154NT1G,20V,0.54A,550m24.5V,G,SOT563-6,SMD | ON SEMICONDUCTOR CORP | NTZD3154NT1G | G | PWA BOM | In Old BOM |
| 31 | Q5,Q7 | 2 | 510406000-185-G | MOS P,FDD6685,30V,11A,30m@4.5V,G,TO252-3,SMD | FAIRCHILD SEMICONDUCTOR CORP | FDD6685 | G | PWA BOM | In New BOM |
|  |  |  | IPD042P03L3 | MOS P,30V,11A,30m@4.5V,G,TO252-3,SMD | INFINEON TECHNOLOGIES CORP. | IPD042P03L3 | G | PWA BOM | In New BOM |
|  |  |  | 51040WQ00-131-G | MOS P,TJ40S04M3L,-40V,-40A,9.1m@-10V,G,SMD-3 | TOSHIBA ELECTRONICS ASIA LTD | TJ40S04M3L | G | PWA BOM | In New BOM |
|  | Q5,Q7 | 2 | 510406000-185-G | MOS P,FDD6685,30V,11A,30m@4.5V,G,TO252-3,SMD | FAIRCHILD SEMICONDUCTOR CORP | FDD6685 | G | PWA BOM | In Old BOM |
| 32 | Q12 | 1 | 510501900-237-G | MOS N/N,2N7002DW-7-F,60V,0.115A,7.5ohm@5V,G,SOT363-6,SMD | DIODES INEORPORATION | 2N7002DW-7-F | G | PWA BOM | In New BOM |
|  |  |  | 51050HV00-031-G | FET Dual channel,NX7002BKS,60V,240mA,2.8Ohm@Vgs=10V,3.2Ohm@Vgs=5V,SOT-363,6P,G | NXP SEMICONDUCTORS | NX7002BKS | G | PWA BOM | In New BOM |
|  |  |  | 510507800-131-G | MOS N/N,SSM6N7002BFU,60V,200mA,3.3Ohm@4.5V,G,SC88-6,SMD | TOSHIBA ELECTRONICS ASIA LTD | SSM6N7002BFU | G | PWA BOM | In New BOM |
|  | Q12 | 1 | 510501900-237-G | MOS N/N,2N7002DW-7-F,60V,0.115A,7.5ohm@5V,G,SOT363-6,SMD | DIODES INEORPORATION | 2N7002DW-7-F | G | PWA BOM | In Old BOM |
| 33 | U6,U7,U8,U9,U53,U54,U56,U57,U58,U59,U64,U65,U67,U69,U70,U71,U72,U85,U88,U111,U113,U114,U115,U117,U169 | 25 | 310502800-031-G | IC,Buffer,74LVC1G07GW,1.65~5.5V,G,SOT353-5,SMD | NXP SEMICONDUCTORS | 74LVC1G07GW | G | PWA BOM | In New BOM |
|  |  |  | 310502C00-223-G | IC,Buffer,NL17SZ07DFT2G,1.65~5.50V,G,SC-88A/SOT-353-5,SMD | ON SEMICONDUCTOR CORP | NL17SZ07DFT2G | G | PWA BOM | In New BOM |
|  |  |  | 31050CU00-131-G | IC,Buffer,TC7SZ07FU,1.65~5.5V,G,SSOP-5,SMD | TOSHIBA ELECTRONICS ASIA LTD | TC7SZ07FU | G | PWA BOM | In New BOM |
|  | U6,U7,U8,U9,U53,U54,U56,U57,U58,U59,U64,U65,U67,U69,U70,U71,U72,U85,U88,U111,U113,U114,U115,U117,U169 | 25 | 310502800-031-G | IC,Buffer,74LVC1G07GW,1.65~5.5V,G,SOT353-5,SMD | NXP SEMICONDUCTORS | 74LVC1G07GW | G | PWA BOM | In Old BOM |
| 34 | U17 | 1 | 420212A00-216-G | DRAM,MT40A512M16JY-083E:B,1.2V,512M*16,1.2GHz,G,FBGA-96,SMD | MICRON SEMICONDUCTOR ASIA PTE.LTD. | MT40A512M16JY-083E:B | G | PWA BOM | In New BOM |
|  |  |  | H5AN8G6NAFR-UHC | DRAM,1.2V,512M*16,1.2GHz,G,FBGA-96,SMD | SK HYNIX | H5AN8G6NAFR-UHC | G | PWA BOM | In New BOM |
|  | U17 | 1 | 420212A00-216-G | DRAM,MT40A512M16JY-083E:B,1.2V,512M*16,1.2GHz,G,FBGA-96,SMD | MICRON SEMICONDUCTOR ASIA PTE.LTD. | MT40A512M16JY-083E:B | G | PWA BOM | In Old BOM |
| 35 | U24 | 1 | 41050DL00-233-G | Flash,MX25L6445EMI-10G,2.7~3.6V,64M,SPI,G,SOP-16,SMD | MACRONIX INTERNATIONAL CO.,LTD. | MX25L6445EMI-10G | G | PWA BOM | In New BOM |
|  |  |  | 41050SF00-233-G | Flash,MX25L6435EMI-10G,2.7~3.6V,64M,SPI,G,SOP-16,SMD | MACRONIX INTERNATIONAL CO.,LTD. | MX25L6435EMI-10G | G | PWA BOM | In New BOM |
|  |  |  | 41050DW00-396-G | Flash,S25FL064P0XMFI001,2.7~3.6V,64M,SPI,G,SO-16,SMD | SPANSION INTERNATIONAL LLC | S25FL064P0XMFI001 | G | PWA BOM | In New BOM |
|  | U24 | 1 | 41050DL00-233-G | Flash,MX25L6445EMI-10G,2.7~3.6V,64M,SPI,G,SOP-16,SMD | MACRONIX INTERNATIONAL CO.,LTD. | MX25L6445EMI-10G | G | PWA BOM | In Old BOM |
| 36 | U29 | 1 | 21050F900-217-G | IC,IDT,2305B-1DCG8,B,G,SOIC-8,SMD | INTEGRATED DEVICE TECHNOLOGY | 2305B-1DCG8 | G | PWA BOM | In New BOM |
|  |  |  | SL2305SC-1 | IC,SL2305SC-1,G,SOIC-8,SMD | Silicon Laboratories Inc. | SL2305SC-1 | G | PWA BOM | In New BOM |
|  |  |  | 31050JC00-223-G | Logic IC,Buffer,NB2305AI1DR2G,3.0V~3.6V,0.35ns,SOIC,8P,G | ON SEMICONDUCTOR CORP | NB2305AI1DR2G | G | PWA BOM | In New BOM |
|  | U29 | 1 | 21050F900-217-G | IC,IDT,2305B-1DCG8,B,G,SOIC-8,SMD | INTEGRATED DEVICE TECHNOLOGY | 2305B-1DCG8 | G | PWA BOM | In Old BOM |
| 37 | U46 | 1 | 41050K700-233-G | Flash,MX25L4006EM2I-12G,2.7V~3.6V,4M,SPI,G,SOP-8,SMD | MACRONIX INTERNATIONAL CO.,LTD. | MX25L4006EM2I-12G | G | PWA BOM | In New BOM |
|  |  |  | 41050RL00-205-G | NOR Flash,W25X40CLSSIG,2.3V,N/A,3.6V,4M,SPI,-40_x0003_~85_x0003_,SOIC,8P,G | WINBOND ELECTRONIC CO.,LTD. | W25X40CLSSIG | G | PWA BOM | In New BOM |
|  | U46 | 1 | 41050K700-233-G | Flash,MX25L4006EM2I-12G,2.7V~3.6V,4M,SPI,G,SOP-8,SMD | MACRONIX INTERNATIONAL CO.,LTD. | MX25L4006EM2I-12G | G | PWA BOM | In Old BOM |
|  |  |  | 41050RL00-205-G | NOR Flash,W25X40CLSSIG,2.3V,N/A,3.6V,4M,SPI,-40_x0003_~85_x0003_,SOIC,8P,G | WINBOND | W25X40CLSSIG | G | PWA BOM | In Old BOM |
| 38 | U61 | 1 | 21050Q600-217-G | IC,IDT,5PB1102PGGI8,G,TSSOP-8,SMD | INTEGRATED DEVICE TECHNOLOGY | 5PB1102PGGI8 | G | PWA BOM | In New BOM |
|  |  |  | 31050JY00-223-G | Logic IC,Buffer,NB3V1102CDTR2G,1.8V/2.5V/3.3V,3.5ns,TSSOP,8P,G | ON SEMICONDUCTOR CORP | NB3V1102CDTR2G | G | PWA BOM | In New BOM |
|  | U61 | 1 | 21050Q600-217-G | IC,IDT,5PB1102PGGI8,G,TSSOP-8,SMD | INTEGRATED DEVICE TECHNOLOGY | 5PB1102PGGI8 | G | PWA BOM | In Old BOM |
| 39 | U83,U101,U102 | 3 | 310500F00-031-G | IC,Buffer,74LVC07APW,1.65~5.5V,G,TSSOP-14,SMD | NXP SEMICONDUCTORS | 74LVC07APW | G | PWA BOM | In New BOM |
|  |  |  | 74LVC0AT14-13 | IC,Buffer,74LVC07A,1.65~5.5V,G,TSSOP-14,SMD | DIODES INCORPORATION | 74LVC0AT14-13 | G | PWA BOM | In New BOM |
|  | U83,U101,U102 | 3 | 310500F00-031-G | IC,Buffer,74LVC07APW,1.65~5.5V,G,TSSOP-14,SMD | NXP SEMICONDUCTORS | 74LVC07APW | G | PWA BOM | In Old BOM |
| 40 | U109 | 1 | 310307T00-031-G | IC,Switch,74CBTLV1G125GV,2.3~3.6V,G,SOT753-5,SMD | NXP SEMICONDUCTORS | 74CBTLV1G125GV | G | PWA BOM | In New BOM |
|  |  |  | 310300D00-183-G | Logic IC,Switch,SN74CBTLV1G125DBVR,2.3V-3.6V,0.25ns,SOT-23,5P,G | Texas Instruments | SN74CBTLV1G125DBVR | G | PWA BOM | In New BOM |
|  | U109 | 1 | 310307T00-031-G | IC,Switch,74CBTLV1G125GV,2.3~3.6V,G,SOT753-5,SMD | NXP SEMICONDUCTORS | 74CBTLV1G125GV | G | PWA BOM | In Old BOM |
| 41 | U171 | 1 | 31050KL00-031-G | IC,Buffer,74HC75PW,2.0V~6.0V,G,TSSOP-16,SMD | NXP SEMICONDUCTORS | 74HC75PW | G | PWA BOM | In New BOM |
|  |  |  | CD74HC75PWRG4 | IC,Buffer,CD74HC75PWRG4 | Texas Instruments | CD74HC75PWRG4 |  | PWA BOM | In New BOM |
|  | U171 | 1 | 31050KL00-031-G | IC,Buffer,74HC75PW,2.0V~6.0V,G,TSSOP-16,SMD | NXP SEMICONDUCTORS | 74HC75PW | G | PWA BOM | In Old BOM |
| 42 | DIMM02,DIMM04,DIMM06,DIMM09,DIMM11,DIMM13,DIMM15,DIMM16,DIMM18,DIMM20,DIMM22,DIMM25,DIMM27,DIMM29,DIMM31,DIMM00 | 16 | 34021BC00-G78-G | CONN,DDR IV,V/T,1.2V,Blu,0.85mm,15u,G,SMD-288 | FCI CONNECTORS HONGKONG LTD. | 10140702-0302K11LF | G | PWA BOM | In New BOM |
|  |  |  | 34021CC00-245-G | Memory Connector,DDR4288S05A1H,DDR IV,288,SMD,NYLON,0.85mm,15u",Blue,G | AMPHENOL SHANGHAI CORP. | DDR4288S05A1H | G | PWA BOM | In New BOM |
|  | DIMM02,DIMM04,DIMM06,DIMM09,DIMM11,DIMM13,DIMM15,DIMM16,DIMM18,DIMM20,DIMM22,DIMM25,DIMM27,DIMM29,DIMM31,DIMM00 | 16 | 34021BC00-G78-G | CONN,DDR IV,V/T,1.2V,Blu,0.85mm,15u,G,SMD-288 | FCI CONNECTORS HONGKONG LTD. | 10140702-0302K11LF | G | PWA BOM | In Old BOM |
| 43 | DIMM01,DIMM03,DIMM05,DIMM07,DIMM08,DIMM10,DIMM12,DIMM14,DIMM17,DIMM19,DIMM21,DIMM23,DIMM24,DIMM26,DIMM28,DIMM30 | 16 | 34021BD00-G78-G | CONN,DDR IV,V/T,1.2V,Bla,0.85mm,15u,G,SMD-288 | FCI CONNECTORS HONGKONG LTD. | 10140702-0301K11LF | G | PWA BOM | In New BOM |
|  |  |  | 34021CE00-245-G | Memory Connector,DDR4288S0511H,DDR IV,288,SMD,NYLON,0.85mm,15u",Black,G | AMPHENOL SHANGHAI CORP. | DDR4288S0511H | G | PWA BOM | In New BOM |
|  | DIMM01,DIMM03,DIMM05,DIMM07,DIMM08,DIMM10,DIMM12,DIMM14,DIMM17,DIMM19,DIMM21,DIMM23,DIMM24,DIMM26,DIMM28,DIMM30 | 16 | 34021BD00-G78-G | CONN,DDR IV,V/T,1.2V,Bla,0.85mm,15u,G,SMD-288 | FCI CONNECTORS HONGKONG LTD. | 10140702-0301K11LF | G | PWA BOM | In Old BOM |
| 44 | J15 | 1 | 34031RP00-600-G | CONN,NGFF,R/A,Bla,0.5mm,30u,G,SMD-67 | FOXCONN TECHNOLOGY CO.,LTD. | 2E0BC23-S85BM-7H | G | PWA BOM | In New BOM |
|  |  |  | 34031T300-GRS-G | CONN,NGFF,R/A,Bla,0.5mm,30u,G,SMD-67 | LOTES CO LTD | APCI0164-P004A |  | PWA BOM | In New BOM |
|  | J15 | 1 | 34031RP00-600-G | CONN,NGFF,R/A,Bla,0.5mm,30u,G,SMD-67 | FOXCONN TECHNOLOGY CO.,LTD. | 2E0BC23-S85BM-7H | G | PWA BOM | In Old BOM |
| 45 | J35,J37,J39,J42,J45 | 5 | 3406AQH00-317-G | CONN,Header,Pin Header,1X6,V/T,Bla,2.54mm,G,SMD-6 | MOLEX INCORPORATED | 87898-0656 | G | PWA BOM | In New BOM |
|  |  |  | 3406AYA00-245-G | Header&Socket Connector,G800MR302032EU,Pin Header,6,DIP,LCP,2.54mm,999.9999u",Black,G | AMPHENOL SHANGHAI CORP. | G800MR302032EU |  | PWA BOM | In New BOM |
|  |  |  | 3406A9F00-GRT-G | Header&Socket Connector,212-91-06GBE2,Pin Header,6,SMD,NY6T,2.54mm,3u",Black,G | PINREX TECHNOLOGY CORP. | 212-91-06GBE2 |  | PWA BOM | In New BOM |
|  | J35,J37,J39,J42,J45 | 5 | 3406AQH00-317-G | CONN,Header,Pin Header,1X6,V/T,Bla,2.54mm,G,SMD-6 | MOLEX INCORPORATED | 87898-0656 | G | PWA BOM | In Old BOM |
| 46 | J101 | 1 | 34062MW00-309-G | CONN,Header,WTB,2X5,V/T,Bla,1.27mm,10u,G,SMD-10 | SAMTEC INC. | FTSH-105-01-L-DV-K-P-TR | G | PWA BOM | In New BOM |
|  |  |  | 3406AR700-GRT-G | Header&Socket Connector,232-9B-05SBEC,Pin Header,10,SMD,NY6T,1.27mm,10u",Black,G | PINREX TECHNOLOGY CORP. | 232-9B-05SBEC |  | PWA BOM | In New BOM |
|  | J101 | 1 | 34062MW00-309-G | CONN,Header,WTB,2X5,V/T,Bla,1.27mm,10u,G,SMD-10 | SAMTEC INC. | FTSH-105-01-L-DV-K-P-TR | G | PWA BOM | In Old BOM |
| 47 | J148 | 1 | 340672300-317-G | CONN,Pin Header,1X4,V/T,Bla,2.54mm,30u,G,SMD-4 | MOLEX INCORPORATED | 87898-0455 | G | PWA BOM | In New BOM |
|  |  |  | 340692T00-245-G | CONN,Header,Pin Header,1X4,V/T,Bla,2.54mm,30u,G,SMD-4 | AMPHENOL SHANGHAI CORP. | G800MR304010HR | G | PWA BOM | In New BOM |
|  |  |  | 34068VT00-GRT-G | CONN,Header,Pin Header,1X4,V/T,Bla,2.54mm,30u,G,SMD-4 | PINREX TECHNOLOGY CORP. | 212-91-04SBEJ | G | PWA BOM | In New BOM |
|  | J148 | 1 | 340672300-317-G | CONN,Pin Header,1X4,V/T,Bla,2.54mm,30u,G,SMD-4 | MOLEX INCORPORATED | 87898-0455 | G | PWA BOM | In Old BOM |
| 48 | SW1,SW2 | 2 | 340805A00-638-G | CONN,Switch,tact,50mA,12V,G,SMD-2 | E-SWITCH | TL1015AF160QG | G | PWA BOM | In New BOM |
|  |  |  | 340812T00-653-G | CONN,Switch,tact,50mA,12V,Bla,G,SMD-2 | DIPTRONICS MANUFACTURING INC. | MPTLP2-V-T/R | G | PWA BOM | In New BOM |
|  | SW1,SW2 | 2 | 340805A00-638-G | CONN,Switch,tact,50mA,12V,G,SMD-2 | E-SWITCH | TL1015AF160QG | G | PWA BOM | In Old BOM |
| ##### Change Revision |  |  |  |  |  |  |  |  |  |
| Sheet | REV OF BOM | CUSTOMER | CUSTOMER P/N | PWA PN | PWA DESCRIPTION | PWA REV | DATE | Remark |  |
| OOOOOOOOOOOOOOOOOOOOOOOOOOOOOOOOOOOOOOOOOOOOOOOOOOOOOOOOOOOOOOOOOOOOOOOOOOOOOOOOOOOOOOOOOO | OOOOOOOOOOOOOOOOOOOOOOOOOOOOOOOOOOOOOOOOOOOOOOOOOOOOOOOOOOOOOOOOOOOOOOOOOOOOOOOOOOOOOOOOOO | OOOOOOOOOOOOOOOOOOOOOOOOOOOOOOOOOOOOOOOOOOOOOOOOOOOOOOOOOOOOOOOOOOOOOOOOOOOOOOOOOOOOOOOOOO | OOOOOOOOOOOOOOOOOOOOOOOOOOOOOOOOOOOOOOOOOOOOOOOOOOOOOOOOOOOOOOOOOOOOOOOOOOOOOOOOOOOOOOOOOO | OOOOOOOOOOOOOOOOOOOOOOOOOOOOOOOOOOOOOOOOOOOOOOOOOOOOOOOOOOOOOOOOOOOOOOOOOOOOOOOOOOOOOOOOOO | OOOOOOOOOOOOOOOOOOOOOOOOOOOOOOOOOOOOOOOOOOOOOOOOOOOOOOOOOOOOOOOOOOOOOOOOOOOOOOOOOOOOOOOOOO | OOOOOOOOOOOOOOOOOOOOOOOOOOOOOOOOOOOOOOOOOOOOOOOOOOOOOOOOOOOOOOOOOOOOOOOOOOOOOOOOOOOOOOOOOO | OOOOOOOOOOOOOOOOOOOOOOOOOOOOOOOOOOOOOOOOOOOOOOOOOOOOOOOOOOOOOOOOOOOOOOOOOOOOOOOOOOOOOOOOOO | OOOOOOOOOOOOOOOOOOOOOOOOOOOOOOOOOOOOOOOOOOOOOOOOOOOOOOOOOOOOOOOOOOOOOOOOOOOOOOOOOOOOOOOOOO | OOOOOOOOOOOOOOOOOOOOOOOOOOOOOOOOOOOOOOOOOOOOOOOOOOOOOOOOOOOOOOOOOOOOOOOOOOOOOOOOOOOOOOOOOO |
| Second Source Change |  |  |  |  |  |  |  |  |  |
| Item | Location | Change Type | Foxconn P/N | Part Description | Manufacturer Full Name | Manufacturer P/N | RoHS | Sheet |  |
| 1 | PSTC5,PSLC5,PSFC5,PSEC5,PSDC5,PQPC5,PFRC5,PEEC5,PEDC5,C46,C63,C69,C79,C142,C144,C157,C167,C226,C234,C774,C781,C785,C813,C856,C864,C873,C883 |  | 62012P100-015-G | CAP,2.2uF,+/-20%,X7S,10V,G,SMD0402 | MURATA ELEC. NORTH AMERICA | GRM155C71A225M | G | PWA BOM |  |
|  |  | Delete | 62012P000-023-G | CAP,2.2uF,+/-10%,X7R,16V,G,SMD0603 | TAIYO ELECTRIC IND.CO.LTD | EMK107BB7225KA-T | G | PWA BOM |  |
| 2 | D57 |  | 52030NP00-185-G | DIODE,Schottky,RB521S30,30V,200mA,G,SOD523-2,SMD | FAIRCHILD SEMICONDUCTOR CORP | RB521S30 | G | PWA BOM |  |
|  |  | ADD | 52030NP00-031-G | DIODE,Schottky,SDM20U30-7,30V,0.2A,G,SOD523-2,SMD | NXP SEMICONDUCTORS | RB521S30 | G | PWA BOM |  |
|  |  | ADD | 52030AG00-237-G | DIODE,Schottky,SDM20U30-7,30V,0.2A,G,SOD523-2,SMD | DIODES INCORPORATION | SDM20U30-7 | G | PWA BOM |  |
| 3 | LED11,LED12 |  | 52113AW00-289-G | LED,Green,LTL-42NGY8DH184P,5V,20mA,G,DIP-2 | LITE-ON TECHNOLOGY CORPORATION | LTL-42NGY8DH184P | G | PWA BOM |  |
|  |  | ADD | SSF-LXH303SUGD | LED,Green,LTL-42NGY8DH184P,5V,20mA,G,DIP-2 | LUEMX INC,TAIWAN BRANCH | SSF-LXH303SUGD | G | PWA BOM |  |
| 4 | L17 |  | 720106E00-015-G | FB,330 Ohm@100MHz,+/-25%,500mA,300mOhm,G,SMD0603 | MURATA ELEC. NORTH AMERICA | BLM18EG331TN1D | G | PWA BOM |  |
|  |  | ADD | 72010YW01-129-G | FB,Multilayer,100mOhm,330Ohm@100MHz,+/-25%,2A,,SMD0603,G | MAG.LAYERS, SCIENTIFIC-TECHNICS (KUNSHAN) CO., LTD. | GMLB-160808-0330P-N8 | G | PWA BOM |  |
| 5 | L22,L23,L24,L25 |  | 720105P00-016-G | FB,80 Ohm@100MHz,+/-25%,500mA,150mOhm,G,SMD0603 | TDK ELECTRONICS EUROPE GMBH | MMZ1608S800AT | G | PWA BOM |  |
|  |  | ADD | 72010WQ00-129-G | FB,Multilayer,40mOhm,80Ohm@100MHz,+/-25%,3A,,SMD0603,G | MAG.LAYERS, SCIENTIFIC-TECHNICS (KUNSHAN) CO., LTD. | GMLB-160808-0080P-N8 | G | PWA BOM |  |
|  |  | Delete | GMLB-160808-0080P-N8 | FB,80 Ohm@100MHz,+/-25%,500mA,150mOhm,G,SMD0603 | MAG.LAYERS, SCIENTIFIC-TECHNICS (KUNSHAN) CO., LTD. | GMLB-160808-0080P-N8 | G | PWA BOM |  |
| 6 | L45 |  | 720101M00-015-G | FB,600 Ohm@100MHz,+/-25%,200mA,650mOhm,G,SMD0603 | MURATA ELEC. NORTH AMERICA | BLM18BD601SN1D | G | PWA BOM |  |
|  |  | ADD | 720103000-023-G | FB,600 Ohm@100MHz,+/-25%,250mA,600mOhm,G,SMD0603 | TAIYO ELECTRIC IND.CO.LTD | BK1608HM601-T | G | PWA BOM |  |
| 7 | PBMC6,PBFC6,PBEC6,PBAC6,PAMC6,PAFC6,PAEC6,PAAC6 |  | 62011DQ00-015-G | CAP,27nF,+/-10%,X7R,25V,G,SMD0402 | MURATA ELEC. NORTH AMERICA | GRM155R71E273KA88D | G | PWA BOM |  |
|  |  | ADD | C0402C273K3RAC | CAP,27nF,+/-10%,X7R,25V,G,SMD0402 | KEMET ELECTRONICS CORPORATION | C0402C273K3RAC | G | PWA BOM |  |
| 8 | PBMD1,PBFD1,PBED1,PBAD1,PAMD1,PAFD1,PAED1,PAAD1 |  | 520103B00-185-G | Diode,Rectifier&Switching,MMBD1205,100V,200mA,G,SOT-23-3,SMD | FAIRCHILD SEMICONDUCTOR CORP | MMBD1205 | G | PWA BOM |  |
|  |  | ADD | MMBD3004A | Diode,Rectifier&Switching,100V,200mA,G,SOT-23-3,SMD | DIODES INCORPORATION | MMBD3004A | G | PWA BOM |  |
| 9 | PSUFS1,PBAFS1,PAAFS1,PSUFS2 |  | 730100M00-086-G | Fuse,Very fast acting,125V,10A,G,SMD | LITTELFUSE FAR EAST PTE LTD | 0451010.MRL | G | PWA BOM |  |
|  |  | ADD | CB61F10A-TR2 | Fuse,CB61F10A-TR2 | COOPER BUSSMANN, INC. | CB61F10A-TR2 | G | PWA BOM |  |
| 10 | PBML1,PBAL1,PAML1,PAAL1,PBFL2,PBEL2,PAFL2,PAEL2,PBML3,PBFL3,PBEL3,PBAL3,PAML3,PAFL3,PAEL3,PAAL3,PBAL5,PAAL5 |  | 63035NQ00-029-G | IND,0.1uH@100KHz,+/-20%,11.5A,6mOhm,SHLD,G,SMD | VISHAY ENTER TECHNO LOGY.INC | IHLP1616ABERR10M01 | G | PWA BOM |  |
|  |  | ADD | 63032QU00-034-G | Coil Ind,Shielded(SHLD),100nH@100KHz,+/-20%,12A,4mOhm,SMD,4.15*4.0*1.8,G | CYNTEC CO. LTD | PCMB042T-R10MS | G | PWA BOM |  |
| 11 | PHAR4,PBMR90,PAMR90,PBER92,PBAR92,PAFR92,PAER92,PAAR92,PBFR93,PBAR102,PAAR102 |  | 610130Y00-017-G | RES,1 Ohm,+/-1%,1/3W,G,SMD1206 | KOA SPEER ELECTRONICS, INC. | SR732BTTD1R00F | G | PWA BOM |  |
|  |  | ADD | L1206K1R00FNT | RES,1 Ohm,+/-1%,1/3W,G,SMD1206 | VISHAY ENTER TECHNO LOGY.INC | L1206K1R00FNT | G | PWA BOM |  |
| 12 | PBMR113,PAMR113,PBER115,PAFR115,PAER115,PBFR116,PBAR119,PAAR119 |  | 61100RU00-017-G | RES,59 Ohm,+/-1%,1/16W,G,SMD0402 | KOA SPEER ELECTRONICS, INC. | RN731ETTP59R0F25 | G | PWA BOM |  |
|  |  | ADD | TNPW040259R0FEEP | RES,59 Ohm,+/-1%,1/10W,G,SMD0402 | VISHAY ENTER TECHNO LOGY.INC | TNPW040259R0FEEP | G | PWA BOM |  |
| 13 | PBFL1,PBEL1,PAFL1,PAEL1,PBML2,PAML2 |  | 63035NF00-57M-G | IND,1.5uH@100KHz,+/-10%,12A,6mOhm,SHLD,G,SMD | Eaton Corporation | HCV1206-1R5-R | G | PWA BOM |  |
|  |  | ADD | HMS1360-1R5 | IND,1.5uH@100KHz,+/-10%,12A,6mOhm,SHLD,G,SMD | DELTA ELECTRONICS INDUSTRIAL CO.,LTD | HMS1360-1R5 | G | PWA BOM |  |
| 14 | PCIE1,PCIE5 |  | 10061913-102HLF | CONN,PCIE-8X,V/T,Bla,1mm,30u,G,SMD-98 | FCI CONNECTORS HONGKONG LTD. | 10061913-102HLF | G | PWA BOM |  |
|  |  | ADD | 2041366-4 | CONN,PCIE-8X,V/T,Bla,1mm,30u,G,SMD-98 | TYCO ELECTRONICS CORPORATION | 2041366-4 | G | PWA BOM |  |
| 15 | PCIE2,PCIE3,PCIE4 |  | 10061913-103HLF | CONN,PCIE-16X,V/T,Bla,1mm,30u,G,SMD-164 | FCI CONNECTORS HONGKONG LTD. | 10061913-103HLF | G | PWA BOM |  |
|  |  | ADD | 2041366-6 | CONN,PCIE-16X,V/T,Bla,1mm,30u,G,SMD-164 | TYCO ELECTRONICS CORPORATION | 2041366-6 | G | PWA BOM |  |
| 16 | PETL1,PERL1,PSFL2,PEEL2,PEDL2 |  | 63032CD00-088-G | IND,2.2uH@100KHz,+/-20%,8A,20mOhm,SHLD,G,SMD | COOPER BUSSMANN, INC. | HCM0703-2R2-R | G | PWA BOM |  |
|  |  | ADD | CMLE063T-2R2MS | IND,CMLE063T-2R2MS | CYNTEC CO. LTD | CMLE063T-2R2MS | G | PWA BOM |  |
| 17 | PSPCE1,PIPCE1,PFPCE1,PEPCE1,PSUCE4 |  | 62120HJ00-022-G | ECAP,SPEA,270uF,+/-20%,16V,105C,G,SMD6.3X9.9,ESR<=8mOhm | SANYO ELECTRIC CO., LTD. | 16SVPG270M | G | PWA BOM |  |
|  |  | ADD | 62120LS00-021-G | ECAP,Solid Polymer Electrolytic Aluminium Capacitor (SPEA),Low ESR(LESR),270uF,+/-20%,16V,105℃,10mOhm,SMD,6.3*7.7,G | NIPPON CHEMI-CON CORPORATION | APXJ160ARA271MF80J | G | PWA BOM |  |
| 18 | PSPL1,PIPL1,PFPL1,PEPL1 |  | 63032CC00-088-G | IND,1uH@100KHz,+/-20%,11A,10mOhm,SHLD,G,SMD | COOPER BUSSMANN, INC. | HCM0703-1R0-R | G | PWA BOM |  |
|  |  | ADD | CMMS063T1R0MS | IND,CMMS063T1R0MS | CYNTEC CO. LTD | CMMS063T1R0MS | G | PWA BOM |  |
|  |  | ADD | PA4341.102NLT | IND,PA4341.102NLT | PULSE ELECTRONICS (SINGAPORE) | PA4341.102NLT | G | PWA BOM |  |
| 19 | PHAQ4 |  | 51020A000-031-G | TRANS P,PBHV9115T,150V,1A,G,SOT23-3,SMD | NXP SEMICONDUCTORS | PBHV9115T | G | PWA BOM |  |
|  |  | ADD | MMBT5401 | TRANS P,150V,1A,G,SOT23-3,SMD | FAIRCHILD SEMICONDUCTOR CORP | MMBT5401 | G | PWA BOM |  |
|  |  | ADD | MMBT5401-1 | TRANS P,150V,1A,G,SOT23-3,SMD | DIODES INCORPORATION | MMBT5401-1 | G | PWA BOM |  |
| 20 | PHAQ5,PHAQ6 |  | 51032D100-237-G | MOS N,DMN10H220L-7,100V,1.6A,220m@10V,G,SOT-23-3,SMD | DIODES INCORPORATION | DMN10H220L-7 | G | PWA BOM |  |
|  |  | ADD | FQT7N10LTF | MOS N,FQT7N10LTF,100V,1.7A,220m@10V,G,SOT-23-3,SMD | FAIRCHILD SEMICONDUCTOR CORP | FQT7N10LTF | G | PWA BOM |  |
|  |  | Delete | FQT7N10L | MOS N,FQT7N10L,100V,1.7A,220m@10V,G,SOT-23-3,SMD | FAIRCHILD SEMICONDUCTOR CORP | FQT7N10L | G | PWA BOM |  |
| 21 | PSTL2,PSLL2,PSDL2 |  | 630328U00-088-G | IND,3.3uH@100KHz,+/-20%,6A,30mOhm,SHLD,G,SMD | COOPER BUSSMANN, INC. | HCM0703-3R3-R | G | PWA BOM |  |
|  |  | ADD | 63034QP00-034-G | IND,3.3uH@100KHz,+/-20%,6.5A,21mOhm,SHLD,G,SMD | CYNTEC CO. LTD | PCME063T-3R3MS | G | PWA BOM |  |
| 22 | PSRL1 |  | 63033PG00-15A-G | IND,22nH@100KHz,+/-15%,22A,249.55uOhm,SHLD,G,SMD | The Inter-Technical Group, Inc. | SLC1615A-R022LHF | G | PWA BOM |  |
|  |  | ADD | 63035Y500-129-G | IND,22nH@100KHz,+/-15%,22A,249.55uOhm,SHLD,G,SMD | MAG.LAYERS, SCIENTIFIC-TECHNICS (KUNSHAN) CO., LTD. | MSI-400404-22NL-I | G | PWA BOM |  |
|  |  | ADD | 630352U00-034-G | IND,22nH@100KHz,+/-15%,22A,249.55uOhm,SHLD,G,SMD | CYNTEC CO. LTD | HCB0439-220 | G | PWA BOM |  |
| 23 | PSRL2 |  | 63034GW00-088-G | IND,680nH@100KHz,+/-20%,34A,1.33mOhm,SHLD,G,SMD | COOPER BUSSMANN, INC. | HCM1305-R68-R | G | PWA BOM |  |
|  |  | ADD | CMLB135T-R68MS | IND,680nH@100KHz,+/-20%,34A,1.33mOhm,SHLD,G,SMD | CYNTEC CO. LTD | CMLB135T-R68MS | G | PWA BOM |  |
| 24 | QN2,QN3 |  | 510503B00-223-G | MOS N/N,NTZD3154NT1G,20V,0.54A,550m24.5V,G,SOT563-6,SMD | ON SEMICONDUCTOR CORP | NTZD3154NT1G | G | PWA BOM |  |
|  |  | ADD | Si1034CX-T1-GE3 | MOS N/N,EM6K6T2R,20V,0.3A,1ohm@4V,G,EMT-6,SMD | VISHAY ENTER TECHNO LOGY.INC | Si1034CX-T1-GE3 | G | PWA BOM |  |
|  |  | ADD | SSM6N36FE | MOS N/N,20V,0.54A,550m24.5V,G,SOT563-6,SMD | TOSHIBA ELECTRONICS ASIA LTD | SSM6N36FE | G | PWA BOM |  |
| 25 | Q5,Q7 |  | 510406000-185-G | MOS P,FDD6685,30V,11A,30m@4.5V,G,TO252-3,SMD | FAIRCHILD SEMICONDUCTOR CORP | FDD6685 | G | PWA BOM |  |
|  |  | ADD | IPD042P03L3 | MOS P,30V,11A,30m@4.5V,G,TO252-3,SMD | INFINEON TECHNOLOGIES CORP. | IPD042P03L3 | G | PWA BOM |  |
|  |  | ADD | 51040WQ00-131-G | MOS P,TJ40S04M3L,-40V,-40A,9.1m@-10V,G,SMD-3 | TOSHIBA ELECTRONICS ASIA LTD | TJ40S04M3L | G | PWA BOM |  |
| 26 | Q12 |  | 510501900-237-G | MOS N/N,2N7002DW-7-F,60V,0.115A,7.5ohm@5V,G,SOT363-6,SMD | DIODES INEORPORATION | 2N7002DW-7-F | G | PWA BOM |  |
|  |  | ADD | 51050HV00-031-G | FET Dual channel,NX7002BKS,60V,240mA,2.8Ohm@Vgs=10V,3.2Ohm@Vgs=5V,SOT-363,6P,G | NXP SEMICONDUCTORS | NX7002BKS | G | PWA BOM |  |
|  |  | ADD | 510507800-131-G | MOS N/N,SSM6N7002BFU,60V,200mA,3.3Ohm@4.5V,G,SC88-6,SMD | TOSHIBA ELECTRONICS ASIA LTD | SSM6N7002BFU | G | PWA BOM |  |
| 27 | U6,U7,U8,U9,U53,U54,U56,U57,U58,U59,U64,U65,U67,U69,U70,U71,U72,U85,U88,U111,U113,U114,U115,U117,U169 |  | 310502800-031-G | IC,Buffer,74LVC1G07GW,1.65~5.5V,G,SOT353-5,SMD | NXP SEMICONDUCTORS | 74LVC1G07GW | G | PWA BOM |  |
|  |  | ADD | 310502C00-223-G | IC,Buffer,NL17SZ07DFT2G,1.65~5.50V,G,SC-88A/SOT-353-5,SMD | ON SEMICONDUCTOR CORP | NL17SZ07DFT2G | G | PWA BOM |  |
|  |  | ADD | 31050CU00-131-G | IC,Buffer,TC7SZ07FU,1.65~5.5V,G,SSOP-5,SMD | TOSHIBA ELECTRONICS ASIA LTD | TC7SZ07FU | G | PWA BOM |  |
| 28 | U17 |  | 420212A00-216-G | DRAM,MT40A512M16JY-083E:B,1.2V,512M*16,1.2GHz,G,FBGA-96,SMD | MICRON SEMICONDUCTOR ASIA PTE.LTD. | MT40A512M16JY-083E:B | G | PWA BOM |  |
|  |  | ADD | H5AN8G6NAFR-UHC | DRAM,1.2V,512M*16,1.2GHz,G,FBGA-96,SMD | SK HYNIX | H5AN8G6NAFR-UHC | G | PWA BOM |  |
| 29 | U24 |  | 41050DL00-233-G | Flash,MX25L6445EMI-10G,2.7~3.6V,64M,SPI,G,SOP-16,SMD | MACRONIX INTERNATIONAL CO.,LTD. | MX25L6445EMI-10G | G | PWA BOM |  |
|  |  | ADD | 41050SF00-233-G | Flash,MX25L6435EMI-10G,2.7~3.6V,64M,SPI,G,SOP-16,SMD | MACRONIX INTERNATIONAL CO.,LTD. | MX25L6435EMI-10G | G | PWA BOM |  |
|  |  | ADD | 41050DW00-396-G | Flash,S25FL064P0XMFI001,2.7~3.6V,64M,SPI,G,SO-16,SMD | SPANSION INTERNATIONAL LLC | S25FL064P0XMFI001 | G | PWA BOM |  |
| 30 | U29 |  | 21050F900-217-G | IC,IDT,2305B-1DCG8,B,G,SOIC-8,SMD | INTEGRATED DEVICE TECHNOLOGY | 2305B-1DCG8 | G | PWA BOM |  |
|  |  | ADD | SL2305SC-1 | IC,SL2305SC-1,G,SOIC-8,SMD | Silicon Laboratories Inc. | SL2305SC-1 | G | PWA BOM |  |
|  |  | ADD | 31050JC00-223-G | Logic IC,Buffer,NB2305AI1DR2G,3.0V~3.6V,0.35ns,SOIC,8P,G | ON SEMICONDUCTOR CORP | NB2305AI1DR2G | G | PWA BOM |  |
| 31 | U61 |  | 21050Q600-217-G | IC,IDT,5PB1102PGGI8,G,TSSOP-8,SMD | INTEGRATED DEVICE TECHNOLOGY | 5PB1102PGGI8 | G | PWA BOM |  |
|  |  | ADD | 31050JY00-223-G | Logic IC,Buffer,NB3V1102CDTR2G,1.8V/2.5V/3.3V,3.5ns,TSSOP,8P,G | ON SEMICONDUCTOR CORP | NB3V1102CDTR2G | G | PWA BOM |  |
| 32 | U83,U101,U102 |  | 310500F00-031-G | IC,Buffer,74LVC07APW,1.65~5.5V,G,TSSOP-14,SMD | NXP SEMICONDUCTORS | 74LVC07APW | G | PWA BOM |  |
|  |  | ADD | 74LVC0AT14-13 | IC,Buffer,74LVC07A,1.65~5.5V,G,TSSOP-14,SMD | DIODES INCORPORATION | 74LVC0AT14-13 | G | PWA BOM |  |
| 33 | U109 |  | 310307T00-031-G | IC,Switch,74CBTLV1G125GV,2.3~3.6V,G,SOT753-5,SMD | NXP SEMICONDUCTORS | 74CBTLV1G125GV | G | PWA BOM |  |
|  |  | ADD | 310300D00-183-G | Logic IC,Switch,SN74CBTLV1G125DBVR,2.3V-3.6V,0.25ns,SOT-23,5P,G | Texas Instruments | SN74CBTLV1G125DBVR | G | PWA BOM |  |
| 34 | U171 |  | 31050KL00-031-G | IC,Buffer,74HC75PW,2.0V~6.0V,G,TSSOP-16,SMD | NXP SEMICONDUCTORS | 74HC75PW | G | PWA BOM |  |
|  |  | ADD | CD74HC75PWRG4 | IC,Buffer,CD74HC75PWRG4 | Texas Instruments | CD74HC75PWRG4 |  | PWA BOM |  |
| 35 | DIMM02,DIMM04,DIMM06,DIMM09,DIMM11,DIMM13,DIMM15,DIMM16,DIMM18,DIMM20,DIMM22,DIMM25,DIMM27,DIMM29,DIMM31,DIMM00 |  | 34021BC00-G78-G | CONN,DDR IV,V/T,1.2V,Blu,0.85mm,15u,G,SMD-288 | FCI CONNECTORS HONGKONG LTD. | 10140702-0302K11LF | G | PWA BOM |  |
|  |  | ADD | 34021CC00-245-G | Memory Connector,DDR4288S05A1H,DDR IV,288,SMD,NYLON,0.85mm,15u",Blue,G | AMPHENOL SHANGHAI CORP. | DDR4288S05A1H | G | PWA BOM |  |
| 36 | DIMM01,DIMM03,DIMM05,DIMM07,DIMM08,DIMM10,DIMM12,DIMM14,DIMM17,DIMM19,DIMM21,DIMM23,DIMM24,DIMM26,DIMM28,DIMM30 |  | 34021BD00-G78-G | CONN,DDR IV,V/T,1.2V,Bla,0.85mm,15u,G,SMD-288 | FCI CONNECTORS HONGKONG LTD. | 10140702-0301K11LF | G | PWA BOM |  |
|  |  | ADD | 34021CE00-245-G | Memory Connector,DDR4288S0511H,DDR IV,288,SMD,NYLON,0.85mm,15u",Black,G | AMPHENOL SHANGHAI CORP. | DDR4288S0511H | G | PWA BOM |  |
| 37 | J15 |  | 34031RP00-600-G | CONN,NGFF,R/A,Bla,0.5mm,30u,G,SMD-67 | FOXCONN TECHNOLOGY CO.,LTD. | 2E0BC23-S85BM-7H | G | PWA BOM |  |
|  |  | ADD | 34031T300-GRS-G | CONN,NGFF,R/A,Bla,0.5mm,30u,G,SMD-67 | LOTES CO LTD | APCI0164-P004A |  | PWA BOM |  |
| 38 | J35,J37,J39,J42,J45 |  | 3406AQH00-317-G | CONN,Header,Pin Header,1X6,V/T,Bla,2.54mm,G,SMD-6 | MOLEX INCORPORATED | 87898-0656 | G | PWA BOM |  |
|  |  | ADD | 3406AYA00-245-G | Header&Socket Connector,G800MR302032EU,Pin Header,6,DIP,LCP,2.54mm,999.9999u",Black,G | AMPHENOL SHANGHAI CORP. | G800MR302032EU |  | PWA BOM |  |
|  |  | ADD | 3406A9F00-GRT-G | Header&Socket Connector,212-91-06GBE2,Pin Header,6,SMD,NY6T,2.54mm,3u",Black,G | PINREX TECHNOLOGY CORP. | 212-91-06GBE2 |  | PWA BOM |  |
| 39 | J101 |  | 34062MW00-309-G | CONN,Header,WTB,2X5,V/T,Bla,1.27mm,10u,G,SMD-10 | SAMTEC INC. | FTSH-105-01-L-DV-K-P-TR | G | PWA BOM |  |
|  |  | ADD | 3406AR700-GRT-G | Header&Socket Connector,232-9B-05SBEC,Pin Header,10,SMD,NY6T,1.27mm,10u",Black,G | PINREX TECHNOLOGY CORP. | 232-9B-05SBEC |  | PWA BOM |  |
| 40 | J148 |  | 340672300-317-G | CONN,Pin Header,1X4,V/T,Bla,2.54mm,30u,G,SMD-4 | MOLEX INCORPORATED | 87898-0455 | G | PWA BOM |  |
|  |  | ADD | 340692T00-245-G | CONN,Header,Pin Header,1X4,V/T,Bla,2.54mm,30u,G,SMD-4 | AMPHENOL SHANGHAI CORP. | G800MR304010HR | G | PWA BOM |  |
|  |  | ADD | 34068VT00-GRT-G | CONN,Header,Pin Header,1X4,V/T,Bla,2.54mm,30u,G,SMD-4 | PINREX TECHNOLOGY CORP. | 212-91-04SBEJ | G | PWA BOM |  |
| 41 | SW1,SW2 |  | 340805A00-638-G | CONN,Switch,tact,50mA,12V,G,SMD-2 | E-SWITCH | TL1015AF160QG | G | PWA BOM |  |
|  |  | ADD | 340812T00-653-G | CONN,Switch,tact,50mA,12V,Bla,G,SMD-2 | DIPTRONICS MANUFACTURING INC. | MPTLP2-V-T/R | G | PWA BOM |  |
| OOOOOOOOOOOOOOOOOOOOOOOOOOOOOOOOOOOOOOOOOOOOOOOOOOOOOOOOOOOOOOOOOOOOOOOOOOOOOOOOOOOOOOOOOO | OOOOOOOOOOOOOOOOOOOOOOOOOOOOOOOOOOOOOOOOOOOOOOOOOOOOOOOOOOOOOOOOOOOOOOOOOOOOOOOOOOOOOOOOOO | OOOOOOOOOOOOOOOOOOOOOOOOOOOOOOOOOOOOOOOOOOOOOOOOOOOOOOOOOOOOOOOOOOOOOOOOOOOOOOOOOOOOOOOOOO | OOOOOOOOOOOOOOOOOOOOOOOOOOOOOOOOOOOOOOOOOOOOOOOOOOOOOOOOOOOOOOOOOOOOOOOOOOOOOOOOOOOOOOOOOO | OOOOOOOOOOOOOOOOOOOOOOOOOOOOOOOOOOOOOOOOOOOOOOOOOOOOOOOOOOOOOOOOOOOOOOOOOOOOOOOOOOOOOOOOOO | OOOOOOOOOOOOOOOOOOOOOOOOOOOOOOOOOOOOOOOOOOOOOOOOOOOOOOOOOOOOOOOOOOOOOOOOOOOOOOOOOOOOOOOOOO | OOOOOOOOOOOOOOOOOOOOOOOOOOOOOOOOOOOOOOOOOOOOOOOOOOOOOOOOOOOOOOOOOOOOOOOOOOOOOOOOOOOOOOOOOO | OOOOOOOOOOOOOOOOOOOOOOOOOOOOOOOOOOOOOOOOOOOOOOOOOOOOOOOOOOOOOOOOOOOOOOOOOOOOOOOOOOOOOOOOOO | OOOOOOOOOOOOOOOOOOOOOOOOOOOOOOOOOOOOOOOOOOOOOOOOOOOOOOOOOOOOOOOOOOOOOOOOOOOOOOOOOOOOOOOOOO | OOOOOOOOOOOOOOOOOOOOOOOOOOOOOOOOOOOOOOOOOOOOOOOOOOOOOOOOOOOOOOOOOOOOOOOOOOOOOOOOOOOOOOOOOO |
| Master Materials Change |  |  |  |  |  |  |  |  |  |
| Item | Foxconn P/N | Orig._Usage | New_Usage | Part Description | Manufacturer Full Name | Manufacturer P/N | RoHS | Location | Sheet |
| OOOOOOOOOOOOOOOOOOOOOOOOOOOOOOOOOOOOOOOOOOOOOOOOOOOOOOOOOOOOOOOOOOOOOOOOOOOOOOOOOOOOOOOOOO | OOOOOOOOOOOOOOOOOOOOOOOOOOOOOOOOOOOOOOOOOOOOOOOOOOOOOOOOOOOOOOOOOOOOOOOOOOOOOOOOOOOOOOOOOO | OOOOOOOOOOOOOOOOOOOOOOOOOOOOOOOOOOOOOOOOOOOOOOOOOOOOOOOOOOOOOOOOOOOOOOOOOOOOOOOOOOOOOOOOOO | OOOOOOOOOOOOOOOOOOOOOOOOOOOOOOOOOOOOOOOOOOOOOOOOOOOOOOOOOOOOOOOOOOOOOOOOOOOOOOOOOOOOOOOOOO | OOOOOOOOOOOOOOOOOOOOOOOOOOOOOOOOOOOOOOOOOOOOOOOOOOOOOOOOOOOOOOOOOOOOOOOOOOOOOOOOOOOOOOOOOO | OOOOOOOOOOOOOOOOOOOOOOOOOOOOOOOOOOOOOOOOOOOOOOOOOOOOOOOOOOOOOOOOOOOOOOOOOOOOOOOOOOOOOOOOOO | OOOOOOOOOOOOOOOOOOOOOOOOOOOOOOOOOOOOOOOOOOOOOOOOOOOOOOOOOOOOOOOOOOOOOOOOOOOOOOOOOOOOOOOOOO | OOOOOOOOOOOOOOOOOOOOOOOOOOOOOOOOOOOOOOOOOOOOOOOOOOOOOOOOOOOOOOOOOOOOOOOOOOOOOOOOOOOOOOOOOO | OOOOOOOOOOOOOOOOOOOOOOOOOOOOOOOOOOOOOOOOOOOOOOOOOOOOOOOOOOOOOOOOOOOOOOOOOOOOOOOOOOOOOOOOOO | OOOOOOOOOOOOOOOOOOOOOOOOOOOOOOOOOOOOOOOOOOOOOOOOOOOOOOOOOOOOOOOOOOOOOOOOOOOOOOOOOOOOOOOOOO |
| TLA Parts Change |  |  |  |  |  |  |  |  |  |
| Item | Foxconn P/N | Qty | Part Description | Manufacturer Full Name | Manufacturer P/N | RoHS | Location | Remark | BOM |
| BOM Change List Date:Wed May 31 18:58:26 CST 2017 |  |  |  |  |  |  |  |  |  |
| New BOM file : C:\<user>\ZAIUS-MB-DVT-X03-SKU-BOM_X23_20170531.xls |  |  |  |  |  |  |  |  |  |
| Old BOM file : C:\<user>\ZAIUS-MB-DVT-X03-SKU-BOM_X23_20170531.xls |  |  |  |  |  |  |  |  |  |
| ##### Add Parts |  |  |  |  |  |  |  |  |  |
| Item | Location | Qty | Foxconn P/N | Part Description | Manufacturer Full Name | Manufacturer P/N | RoHS | Sheet |  |
| ##### Remove Parts |  |  |  |  |  |  |  |  |  |
| Item | Location | Qty | Foxconn P/N | Part Description | Manufacturer Full Name | Manufacturer P/N | RoHS | Sheet |  |
| ##### Change Parts |  |  |  |  |  |  |  |  |  |
| Item | Location | Qty | Foxconn P/N | Part Description | Manufacturer Full Name | Manufacturer P/N | RoHS | Sheet | Remark |
| 1 | ED1,ED2,ED3 | 3 | 521800900-227-G | DIODE,Array-TVS,SRV05-4.TCT,5V,12A,G,SOT23-6,SMD | SEMTECH CORPORATION. | SRV05-4.TCT | G | PWA BOM | In New BOM |
|  |  |  | 52180C200-086-G | Diode,Array-TVS,SRV05-4HTG,SOT-23,6P,G | LITTELFUSE FAR EAST PTE LTD | SRV05-4HTG |  | PWA BOM | In New BOM |
|  | ED1,ED2,ED3 | 3 | 521800900-227-G | DIODE,Array-TVS,SRV05-4.TCT,5V,12A,G,SOT23-6,SMD | SEMTECH CORPORATION. | SRV05-4.TCT | G | PWA BOM | In Old BOM |
|  |  |  | 52180H500-086-G | Diode,Array-TVS,SRV05-04HTG,SOT-23,6P,G | LITTELFUSE FAR EAST PTE LTD | SRV05-04HTG | G | PWA BOM | In Old BOM |
| 2 | LED10,LED14 | 2 | 52113B000-289-G | LED,Yellow,LTL-42NSV8DH184P,5V,20mA,G,DIP-2 | LITE-ON TECHNOLOGY CORPORATION | LTL-42NSV8DH184P | G | PWA BOM | In New BOM |
|  | LED10,LED14 | 2 | 52113B000-289-G | LED,Yellow,LTL-42NSV8DH184P,5V,20mA,G,DIP-2 | LITE-ON TECHNOLOGY CORPORATION | LTL-42NSV8DH184P | G | PWA BOM | In Old BOM |
|  |  |  | L-7104ADFX012-TW | LED,YellowL-7104ADFX012-TW,5V,20mA,G,DIP-2 | KINGBRIGHT ELECTRONIC CO., LTD. | L-7104ADFX012-TW | G | PWA BOM | In Old BOM |
| 3 | LED11,LED12 | 2 | 52113AW00-289-G | LED,Green,LTL-42NGY8DH184P,5V,20mA,G,DIP-2 | LITE-ON TECHNOLOGY CORPORATION | LTL-42NGY8DH184P | G | PWA BOM | In New BOM |
|  | LED11,LED12 | 2 | 52113AW00-289-G | LED,Green,LTL-42NGY8DH184P,5V,20mA,G,DIP-2 | LITE-ON TECHNOLOGY CORPORATION | LTL-42NGY8DH184P | G | PWA BOM | In Old BOM |
|  |  |  | SSF-LXH303GD | LED,Green,SSF-LXH303GD,5V,20mA,G,DIP-2 | LUEMX INC,TAIWAN BRANCH | SSF-LXH303GD | G | PWA BOM | In Old BOM |
| 4 | LED13 | 1 | 52113B100-289-G | LED,Blue,LTL42TB6NH184P,5V,30mA,G,DIP-2 | LITE-ON TECHNOLOGY CORPORATION | LTL42TB6NH184P | G | PWA BOM | In New BOM |
|  | LED13 | 1 | 52113B100-289-G | LED,Blue,LTL42TB6NH184P,5V,30mA,G,DIP-2 | LITE-ON TECHNOLOGY CORPORATION | LTL42TB6NH184P | G | PWA BOM | In Old BOM |
|  |  |  | L-7104ADFX010-TW | LED,Blue,L-7104ADFX010-TW,5V,30mA,G,DIP-2 | KINGBRIGHT ELECTRONIC CO., LTD. | L-7104ADFX010-TW | G | PWA BOM | In Old BOM |
| 5 | U24 | 1 | 41050DL00-233-G | Flash,MX25L6445EMI-10G,2.7~3.6V,64M,SPI,G,SOP-16,SMD | MACRONIX INTERNATIONAL CO.,LTD. | MX25L6445EMI-10G | G | PWA BOM | In New BOM |
|  |  |  | 41050DW00-396-G | Flash,S25FL064P0XMFI001,2.7~3.6V,64M,SPI,G,SO-16,SMD | SPANSION INTERNATIONAL LLC | S25FL064P0XMFI001 | G | PWA BOM | In New BOM |
|  |  |  | W25Q64JVSFIQ | Flash,2.7~3.6V,64M,SPI,G,SOP-16,SMD | WINBOND | W25Q64JVSFIQ |  | PWA BOM | In New BOM |
|  |  |  | 41050SF00-233-G | Flash,MX25L6435EMI-10G,2.7~3.6V,64M,SPI,G,SOP-16,SMD | MACRONIX INTERNATIONAL CO.,LTD. | MX25L6435EMI-10G | G | PWA BOM | In New BOM |
|  | U24 | 1 | 41050DL00-233-G | Flash,MX25L6445EMI-10G,2.7~3.6V,64M,SPI,G,SOP-16,SMD | MACRONIX INTERNATIONAL CO.,LTD. | MX25L6445EMI-10G | G | PWA BOM | In Old BOM |
|  |  |  | 41050DW00-396-G | Flash,S25FL064P0XMFI001,2.7~3.6V,64M,SPI,G,SO-16,SMD | SPANSION INTERNATIONAL LLC | S25FL064P0XMFI001 | G | PWA BOM | In Old BOM |
|  |  |  | W25Q64JVSFIM | Flash,2.7~3.6V,64M,SPI,G,SOP-16,SMD | WINBOND | W25Q64JVSFIM |  | PWA BOM | In Old BOM |
|  |  |  | 41050SF00-233-G | Flash,MX25L6435EMI-10G,2.7~3.6V,64M,SPI,G,SOP-16,SMD | MACRONIX INTERNATIONAL CO.,LTD. | MX25L6435EMI-10G | G | PWA BOM | In Old BOM |
| ##### Change Revision |  |  |  |  |  |  |  |  |  |
| Sheet | REV OF BOM | CUSTOMER | CUSTOMER P/N | PWA PN | PWA DESCRIPTION | PWA REV | DATE | Remark |  |
| OOOOOOOOOOOOOOOOOOOOOOOOOOOOOOOOOOOOOOOOOOOOOOOOOOOOOOOOOOOOOOOOOOOOOOOOOOOOOOOOOOOOOOOOOO | OOOOOOOOOOOOOOOOOOOOOOOOOOOOOOOOOOOOOOOOOOOOOOOOOOOOOOOOOOOOOOOOOOOOOOOOOOOOOOOOOOOOOOOOOO | OOOOOOOOOOOOOOOOOOOOOOOOOOOOOOOOOOOOOOOOOOOOOOOOOOOOOOOOOOOOOOOOOOOOOOOOOOOOOOOOOOOOOOOOOO | OOOOOOOOOOOOOOOOOOOOOOOOOOOOOOOOOOOOOOOOOOOOOOOOOOOOOOOOOOOOOOOOOOOOOOOOOOOOOOOOOOOOOOOOOO | OOOOOOOOOOOOOOOOOOOOOOOOOOOOOOOOOOOOOOOOOOOOOOOOOOOOOOOOOOOOOOOOOOOOOOOOOOOOOOOOOOOOOOOOOO | OOOOOOOOOOOOOOOOOOOOOOOOOOOOOOOOOOOOOOOOOOOOOOOOOOOOOOOOOOOOOOOOOOOOOOOOOOOOOOOOOOOOOOOOOO | OOOOOOOOOOOOOOOOOOOOOOOOOOOOOOOOOOOOOOOOOOOOOOOOOOOOOOOOOOOOOOOOOOOOOOOOOOOOOOOOOOOOOOOOOO | OOOOOOOOOOOOOOOOOOOOOOOOOOOOOOOOOOOOOOOOOOOOOOOOOOOOOOOOOOOOOOOOOOOOOOOOOOOOOOOOOOOOOOOOOO | OOOOOOOOOOOOOOOOOOOOOOOOOOOOOOOOOOOOOOOOOOOOOOOOOOOOOOOOOOOOOOOOOOOOOOOOOOOOOOOOOOOOOOOOOO | OOOOOOOOOOOOOOOOOOOOOOOOOOOOOOOOOOOOOOOOOOOOOOOOOOOOOOOOOOOOOOOOOOOOOOOOOOOOOOOOOOOOOOOOOO |
| Second Source Change |  |  |  |  |  |  |  |  |  |
| Item | Location | Change Type | Foxconn P/N | Part Description | Manufacturer Full Name | Manufacturer P/N | RoHS | Sheet |  |
| 1 | ED1,ED2,ED3 |  | 521800900-227-G | DIODE,Array-TVS,SRV05-4.TCT,5V,12A,G,SOT23-6,SMD | SEMTECH CORPORATION. | SRV05-4.TCT | G | PWA BOM |  |
|  |  | ADD | 52180C200-086-G | Diode,Array-TVS,SRV05-4HTG,SOT-23,6P,G | LITTELFUSE FAR EAST PTE LTD | SRV05-4HTG |  | PWA BOM |  |
|  |  | Delete | 52180H500-086-G | Diode,Array-TVS,SRV05-04HTG,SOT-23,6P,G | LITTELFUSE FAR EAST PTE LTD | SRV05-04HTG | G | PWA BOM |  |
| 2 | LED10,LED14 |  | 52113B000-289-G | LED,Yellow,LTL-42NSV8DH184P,5V,20mA,G,DIP-2 | LITE-ON TECHNOLOGY CORPORATION | LTL-42NSV8DH184P | G | PWA BOM |  |
|  |  | Delete | L-7104ADFX012-TW | LED,YellowL-7104ADFX012-TW,5V,20mA,G,DIP-2 | KINGBRIGHT ELECTRONIC CO., LTD. | L-7104ADFX012-TW | G | PWA BOM |  |
| 3 | LED11,LED12 |  | 52113AW00-289-G | LED,Green,LTL-42NGY8DH184P,5V,20mA,G,DIP-2 | LITE-ON TECHNOLOGY CORPORATION | LTL-42NGY8DH184P | G | PWA BOM |  |
|  |  | Delete | SSF-LXH303GD | LED,Green,SSF-LXH303GD,5V,20mA,G,DIP-2 | LUEMX INC,TAIWAN BRANCH | SSF-LXH303GD | G | PWA BOM |  |
| 4 | LED13 |  | 52113B100-289-G | LED,Blue,LTL42TB6NH184P,5V,30mA,G,DIP-2 | LITE-ON TECHNOLOGY CORPORATION | LTL42TB6NH184P | G | PWA BOM |  |
|  |  | Delete | L-7104ADFX010-TW | LED,Blue,L-7104ADFX010-TW,5V,30mA,G,DIP-2 | KINGBRIGHT ELECTRONIC CO., LTD. | L-7104ADFX010-TW | G | PWA BOM |  |
| 5 | U24 |  | 41050DL00-233-G | Flash,MX25L6445EMI-10G,2.7~3.6V,64M,SPI,G,SOP-16,SMD | MACRONIX INTERNATIONAL CO.,LTD. | MX25L6445EMI-10G | G | PWA BOM |  |
|  |  | NO | 41050DW00-396-G | Flash,S25FL064P0XMFI001,2.7~3.6V,64M,SPI,G,SO-16,SMD | SPANSION INTERNATIONAL LLC | S25FL064P0XMFI001 | G | PWA BOM |  |
|  |  | ADD | W25Q64JVSFIQ | Flash,2.7~3.6V,64M,SPI,G,SOP-16,SMD | WINBOND | W25Q64JVSFIQ |  | PWA BOM |  |
|  |  | NO | 41050SF00-233-G | Flash,MX25L6435EMI-10G,2.7~3.6V,64M,SPI,G,SOP-16,SMD | MACRONIX INTERNATIONAL CO.,LTD. | MX25L6435EMI-10G | G | PWA BOM |  |
|  |  | Delete | W25Q64JVSFIM | Flash,2.7~3.6V,64M,SPI,G,SOP-16,SMD | WINBOND | W25Q64JVSFIM |  | PWA BOM |  |
| OOOOOOOOOOOOOOOOOOOOOOOOOOOOOOOOOOOOOOOOOOOOOOOOOOOOOOOOOOOOOOOOOOOOOOOOOOOOOOOOOOOOOOOOOO | OOOOOOOOOOOOOOOOOOOOOOOOOOOOOOOOOOOOOOOOOOOOOOOOOOOOOOOOOOOOOOOOOOOOOOOOOOOOOOOOOOOOOOOOOO | OOOOOOOOOOOOOOOOOOOOOOOOOOOOOOOOOOOOOOOOOOOOOOOOOOOOOOOOOOOOOOOOOOOOOOOOOOOOOOOOOOOOOOOOOO | OOOOOOOOOOOOOOOOOOOOOOOOOOOOOOOOOOOOOOOOOOOOOOOOOOOOOOOOOOOOOOOOOOOOOOOOOOOOOOOOOOOOOOOOOO | OOOOOOOOOOOOOOOOOOOOOOOOOOOOOOOOOOOOOOOOOOOOOOOOOOOOOOOOOOOOOOOOOOOOOOOOOOOOOOOOOOOOOOOOOO | OOOOOOOOOOOOOOOOOOOOOOOOOOOOOOOOOOOOOOOOOOOOOOOOOOOOOOOOOOOOOOOOOOOOOOOOOOOOOOOOOOOOOOOOOO | OOOOOOOOOOOOOOOOOOOOOOOOOOOOOOOOOOOOOOOOOOOOOOOOOOOOOOOOOOOOOOOOOOOOOOOOOOOOOOOOOOOOOOOOOO | OOOOOOOOOOOOOOOOOOOOOOOOOOOOOOOOOOOOOOOOOOOOOOOOOOOOOOOOOOOOOOOOOOOOOOOOOOOOOOOOOOOOOOOOOO | OOOOOOOOOOOOOOOOOOOOOOOOOOOOOOOOOOOOOOOOOOOOOOOOOOOOOOOOOOOOOOOOOOOOOOOOOOOOOOOOOOOOOOOOOO | OOOOOOOOOOOOOOOOOOOOOOOOOOOOOOOOOOOOOOOOOOOOOOOOOOOOOOOOOOOOOOOOOOOOOOOOOOOOOOOOOOOOOOOOOO |
| Master Materials Change |  |  |  |  |  |  |  |  |  |
| Item | Foxconn P/N | Orig._Usage | New_Usage | Part Description | Manufacturer Full Name | Manufacturer P/N | RoHS | Location | Sheet |
| OOOOOOOOOOOOOOOOOOOOOOOOOOOOOOOOOOOOOOOOOOOOOOOOOOOOOOOOOOOOOOOOOOOOOOOOOOOOOOOOOOOOOOOOOO | OOOOOOOOOOOOOOOOOOOOOOOOOOOOOOOOOOOOOOOOOOOOOOOOOOOOOOOOOOOOOOOOOOOOOOOOOOOOOOOOOOOOOOOOOO | OOOOOOOOOOOOOOOOOOOOOOOOOOOOOOOOOOOOOOOOOOOOOOOOOOOOOOOOOOOOOOOOOOOOOOOOOOOOOOOOOOOOOOOOOO | OOOOOOOOOOOOOOOOOOOOOOOOOOOOOOOOOOOOOOOOOOOOOOOOOOOOOOOOOOOOOOOOOOOOOOOOOOOOOOOOOOOOOOOOOO | OOOOOOOOOOOOOOOOOOOOOOOOOOOOOOOOOOOOOOOOOOOOOOOOOOOOOOOOOOOOOOOOOOOOOOOOOOOOOOOOOOOOOOOOOO | OOOOOOOOOOOOOOOOOOOOOOOOOOOOOOOOOOOOOOOOOOOOOOOOOOOOOOOOOOOOOOOOOOOOOOOOOOOOOOOOOOOOOOOOOO | OOOOOOOOOOOOOOOOOOOOOOOOOOOOOOOOOOOOOOOOOOOOOOOOOOOOOOOOOOOOOOOOOOOOOOOOOOOOOOOOOOOOOOOOOO | OOOOOOOOOOOOOOOOOOOOOOOOOOOOOOOOOOOOOOOOOOOOOOOOOOOOOOOOOOOOOOOOOOOOOOOOOOOOOOOOOOOOOOOOOO | OOOOOOOOOOOOOOOOOOOOOOOOOOOOOOOOOOOOOOOOOOOOOOOOOOOOOOOOOOOOOOOOOOOOOOOOOOOOOOOOOOOOOOOOOO | OOOOOOOOOOOOOOOOOOOOOOOOOOOOOOOOOOOOOOOOOOOOOOOOOOOOOOOOOOOOOOOOOOOOOOOOOOOOOOOOOOOOOOOOOO |
| TLA Parts Change |  |  |  |  |  |  |  |  |  |
| Item | Foxconn P/N | Qty | Part Description | Manufacturer Full Name | Manufacturer P/N | RoHS | Location | Remark | BOM |
| BOM Change List Date:Fri Jun 09 09:19:55 CST 2017 |  |  |  |  |  |  |  |  |  |
| New BOM file : C:\<user>\zaius 0606.xls |  |  |  |  |  |  |  |  |  |
| Old BOM file : C:\<user>\zaius 0531.xls |  |  |  |  |  |  |  |  |  |
| ##### Add Parts |  |  |  |  |  |  |  |  |  |
| Item | Location | Qty | Foxconn P/N | Part Description | Manufacturer Full Name | Manufacturer P/N | RoHS | Sheet |  |
| ##### Remove Parts |  |  |  |  |  |  |  |  |  |
| Item | Location | Qty | Foxconn P/N | Part Description | Manufacturer Full Name | Manufacturer P/N | RoHS | Sheet |  |
| ##### Change Parts |  |  |  |  |  |  |  |  |  |
| Item | Location | Qty | Foxconn P/N | Part Description | Manufacturer Full Name | Manufacturer P/N | RoHS | Sheet | Remark |
| 1 | PSTC4,PSLC4,PSFC4,PSEC4,PSDC4,PQPC4,PFRC4,PEEC4,PEDC4,PSPC3003,PIPC3003,PFPC3003,PEPC3003,PSRC3010 | 14 | 62012T300-015-G | CAP,1uF,+/-10%,X7S,25V,G,SMD0402 | MURATA ELEC. NORTH AMERICA | GRM155C71E105KE11D | G | PWA BOM | In New BOM |
|  |  |  | 620138700-026-G | CAP,1uF,+/-10%,X6S,25V,G,SMD0402 | SAMSUNG | CL05X105KA5NQNC | G | PWA BOM | In New BOM |
|  |  |  | GRM155C81E105KE11D | CAP,1uF,+/-10%,X6S,25V,G,SMD0402 | MURATA | GRM155C81E105KE11D | G | PWA BOM | In New BOM |
|  | PSTC4,PSLC4,PSFC4,PSEC4,PSDC4,PQPC4,PFRC4,PEEC4,PEDC4,PSPC3003,PIPC3003,PFPC3003,PEPC3003,PSRC3010 | 14 | 62012T300-015-G | CAP,1uF,+/-10%,X7S,25V,G,SMD0402 | MURATA ELEC. NORTH AMERICA | GRM155C71E105KE11D | G | PWA BOM | In Old BOM |
| 2 | PSPR10,PIPR10,PFPR10,PEPR10 | 4 | 61100QQ00-017-G | RES,9.76KOhm,+/-0.1%,1/16W,G,SMD0402 | KOA SPEER ELECTRONICS, INC. | RN731ETTP9761B25 | G | PWA BOM | In New BOM |
|  |  |  | 61100QQ00-024-G | RES,9.76KOhm,+/-0.1%,1/16W,G,SMD0402 | PANASONIC INDUSTRIAL CO.,LTD. | ERA2AEB9761X | G | PWA BOM | In New BOM |
|  |  |  | 61100QQ00-029-G | RES,9.76KOhm,+/-0.1%,1/16W,G,SMD0402 | VISHAY ENTER TECHNO LOGY.INC | TNPW04029K76BEED | G | PWA BOM | In New BOM |
|  | PSPR10,PIPR10,PFPR10,PEPR10 | 4 | 61100QQ00-017-G | RES,9.76KOhm,+/-0.1%,1/16W,G,SMD0402 | KOA SPEER ELECTRONICS, INC. | RN731ETTP9761B25 | G | PWA BOM | In Old BOM |
|  |  |  | 61100QQ00-024-G | RES,9.76KOhm,+/-0.1%,1/16W,G,SMD0402 | PANASONIC INDUSTRIAL CO.,LTD. | ERA2AEB9761X | G | PWA BOM | In Old BOM |
| 3 | PERC7 | 1 | 62013BN00-015-G | CAP,4.3nF,+/-10%,X7R,50V,G,SMD0402 | MURATA ELEC. NORTH AMERICA | GRM155R71H432KA01D | G | PWA BOM | In New BOM |
|  |  |  | 62010LJ00-023-G | CAP,4.7nF,+/-10%,X7R,50V,G,SMD0402 | TAIYO ELECTRIC IND.CO.LTD | UMK105B7472KV-F | G | PWA BOM | In New BOM |
|  | PERC7 | 1 | 62013BN00-015-G | CAP,4.3nF,+/-10%,X7R,50V,G,SMD0402 | MURATA ELEC. NORTH AMERICA | GRM155R71H432KA01D | G | PWA BOM | In Old BOM |
| 4 | PFRR19 | 1 | 61100YB00-017-G | RES,2.94KOhm,+/-0.1%,1/16W,G,SMD0402 | KOA SPEER ELECTRONICS, INC. | RN731ETTP2941B25 | G | PWA BOM | In New BOM |
|  |  |  | 61100YB00-011-G | RES,2.94KOhm,+/-0.1%,1/16W,SMD0402,G | YAGEO CORPORATION COMPONENT | RT0402BRD072K94L | G | PWA BOM | In New BOM |
|  |  |  | RB04BTP2941 | RES,2.94KOhm,+/-0.1%,1/16W,SMD0402,G | TA-I TECHNOLOGY CO., LTD. | RB04BTP2941 | G | PWA BOM | In New BOM |
|  | PFRR19 | 1 | 61100YB00-017-G | RES,2.94KOhm,+/-0.1%,1/16W,G,SMD0402 | KOA SPEER ELECTRONICS, INC. | RN731ETTP2941B25 | G | PWA BOM | In Old BOM |
|  |  |  | 61100YB00-011-G | RES,2.94KOhm,+/-0.1%,1/16W,SMD0402,G | YAGEO CORPORATION COMPONENT | RT0402BRD072K94L | G | PWA BOM | In Old BOM |
|  |  |  | RB04BTP2941B | RES,2.94KOhm,+/-0.1%,1/16W,SMD0402,G | TA-I TECHNOLOGY CO., LTD. | RB04BTP2941B | G | PWA BOM | In Old BOM |
| 5 | PHAR2 | 1 | 61100DA00-017-G | RES,33KOhm,+/-0.1%,1/16W,G,SMD0402 | KOA SPEER ELECTRONICS, INC. | RN731ETTP3302B25 | G | PWA BOM | In New BOM |
|  |  |  | 61100DA00-011-G | RES,33KOhm,+/-0.1%,1/16W,G,SMD0402 | YAGEO CORPORATION COMPONENT | RT0402BRD0733KL | G | PWA BOM | In New BOM |
|  |  |  | TNPW040233K0BEED | RES,33KOhm,+/-0.1%,1/16W,G,SMD0402 | VISHAY | TNPW040233K0BEED | G | PWA BOM | In New BOM |
|  | PHAR2 | 1 | 61100DA00-017-G | RES,33KOhm,+/-0.1%,1/16W,G,SMD0402 | KOA SPEER ELECTRONICS, INC. | RN731ETTP3302B25 | G | PWA BOM | In Old BOM |
|  |  |  | 61100DA00-011-G | RES,33KOhm,+/-0.1%,1/16W,G,SMD0402 | YAGEO CORPORATION COMPONENT | RT0402BRD0733KL | G | PWA BOM | In Old BOM |
| 6 | PHAR5 | 1 | 61100QM00-017-G | RES,100KOhm,+/-0.1%,1/10W,G,SMD0603 | KOA SPEER ELECTRONICS, INC. | RN73H1JTTD1003B25 | G | PWA BOM | In New BOM |
|  |  |  | 61100QM00-011-G | RES,100KOhm,+/-0.1%,1/10W,G,SMD0603 | YAGEO CORPORATION COMPONENT | RT0603BRD07100KL | G | PWA BOM | In New BOM |
|  |  |  | TNPW0402100KBEED | RES,100KOhm,+/-0.1%,1/10W,G,SMD0603 | VISHAY | TNPW0402100KBEED | G | PWA BOM | In New BOM |
|  | PHAR5 | 1 | 61100QM00-017-G | RES,100KOhm,+/-0.1%,1/10W,G,SMD0603 | KOA SPEER ELECTRONICS, INC. | RN73H1JTTD1003B25 | G | PWA BOM | In Old BOM |
|  |  |  | 61100QM00-011-G | RES,100KOhm,+/-0.1%,1/10W,G,SMD0603 | YAGEO CORPORATION COMPONENT | RT0603BRD07100KL | G | PWA BOM | In Old BOM |
| 7 | PHAR7 | 1 | 610107P00-017-G | RES,4.12KOhm,+/-1%,1/10W,G,SMD0603 | KOA SPEER ELECTRONICS, INC. | RK73H1JTTD4121F | G | PWA BOM | In New BOM |
|  |  |  | 610107P00-011-G | RES,4.12KOhm,+/-1%,1/10W,G,SMD0603 | YAGEO CORPORATION COMPONENT | RC0603FR-074K12L | G | PWA BOM | In New BOM |
|  |  |  | 610107P00-044-G | RES,4.12KOhm,+/-1%,1/10W,G,SMD0603 | TA-I TECHNOLOGY CO., LTD. | RM06FTN4121 | G | PWA BOM | In New BOM |
|  | PHAR7 | 1 | 610107P00-017-G | RES,4.12KOhm,+/-1%,1/10W,G,SMD0603 | KOA SPEER ELECTRONICS, INC. | RK73H1JTTD4121F | G | PWA BOM | In Old BOM |
|  |  |  | 610107P00-011-G | RES,4.12KOhm,+/-1%,1/10W,G,SMD0603 | YAGEO CORPORATION COMPONENT | RC0603FR-074K12L | G | PWA BOM | In Old BOM |
| 8 | R11,R12,R13,R373,R374,R375 | 6 | 61100Y400-017-G | RES,169 Ohm,+/-0.1%,1/16W,G,SMD0402 | KOA SPEER ELECTRONICS, INC. | RN731ETTP1690B25 | G | PWA BOM | In New BOM |
|  |  |  | 61100Y400-011-G | RES,169Ohm,+/-0.1%,1/16W,SMD0402,G | YAGEO CORPORATION COMPONENT | RT0402BRD07169RL | G | PWA BOM | In New BOM |
|  |  |  | RB04BTP1690 | RES,169Ohm,+/-0.1%,1/16W,SMD0402,G | TA-I TECHNOLOGY CO., LTD. | RB04BTP1690 | G | PWA BOM | In New BOM |
|  | R11,R12,R13,R373,R374,R375 | 6 | 61100Y400-017-G | RES,169 Ohm,+/-0.1%,1/16W,G,SMD0402 | KOA SPEER ELECTRONICS, INC. | RN731ETTP1690B25 | G | PWA BOM | In Old BOM |
|  |  |  | 61100Y400-011-G | RES,169Ohm,+/-0.1%,1/16W,SMD0402,G | YAGEO CORPORATION COMPONENT | RT0402BRD07169RL | G | PWA BOM | In Old BOM |
|  |  |  | RB04BTP1690B | RES,169Ohm,+/-0.1%,1/16W,SMD0402,G | TA-I TECHNOLOGY CO., LTD. | RB04BTP1690B | G | PWA BOM | In Old BOM |
| 9 | R1092,R1093,R1114,R1115 | 4 | 61100QH00-017-G | RES,510 Ohm,+/-0.1%,1/16W,G,SMD0402 | KOA SPEER ELECTRONICS, INC. | RN731ETTP5100B25 | G | PWA BOM | In New BOM |
|  |  |  | 61100QH00-011-G | RES,510 Ohm,+/-0.1%,1/16W,G,SMD0402 | YAGEO CORPORATION COMPONENT | RT0402BRD07510RL | G | PWA BOM | In New BOM |
|  |  |  | 61100QH00-044-G | RES,510 Ohm,+/-0.1%,1/16W,G,SMD0402 | TA-I TECHNOLOGY CO., LTD. | RB04BTP5100 | G | PWA BOM | In New BOM |
|  | R1092,R1093,R1114,R1115 | 4 | 61100QH00-017-G | RES,510 Ohm,+/-0.1%,1/16W,G,SMD0402 | KOA SPEER ELECTRONICS, INC. | RN731ETTP5100B25 | G | PWA BOM | In Old BOM |
|  |  |  | 61100QH00-011-G | RES,510 Ohm,+/-0.1%,1/16W,G,SMD0402 | YAGEO CORPORATION COMPONENT | RT0402BRD07510RL | G | PWA BOM | In Old BOM |
| 10 | U24 | 1 | 41050DL00-233-G | Flash,MX25L6445EMI-10G,2.7~3.6V,64M,SPI,G,SOP-16,SMD | MACRONIX INTERNATIONAL CO.,LTD. | MX25L6445EMI-10G | G | PWA BOM | In New BOM |
|  |  |  | 41050DW00-396-G | Flash,S25FL064P0XMFI001,2.7~3.6V,64M,SPI,G,SO-16,SMD | SPANSION INTERNATIONAL LLC | S25FL064P0XMFI001 | G | PWA BOM | In New BOM |
|  |  |  | W25Q64JVSFIM | Flash,2.7~3.6V,64M,SPI,G,SOP-16,SMD | WINBOND | W25Q64JVSFIM |  | PWA BOM | In New BOM |
|  |  |  | 41050SF00-233-G | Flash,MX25L6435EMI-10G,2.7~3.6V,64M,SPI,G,SOP-16,SMD | MACRONIX INTERNATIONAL CO.,LTD. | MX25L6435EMI-10G | G | PWA BOM | In New BOM |
|  | U24 | 1 | 41050DL00-233-G | Flash,MX25L6445EMI-10G,2.7~3.6V,64M,SPI,G,SOP-16,SMD | MACRONIX INTERNATIONAL CO.,LTD. | MX25L6445EMI-10G | G | PWA BOM | In Old BOM |
|  |  |  | 41050DW00-396-G | Flash,S25FL064P0XMFI001,2.7~3.6V,64M,SPI,G,SO-16,SMD | SPANSION INTERNATIONAL LLC | S25FL064P0XMFI001 | G | PWA BOM | In Old BOM |
|  |  |  | W25Q64JVSFIQ | Flash,2.7~3.6V,64M,SPI,G,SOP-16,SMD | WINBOND | W25Q64JVSFIQ |  | PWA BOM | In Old BOM |
|  |  |  | 41050SF00-233-G | Flash,MX25L6435EMI-10G,2.7~3.6V,64M,SPI,G,SOP-16,SMD | MACRONIX INTERNATIONAL CO.,LTD. | MX25L6435EMI-10G | G | PWA BOM | In Old BOM |
| 11 | X3 | 1 | 710113800-100-G | XTAL,24MHz,+/-30ppm,20pF,G,SMD | TXC CORPORATION | 7B24000038 | G | PWA BOM | In New BOM |
|  |  |  | CX5032SB24000R0KZQ01 | XTAL,24MHz,+/-30ppm,20pF,G,SMD | Kyocera | CX5032SB24000R0KZQ01 | G | PWA BOM | In New BOM |
|  | X3 | 1 | 710113800-100-G | XTAL,24MHz,+/-30ppm,20pF,G,SMD | TXC CORPORATION | 7B24000038 | G | PWA BOM | In Old BOM |
| 12 | X6 | 1 | 710106900-162-G | XTAL,32.768KHz,+/-20ppm,12.5pF,G,SMD | EPSON ELECTRONICS AMERICA,INC. | Q13FC1350000400 | G | PWA BOM | In New BOM |
|  |  |  | ST3215SB32768H5HPWAA | XTAL,32.768KHz,+/-20ppm,12.5pF,G,SMD | Kyocera | ST3215SB32768H5HPWAA |  | PWA BOM | In New BOM |
|  |  |  | 06172-W-052-3 | XTAL,32.768KHz,+/-20ppm,12.5pF,G,SMD | TAITIEN | 06172-W-052-3 |  | PWA BOM | In New BOM |
|  | X6 | 1 | 710106900-162-G | XTAL,32.768KHz,+/-20ppm,12.5pF,G,SMD | EPSON ELECTRONICS AMERICA,INC. | Q13FC1350000400 | G | PWA BOM | In Old BOM |
| 13 | Y2 | 1 | 71020Q600-16G-G | OSC,50MHz,50ppm,3.3V,G,SMD | SiTime Corporation | SIT1602AC-23-33E-50.000000T | G | PWA BOM | In New BOM |
|  |  |  | 71012DA00-100-G | OSC,50MHz,+/-25ppm,15pF,G,SMD | TXC CORPORATION | 7X50000015 |  | PWA BOM | In New BOM |
|  |  |  | SSW050000I3CHE-ST7R2 | OSC,50MHz,50ppm,3.3V,G,SMD | HARMONY (HELE) | SSW050000I3CHE-ST7R2 |  | PWA BOM | In New BOM |
|  |  |  | KC3225K50.0000C1GE00 | OSC,50MHz,50ppm,3.3V,G,SMD | Kyocera | KC3225K50.0000C1GE00 |  | PWA BOM | In New BOM |
|  | Y2 | 1 | 71020Q600-16G-G | OSC,50MHz,50ppm,3.3V,G,SMD | SiTime Corporation | SIT1602AC-23-33E-50.000000T | G | PWA BOM | In Old BOM |
| 14 | Y4 | 1 | 71020KL00-100-G | OSC,33MHz,+/-50ppm,3.3V,15pF,G,SMD | TXC CORPORATION | 7X33000013 | G | PWA BOM | In New BOM |
|  |  |  | 710211800-967-G | OSC,33MHz,+/-50ppm,3.3V,15pF,G,SMD | eCERA | FK3300011 | G | PWA BOM | In New BOM |
|  |  |  | KC3225K33.0000C10E00 | OSC,33MHz,+/-50ppm,3.3V,15pF,G,SMD | Kyocera | KC3225K33.0000C10E00 | G | PWA BOM | In New BOM |
|  | Y4 | 1 | 71020KL00-100-G | OSC,33MHz,+/-50ppm,3.3V,15pF,G,SMD | TXC CORPORATION | 7X33000013 | G | PWA BOM | In Old BOM |
| 15 | J11 | 1 | 3406AEU00-245-G | CONN,Header,Shrouded,2X4,R/A,Bla,2.54mm,G/F,G,DIP-8 | AMPHENOL SHANGHAI CORP. | G821EU208AGN00Y | G | PWA BOM | In New BOM |
|  |  |  | 3406AYC00-GRT-G | Header&Socket Connector,511-90-08GB00,Shrouded Header,8,DIP,NY9T,2.54mm,3u",Black,G | PINREX TECHNOLOGY CORP. | 511-90-08GB00 | G | PWA BOM | In New BOM |
|  |  |  | 3406AYD00-971-G | Header&Socket Connector,C18359-10839-Y,Shrouded Header,8,DIP,LCP,2.54mm,999.9999u",Black,G | ALLTOP TECHNOLOGY CO.,LTD | C18359-10839-Y | G | PWA BOM | In New BOM |
|  |  |  | 3406AYE00-637-G | Header&Socket Connector,3112110800-0231,Shrouded Header,8,DIP,NY6T,2.54mm,3u",Black,G | LONG SHOUNG CO.,LTD. | 3112110800-0231 | G | PWA BOM | In New BOM |
|  | J11 | 1 | 3406AEU00-245-G | CONN,Header,Shrouded,2X4,R/A,Bla,2.54mm,G/F,G,DIP-8 | AMPHENOL SHANGHAI CORP. | G821EU208AGN00Y | G | PWA BOM | In Old BOM |
| 16 | J19,J20,J21,J22 | 4 | 340604M00-600-G | CONN,Header,Friction,1X3,V/T,Ivo,2.54mm,G,DIP-3 | FOXCONN TECHNOLOGY CO.,LTD. | HF2803E-P1 | G | PWA BOM | In New BOM |
|  |  |  | 744-81-03GW10 | CONN,Header,Friction,1X3,V/T,2.54mm,G,DIP-3 | PINREX TECHNOLOGY CORP. | 744-81-03GW10 | G | PWA BOM | In New BOM |
|  |  |  | 2111110300-0212 | CONN,Header,Friction,1X3,V/T,2.54mm,G,DIP-3 | LONG SHOUNG CO.,LTD. | 2111110300-0212 | G | PWA BOM | In New BOM |
|  |  |  | 22-23-2031 | CONN,Header,Friction,1X3,V/T,2.54mm,G,DIP-3 | MOLEX INCORPORATED | 22-23-2031 | G | PWA BOM | In New BOM |
|  | J19,J20,J21,J22 | 4 | 340604M00-600-G | CONN,Header,Friction,1X3,V/T,Ivo,2.54mm,G,DIP-3 | FOXCONN TECHNOLOGY CO.,LTD. | HF2803E-P1 | G | PWA BOM | In Old BOM |
| 17 | J23,J24,J25,J26 | 4 | 3406A2B00-317-G | CONN,Header,WTB,1X4,V/T,Bla,2.54mm,15u,G,DIP-4 | MOLEX INCORPORATED | 171856-1104 | G | PWA BOM | In New BOM |
|  |  |  | 640456-4 | CONN,Header,WTB,1X4,V/T,Bla,2.54mm,15u,G,DIP-4 | TYCO ELECTRONICS CORPORATION | 640456-4 | G | PWA BOM | In New BOM |
|  |  |  | 3406AYG00-637-G | Header&Socket Connector,2111100400-0141,Wire-to-Board Header,4,DIP,NY66,2.54mm,15u",Black,G | LONG SHOUNG CO.,LTD. | 2111100400-0141 | G | PWA BOM | In New BOM |
|  | J23,J24,J25,J26 | 4 | 3406A2B00-317-G | CONN,Header,WTB,1X4,V/T,Bla,2.54mm,15u,G,DIP-4 | MOLEX INCORPORATED | 171856-1104 | G | PWA BOM | In Old BOM |
| ##### Change Revision |  |  |  |  |  |  |  |  |  |
| Sheet | REV OF BOM | CUSTOMER | CUSTOMER P/N | PWA PN | PWA DESCRIPTION | PWA REV | DATE | Remark |  |
| OOOOOOOOOOOOOOOOOOOOOOOOOOOOOOOOOOOOOOOOOOOOOOOOOOOOOOOOOOOOOOOOOOOOOOOOOOOOOOOOOOOOOOOOOO | OOOOOOOOOOOOOOOOOOOOOOOOOOOOOOOOOOOOOOOOOOOOOOOOOOOOOOOOOOOOOOOOOOOOOOOOOOOOOOOOOOOOOOOOOO | OOOOOOOOOOOOOOOOOOOOOOOOOOOOOOOOOOOOOOOOOOOOOOOOOOOOOOOOOOOOOOOOOOOOOOOOOOOOOOOOOOOOOOOOOO | OOOOOOOOOOOOOOOOOOOOOOOOOOOOOOOOOOOOOOOOOOOOOOOOOOOOOOOOOOOOOOOOOOOOOOOOOOOOOOOOOOOOOOOOOO | OOOOOOOOOOOOOOOOOOOOOOOOOOOOOOOOOOOOOOOOOOOOOOOOOOOOOOOOOOOOOOOOOOOOOOOOOOOOOOOOOOOOOOOOOO | OOOOOOOOOOOOOOOOOOOOOOOOOOOOOOOOOOOOOOOOOOOOOOOOOOOOOOOOOOOOOOOOOOOOOOOOOOOOOOOOOOOOOOOOOO | OOOOOOOOOOOOOOOOOOOOOOOOOOOOOOOOOOOOOOOOOOOOOOOOOOOOOOOOOOOOOOOOOOOOOOOOOOOOOOOOOOOOOOOOOO | OOOOOOOOOOOOOOOOOOOOOOOOOOOOOOOOOOOOOOOOOOOOOOOOOOOOOOOOOOOOOOOOOOOOOOOOOOOOOOOOOOOOOOOOOO | OOOOOOOOOOOOOOOOOOOOOOOOOOOOOOOOOOOOOOOOOOOOOOOOOOOOOOOOOOOOOOOOOOOOOOOOOOOOOOOOOOOOOOOOOO | OOOOOOOOOOOOOOOOOOOOOOOOOOOOOOOOOOOOOOOOOOOOOOOOOOOOOOOOOOOOOOOOOOOOOOOOOOOOOOOOOOOOOOOOOO |
| Second Source Change |  |  |  |  |  |  |  |  |  |
| Item | Location | Change Type | Foxconn P/N | Part Description | Manufacturer Full Name | Manufacturer P/N | RoHS | Sheet |  |
| 1 | PSTC4,PSLC4,PSFC4,PSEC4,PSDC4,PQPC4,PFRC4,PEEC4,PEDC4,PSPC3003,PIPC3003,PFPC3003,PEPC3003,PSRC3010 |  | 62012T300-015-G | CAP,1uF,+/-10%,X7S,25V,G,SMD0402 | MURATA ELEC. NORTH AMERICA | GRM155C71E105KE11D | G | PWA BOM |  |
|  |  | ADD | 620138700-026-G | CAP,1uF,+/-10%,X6S,25V,G,SMD0402 | SAMSUNG | CL05X105KA5NQNC | G | PWA BOM |  |
|  |  | ADD | GRM155C81E105KE11D | CAP,1uF,+/-10%,X6S,25V,G,SMD0402 | MURATA | GRM155C81E105KE11D | G | PWA BOM |  |
| 2 | PSPR10,PIPR10,PFPR10,PEPR10 |  | 61100QQ00-017-G | RES,9.76KOhm,+/-0.1%,1/16W,G,SMD0402 | KOA SPEER ELECTRONICS, INC. | RN731ETTP9761B25 | G | PWA BOM |  |
|  |  | NO | 61100QQ00-024-G | RES,9.76KOhm,+/-0.1%,1/16W,G,SMD0402 | PANASONIC INDUSTRIAL CO.,LTD. | ERA2AEB9761X | G | PWA BOM |  |
|  |  | ADD | 61100QQ00-029-G | RES,9.76KOhm,+/-0.1%,1/16W,G,SMD0402 | VISHAY ENTER TECHNO LOGY.INC | TNPW04029K76BEED | G | PWA BOM |  |
| 3 | PERC7 |  | 62013BN00-015-G | CAP,4.3nF,+/-10%,X7R,50V,G,SMD0402 | MURATA ELEC. NORTH AMERICA | GRM155R71H432KA01D | G | PWA BOM |  |
|  |  | ADD | 62010LJ00-023-G | CAP,4.7nF,+/-10%,X7R,50V,G,SMD0402 | TAIYO ELECTRIC IND.CO.LTD | UMK105B7472KV-F | G | PWA BOM |  |
| 4 | PFRR19 |  | 61100YB00-017-G | RES,2.94KOhm,+/-0.1%,1/16W,G,SMD0402 | KOA SPEER ELECTRONICS, INC. | RN731ETTP2941B25 | G | PWA BOM |  |
|  |  | NO | 61100YB00-011-G | RES,2.94KOhm,+/-0.1%,1/16W,SMD0402,G | YAGEO CORPORATION COMPONENT | RT0402BRD072K94L | G | PWA BOM |  |
|  |  | ADD | RB04BTP2941 | RES,2.94KOhm,+/-0.1%,1/16W,SMD0402,G | TA-I TECHNOLOGY CO., LTD. | RB04BTP2941 | G | PWA BOM |  |
|  |  | Delete | RB04BTP2941B | RES,2.94KOhm,+/-0.1%,1/16W,SMD0402,G | TA-I TECHNOLOGY CO., LTD. | RB04BTP2941B | G | PWA BOM |  |
| 5 | PHAR2 |  | 61100DA00-017-G | RES,33KOhm,+/-0.1%,1/16W,G,SMD0402 | KOA SPEER ELECTRONICS, INC. | RN731ETTP3302B25 | G | PWA BOM |  |
|  |  | NO | 61100DA00-011-G | RES,33KOhm,+/-0.1%,1/16W,G,SMD0402 | YAGEO CORPORATION COMPONENT | RT0402BRD0733KL | G | PWA BOM |  |
|  |  | ADD | TNPW040233K0BEED | RES,33KOhm,+/-0.1%,1/16W,G,SMD0402 | VISHAY | TNPW040233K0BEED | G | PWA BOM |  |
| 6 | PHAR5 |  | 61100QM00-017-G | RES,100KOhm,+/-0.1%,1/10W,G,SMD0603 | KOA SPEER ELECTRONICS, INC. | RN73H1JTTD1003B25 | G | PWA BOM |  |
|  |  | NO | 61100QM00-011-G | RES,100KOhm,+/-0.1%,1/10W,G,SMD0603 | YAGEO CORPORATION COMPONENT | RT0603BRD07100KL | G | PWA BOM |  |
|  |  | ADD | TNPW0402100KBEED | RES,100KOhm,+/-0.1%,1/10W,G,SMD0603 | VISHAY | TNPW0402100KBEED | G | PWA BOM |  |
| 7 | PHAR7 |  | 610107P00-017-G | RES,4.12KOhm,+/-1%,1/10W,G,SMD0603 | KOA SPEER ELECTRONICS, INC. | RK73H1JTTD4121F | G | PWA BOM |  |
|  |  | NO | 610107P00-011-G | RES,4.12KOhm,+/-1%,1/10W,G,SMD0603 | YAGEO CORPORATION COMPONENT | RC0603FR-074K12L | G | PWA BOM |  |
|  |  | ADD | 610107P00-044-G | RES,4.12KOhm,+/-1%,1/10W,G,SMD0603 | TA-I TECHNOLOGY CO., LTD. | RM06FTN4121 | G | PWA BOM |  |
| 8 | R11,R12,R13,R373,R374,R375 |  | 61100Y400-017-G | RES,169 Ohm,+/-0.1%,1/16W,G,SMD0402 | KOA SPEER ELECTRONICS, INC. | RN731ETTP1690B25 | G | PWA BOM |  |
|  |  | NO | 61100Y400-011-G | RES,169Ohm,+/-0.1%,1/16W,SMD0402,G | YAGEO CORPORATION COMPONENT | RT0402BRD07169RL | G | PWA BOM |  |
|  |  | ADD | RB04BTP1690 | RES,169Ohm,+/-0.1%,1/16W,SMD0402,G | TA-I TECHNOLOGY CO., LTD. | RB04BTP1690 | G | PWA BOM |  |
|  |  | Delete | RB04BTP1690B | RES,169Ohm,+/-0.1%,1/16W,SMD0402,G | TA-I TECHNOLOGY CO., LTD. | RB04BTP1690B | G | PWA BOM |  |
| 9 | R1092,R1093,R1114,R1115 |  | 61100QH00-017-G | RES,510 Ohm,+/-0.1%,1/16W,G,SMD0402 | KOA SPEER ELECTRONICS, INC. | RN731ETTP5100B25 | G | PWA BOM |  |
|  |  | NO | 61100QH00-011-G | RES,510 Ohm,+/-0.1%,1/16W,G,SMD0402 | YAGEO CORPORATION COMPONENT | RT0402BRD07510RL | G | PWA BOM |  |
|  |  | ADD | 61100QH00-044-G | RES,510 Ohm,+/-0.1%,1/16W,G,SMD0402 | TA-I TECHNOLOGY CO., LTD. | RB04BTP5100 | G | PWA BOM |  |
| 10 | U24 |  | 41050DL00-233-G | Flash,MX25L6445EMI-10G,2.7~3.6V,64M,SPI,G,SOP-16,SMD | MACRONIX INTERNATIONAL CO.,LTD. | MX25L6445EMI-10G | G | PWA BOM |  |
|  |  | NO | 41050DW00-396-G | Flash,S25FL064P0XMFI001,2.7~3.6V,64M,SPI,G,SO-16,SMD | SPANSION INTERNATIONAL LLC | S25FL064P0XMFI001 | G | PWA BOM |  |
|  |  | ADD | W25Q64JVSFIM | Flash,2.7~3.6V,64M,SPI,G,SOP-16,SMD | WINBOND | W25Q64JVSFIM |  | PWA BOM |  |
|  |  | NO | 41050SF00-233-G | Flash,MX25L6435EMI-10G,2.7~3.6V,64M,SPI,G,SOP-16,SMD | MACRONIX INTERNATIONAL CO.,LTD. | MX25L6435EMI-10G | G | PWA BOM |  |
|  |  | Delete | W25Q64JVSFIQ | Flash,2.7~3.6V,64M,SPI,G,SOP-16,SMD | WINBOND | W25Q64JVSFIQ |  | PWA BOM |  |
| 11 | X3 |  | 710113800-100-G | XTAL,24MHz,+/-30ppm,20pF,G,SMD | TXC CORPORATION | 7B24000038 | G | PWA BOM |  |
|  |  | ADD | CX5032SB24000R0KZQ01 | XTAL,24MHz,+/-30ppm,20pF,G,SMD | Kyocera | CX5032SB24000R0KZQ01 | G | PWA BOM |  |
| 12 | X6 |  | 710106900-162-G | XTAL,32.768KHz,+/-20ppm,12.5pF,G,SMD | EPSON ELECTRONICS AMERICA,INC. | Q13FC1350000400 | G | PWA BOM |  |
|  |  | ADD | ST3215SB32768H5HPWAA | XTAL,32.768KHz,+/-20ppm,12.5pF,G,SMD | Kyocera | ST3215SB32768H5HPWAA |  | PWA BOM |  |
|  |  | ADD | 06172-W-052-3 | XTAL,32.768KHz,+/-20ppm,12.5pF,G,SMD | TAITIEN | 06172-W-052-3 |  | PWA BOM |  |
| 13 | Y2 |  | 71020Q600-16G-G | OSC,50MHz,50ppm,3.3V,G,SMD | SiTime Corporation | SIT1602AC-23-33E-50.000000T | G | PWA BOM |  |
|  |  | ADD | 71012DA00-100-G | OSC,50MHz,+/-25ppm,15pF,G,SMD | TXC CORPORATION | 7X50000015 |  | PWA BOM |  |
|  |  | ADD | SSW050000I3CHE-ST7R2 | OSC,50MHz,50ppm,3.3V,G,SMD | HARMONY (HELE) | SSW050000I3CHE-ST7R2 |  | PWA BOM |  |
|  |  | ADD | KC3225K50.0000C1GE00 | OSC,50MHz,50ppm,3.3V,G,SMD | Kyocera | KC3225K50.0000C1GE00 |  | PWA BOM |  |
| 14 | Y4 |  | 71020KL00-100-G | OSC,33MHz,+/-50ppm,3.3V,15pF,G,SMD | TXC CORPORATION | 7X33000013 | G | PWA BOM |  |
|  |  | ADD | 710211800-967-G | OSC,33MHz,+/-50ppm,3.3V,15pF,G,SMD | eCERA | FK3300011 | G | PWA BOM |  |
|  |  | ADD | KC3225K33.0000C10E00 | OSC,33MHz,+/-50ppm,3.3V,15pF,G,SMD | Kyocera | KC3225K33.0000C10E00 | G | PWA BOM |  |
| 15 | J11 |  | 3406AEU00-245-G | CONN,Header,Shrouded,2X4,R/A,Bla,2.54mm,G/F,G,DIP-8 | AMPHENOL SHANGHAI CORP. | G821EU208AGN00Y | G | PWA BOM |  |
|  |  | ADD | 3406AYC00-GRT-G | Header&Socket Connector,511-90-08GB00,Shrouded Header,8,DIP,NY9T,2.54mm,3u",Black,G | PINREX TECHNOLOGY CORP. | 511-90-08GB00 | G | PWA BOM |  |
|  |  | ADD | 3406AYD00-971-G | Header&Socket Connector,C18359-10839-Y,Shrouded Header,8,DIP,LCP,2.54mm,999.9999u",Black,G | ALLTOP TECHNOLOGY CO.,LTD | C18359-10839-Y | G | PWA BOM |  |
|  |  | ADD | 3406AYE00-637-G | Header&Socket Connector,3112110800-0231,Shrouded Header,8,DIP,NY6T,2.54mm,3u",Black,G | LONG SHOUNG CO.,LTD. | 3112110800-0231 | G | PWA BOM |  |
| 16 | J19,J20,J21,J22 |  | 340604M00-600-G | CONN,Header,Friction,1X3,V/T,Ivo,2.54mm,G,DIP-3 | FOXCONN TECHNOLOGY CO.,LTD. | HF2803E-P1 | G | PWA BOM |  |
|  |  | ADD | 744-81-03GW10 | CONN,Header,Friction,1X3,V/T,2.54mm,G,DIP-3 | PINREX TECHNOLOGY CORP. | 744-81-03GW10 | G | PWA BOM |  |
|  |  | ADD | 2111110300-0212 | CONN,Header,Friction,1X3,V/T,2.54mm,G,DIP-3 | LONG SHOUNG CO.,LTD. | 2111110300-0212 | G | PWA BOM |  |
|  |  | ADD | 22-23-2031 | CONN,Header,Friction,1X3,V/T,2.54mm,G,DIP-3 | MOLEX INCORPORATED | 22-23-2031 | G | PWA BOM |  |
| 17 | J23,J24,J25,J26 |  | 3406A2B00-317-G | CONN,Header,WTB,1X4,V/T,Bla,2.54mm,15u,G,DIP-4 | MOLEX INCORPORATED | 171856-1104 | G | PWA BOM |  |
|  |  | ADD | 640456-4 | CONN,Header,WTB,1X4,V/T,Bla,2.54mm,15u,G,DIP-4 | TYCO ELECTRONICS CORPORATION | 640456-4 | G | PWA BOM |  |
|  |  | ADD | 3406AYG00-637-G | Header&Socket Connector,2111100400-0141,Wire-to-Board Header,4,DIP,NY66,2.54mm,15u",Black,G | LONG SHOUNG CO.,LTD. | 2111100400-0141 | G | PWA BOM |  |
| OOOOOOOOOOOOOOOOOOOOOOOOOOOOOOOOOOOOOOOOOOOOOOOOOOOOOOOOOOOOOOOOOOOOOOOOOOOOOOOOOOOOOOOOOO | OOOOOOOOOOOOOOOOOOOOOOOOOOOOOOOOOOOOOOOOOOOOOOOOOOOOOOOOOOOOOOOOOOOOOOOOOOOOOOOOOOOOOOOOOO | OOOOOOOOOOOOOOOOOOOOOOOOOOOOOOOOOOOOOOOOOOOOOOOOOOOOOOOOOOOOOOOOOOOOOOOOOOOOOOOOOOOOOOOOOO | OOOOOOOOOOOOOOOOOOOOOOOOOOOOOOOOOOOOOOOOOOOOOOOOOOOOOOOOOOOOOOOOOOOOOOOOOOOOOOOOOOOOOOOOOO | OOOOOOOOOOOOOOOOOOOOOOOOOOOOOOOOOOOOOOOOOOOOOOOOOOOOOOOOOOOOOOOOOOOOOOOOOOOOOOOOOOOOOOOOOO | OOOOOOOOOOOOOOOOOOOOOOOOOOOOOOOOOOOOOOOOOOOOOOOOOOOOOOOOOOOOOOOOOOOOOOOOOOOOOOOOOOOOOOOOOO | OOOOOOOOOOOOOOOOOOOOOOOOOOOOOOOOOOOOOOOOOOOOOOOOOOOOOOOOOOOOOOOOOOOOOOOOOOOOOOOOOOOOOOOOOO | OOOOOOOOOOOOOOOOOOOOOOOOOOOOOOOOOOOOOOOOOOOOOOOOOOOOOOOOOOOOOOOOOOOOOOOOOOOOOOOOOOOOOOOOOO | OOOOOOOOOOOOOOOOOOOOOOOOOOOOOOOOOOOOOOOOOOOOOOOOOOOOOOOOOOOOOOOOOOOOOOOOOOOOOOOOOOOOOOOOOO | OOOOOOOOOOOOOOOOOOOOOOOOOOOOOOOOOOOOOOOOOOOOOOOOOOOOOOOOOOOOOOOOOOOOOOOOOOOOOOOOOOOOOOOOOO |
| Master Materials Change |  |  |  |  |  |  |  |  |  |
| Item | Foxconn P/N | Orig._Usage | New_Usage | Part Description | Manufacturer Full Name | Manufacturer P/N | RoHS | Location | Sheet |
| OOOOOOOOOOOOOOOOOOOOOOOOOOOOOOOOOOOOOOOOOOOOOOOOOOOOOOOOOOOOOOOOOOOOOOOOOOOOOOOOOOOOOOOOOO | OOOOOOOOOOOOOOOOOOOOOOOOOOOOOOOOOOOOOOOOOOOOOOOOOOOOOOOOOOOOOOOOOOOOOOOOOOOOOOOOOOOOOOOOOO | OOOOOOOOOOOOOOOOOOOOOOOOOOOOOOOOOOOOOOOOOOOOOOOOOOOOOOOOOOOOOOOOOOOOOOOOOOOOOOOOOOOOOOOOOO | OOOOOOOOOOOOOOOOOOOOOOOOOOOOOOOOOOOOOOOOOOOOOOOOOOOOOOOOOOOOOOOOOOOOOOOOOOOOOOOOOOOOOOOOOO | OOOOOOOOOOOOOOOOOOOOOOOOOOOOOOOOOOOOOOOOOOOOOOOOOOOOOOOOOOOOOOOOOOOOOOOOOOOOOOOOOOOOOOOOOO | OOOOOOOOOOOOOOOOOOOOOOOOOOOOOOOOOOOOOOOOOOOOOOOOOOOOOOOOOOOOOOOOOOOOOOOOOOOOOOOOOOOOOOOOOO | OOOOOOOOOOOOOOOOOOOOOOOOOOOOOOOOOOOOOOOOOOOOOOOOOOOOOOOOOOOOOOOOOOOOOOOOOOOOOOOOOOOOOOOOOO | OOOOOOOOOOOOOOOOOOOOOOOOOOOOOOOOOOOOOOOOOOOOOOOOOOOOOOOOOOOOOOOOOOOOOOOOOOOOOOOOOOOOOOOOOO | OOOOOOOOOOOOOOOOOOOOOOOOOOOOOOOOOOOOOOOOOOOOOOOOOOOOOOOOOOOOOOOOOOOOOOOOOOOOOOOOOOOOOOOOOO | OOOOOOOOOOOOOOOOOOOOOOOOOOOOOOOOOOOOOOOOOOOOOOOOOOOOOOOOOOOOOOOOOOOOOOOOOOOOOOOOOOOOOOOOOO |
| TLA Parts Change |  |  |  |  |  |  |  |  |  |
| Item | Foxconn P/N | Qty | Part Description | Manufacturer Full Name | Manufacturer P/N | RoHS | Location | Remark | BOM |
| BOM Change List Date:Fri Jun 09 11:19:50 GMT+08:00 2017 |  |  |  |  |  |  |  |  |  |
| New BOM file : C:\<user>\zaius 0606——11：00.xls |  |  |  |  |  |  |  |  |  |
| Old BOM file : C:\<user>\zaius 0606——10：00.xls |  |  |  |  |  |  |  |  |  |
| ##### Add Parts |  |  |  |  |  |  |  |  |  |
| Item | Location | Qty | Foxconn P/N | Part Description | Manufacturer Full Name | Manufacturer P/N | RoHS | Sheet |  |
| ##### Remove Parts |  |  |  |  |  |  |  |  |  |
| Item | Location | Qty | Foxconn P/N | Part Description | Manufacturer Full Name | Manufacturer P/N | RoHS | Sheet |  |
| ##### Change Parts |  |  |  |  |  |  |  |  |  |
| Item | Location | Qty | Foxconn P/N | Part Description | Manufacturer Full Name | Manufacturer P/N | RoHS | Sheet | Remark |
| 1 | U29 | 1 | 21050F900-217-G | IC,IDT,2305B-1DCG8,B,G,SOIC-8,SMD | INTEGRATED DEVICE TECHNOLOGY | 2305B-1DCG8 | G | PWA BOM | In New BOM |
|  |  |  | 31050JC00-223-G | Logic IC,Buffer,NB2305AI1DR2G,3.0V~3.6V,0.35ns,SOIC,8P,G | ON SEMICONDUCTOR CORP | NB2305AI1DR2G | G | PWA BOM | In New BOM |
|  | U29 | 1 | 21050F900-217-G | IC,IDT,2305B-1DCG8,B,G,SOIC-8,SMD | INTEGRATED DEVICE TECHNOLOGY | 2305B-1DCG8 | G | PWA BOM | In Old BOM |
|  |  |  | 31050JC00-223-G | Logic IC,Buffer,NB2305AI1DR2G,3.0V~3.6V,0.35ns,SOIC,8P,G | ON SEMICONDUCTOR CORP | NB2305AI1DR2G | G | PWA BOM | In Old BOM |
|  |  |  | SL2305SC-1 | IC,SL2305SC-1,G,SOIC-8,SMD | Silicon Laboratories Inc. | SL2305SC-1 | G | PWA BOM | In Old BOM |
| 2 | J11 | 1 | 3406AEU00-245-G | CONN,Header,Shrouded,2X4,R/A,Bla,2.54mm,G/F,G,DIP-8 | AMPHENOL SHANGHAI CORP. | G821EU208AGN00Y | G | PWA BOM | In New BOM |
|  |  |  | 3406AYC00-GRT-G | Header&Socket Connector,511-90-08GB00,Shrouded Header,8,DIP,NY9T,2.54mm,3u",Black,G | PINREX TECHNOLOGY CORP. | 511-90-08GB00 | G | PWA BOM | In New BOM |
|  |  |  | 3406AYE00-637-G | Header&Socket Connector,3112110800-0231,Shrouded Header,8,DIP,NY6T,2.54mm,3u",Black,G | LONG SHOUNG CO.,LTD. | 3112110800-0231 | G | PWA BOM | In New BOM |
|  | J11 | 1 | 3406AEU00-245-G | CONN,Header,Shrouded,2X4,R/A,Bla,2.54mm,G/F,G,DIP-8 | AMPHENOL SHANGHAI CORP. | G821EU208AGN00Y | G | PWA BOM | In Old BOM |
|  |  |  | 3406AYC00-GRT-G | Header&Socket Connector,511-90-08GB00,Shrouded Header,8,DIP,NY9T,2.54mm,3u",Black,G | PINREX TECHNOLOGY CORP. | 511-90-08GB00 | G | PWA BOM | In Old BOM |
|  |  |  | 3406AYD00-971-G | Header&Socket Connector,C18359-10839-Y,Shrouded Header,8,DIP,LCP,2.54mm,999.9999u",Black,G | ALLTOP TECHNOLOGY CO.,LTD | C18359-10839-Y | G | PWA BOM | In Old BOM |
|  |  |  | 3406AYE00-637-G | Header&Socket Connector,3112110800-0231,Shrouded Header,8,DIP,NY6T,2.54mm,3u",Black,G | LONG SHOUNG CO.,LTD. | 3112110800-0231 | G | PWA BOM | In Old BOM |
| ##### Change Revision |  |  |  |  |  |  |  |  |  |
| Sheet | REV OF BOM | CUSTOMER | CUSTOMER P/N | PWA PN | PWA DESCRIPTION | PWA REV | DATE | Remark |  |
| OOOOOOOOOOOOOOOOOOOOOOOOOOOOOOOOOOOOOOOOOOOOOOOOOOOOOOOOOOOOOOOOOOOOOOOOOOOOOOOOOOOOOOOOOO | OOOOOOOOOOOOOOOOOOOOOOOOOOOOOOOOOOOOOOOOOOOOOOOOOOOOOOOOOOOOOOOOOOOOOOOOOOOOOOOOOOOOOOOOOO | OOOOOOOOOOOOOOOOOOOOOOOOOOOOOOOOOOOOOOOOOOOOOOOOOOOOOOOOOOOOOOOOOOOOOOOOOOOOOOOOOOOOOOOOOO | OOOOOOOOOOOOOOOOOOOOOOOOOOOOOOOOOOOOOOOOOOOOOOOOOOOOOOOOOOOOOOOOOOOOOOOOOOOOOOOOOOOOOOOOOO | OOOOOOOOOOOOOOOOOOOOOOOOOOOOOOOOOOOOOOOOOOOOOOOOOOOOOOOOOOOOOOOOOOOOOOOOOOOOOOOOOOOOOOOOOO | OOOOOOOOOOOOOOOOOOOOOOOOOOOOOOOOOOOOOOOOOOOOOOOOOOOOOOOOOOOOOOOOOOOOOOOOOOOOOOOOOOOOOOOOOO | OOOOOOOOOOOOOOOOOOOOOOOOOOOOOOOOOOOOOOOOOOOOOOOOOOOOOOOOOOOOOOOOOOOOOOOOOOOOOOOOOOOOOOOOOO | OOOOOOOOOOOOOOOOOOOOOOOOOOOOOOOOOOOOOOOOOOOOOOOOOOOOOOOOOOOOOOOOOOOOOOOOOOOOOOOOOOOOOOOOOO | OOOOOOOOOOOOOOOOOOOOOOOOOOOOOOOOOOOOOOOOOOOOOOOOOOOOOOOOOOOOOOOOOOOOOOOOOOOOOOOOOOOOOOOOOO | OOOOOOOOOOOOOOOOOOOOOOOOOOOOOOOOOOOOOOOOOOOOOOOOOOOOOOOOOOOOOOOOOOOOOOOOOOOOOOOOOOOOOOOOOO |
| Second Source Change |  |  |  |  |  |  |  |  |  |
| Item | Location | Change Type | Foxconn P/N | Part Description | Manufacturer Full Name | Manufacturer P/N | RoHS | Sheet |  |
| 1 | U29 |  | 21050F900-217-G | IC,IDT,2305B-1DCG8,B,G,SOIC-8,SMD | INTEGRATED DEVICE TECHNOLOGY | 2305B-1DCG8 | G | PWA BOM |  |
|  |  | NO | 31050JC00-223-G | Logic IC,Buffer,NB2305AI1DR2G,3.0V~3.6V,0.35ns,SOIC,8P,G | ON SEMICONDUCTOR CORP | NB2305AI1DR2G | G | PWA BOM |  |
|  |  | Delete | SL2305SC-1 | IC,SL2305SC-1,G,SOIC-8,SMD | Silicon Laboratories Inc. | SL2305SC-1 | G | PWA BOM |  |
| 2 | J11 |  | 3406AEU00-245-G | CONN,Header,Shrouded,2X4,R/A,Bla,2.54mm,G/F,G,DIP-8 | AMPHENOL SHANGHAI CORP. | G821EU208AGN00Y | G | PWA BOM |  |
|  |  | NO | 3406AYC00-GRT-G | Header&Socket Connector,511-90-08GB00,Shrouded Header,8,DIP,NY9T,2.54mm,3u",Black,G | PINREX TECHNOLOGY CORP. | 511-90-08GB00 | G | PWA BOM |  |
|  |  | NO | 3406AYE00-637-G | Header&Socket Connector,3112110800-0231,Shrouded Header,8,DIP,NY6T,2.54mm,3u",Black,G | LONG SHOUNG CO.,LTD. | 3112110800-0231 | G | PWA BOM |  |
|  |  | Delete | 3406AYD00-971-G | Header&Socket Connector,C18359-10839-Y,Shrouded Header,8,DIP,LCP,2.54mm,999.9999u",Black,G | ALLTOP TECHNOLOGY CO.,LTD | C18359-10839-Y | G | PWA BOM |  |
| OOOOOOOOOOOOOOOOOOOOOOOOOOOOOOOOOOOOOOOOOOOOOOOOOOOOOOOOOOOOOOOOOOOOOOOOOOOOOOOOOOOOOOOOOO | OOOOOOOOOOOOOOOOOOOOOOOOOOOOOOOOOOOOOOOOOOOOOOOOOOOOOOOOOOOOOOOOOOOOOOOOOOOOOOOOOOOOOOOOOO | OOOOOOOOOOOOOOOOOOOOOOOOOOOOOOOOOOOOOOOOOOOOOOOOOOOOOOOOOOOOOOOOOOOOOOOOOOOOOOOOOOOOOOOOOO | OOOOOOOOOOOOOOOOOOOOOOOOOOOOOOOOOOOOOOOOOOOOOOOOOOOOOOOOOOOOOOOOOOOOOOOOOOOOOOOOOOOOOOOOOO | OOOOOOOOOOOOOOOOOOOOOOOOOOOOOOOOOOOOOOOOOOOOOOOOOOOOOOOOOOOOOOOOOOOOOOOOOOOOOOOOOOOOOOOOOO | OOOOOOOOOOOOOOOOOOOOOOOOOOOOOOOOOOOOOOOOOOOOOOOOOOOOOOOOOOOOOOOOOOOOOOOOOOOOOOOOOOOOOOOOOO | OOOOOOOOOOOOOOOOOOOOOOOOOOOOOOOOOOOOOOOOOOOOOOOOOOOOOOOOOOOOOOOOOOOOOOOOOOOOOOOOOOOOOOOOOO | OOOOOOOOOOOOOOOOOOOOOOOOOOOOOOOOOOOOOOOOOOOOOOOOOOOOOOOOOOOOOOOOOOOOOOOOOOOOOOOOOOOOOOOOOO | OOOOOOOOOOOOOOOOOOOOOOOOOOOOOOOOOOOOOOOOOOOOOOOOOOOOOOOOOOOOOOOOOOOOOOOOOOOOOOOOOOOOOOOOOO | OOOOOOOOOOOOOOOOOOOOOOOOOOOOOOOOOOOOOOOOOOOOOOOOOOOOOOOOOOOOOOOOOOOOOOOOOOOOOOOOOOOOOOOOOO |
| Master Materials Change |  |  |  |  |  |  |  |  |  |
| Item | Foxconn P/N | Orig._Usage | New_Usage | Part Description | Manufacturer Full Name | Manufacturer P/N | RoHS | Location | Sheet |
| OOOOOOOOOOOOOOOOOOOOOOOOOOOOOOOOOOOOOOOOOOOOOOOOOOOOOOOOOOOOOOOOOOOOOOOOOOOOOOOOOOOOOOOOOO | OOOOOOOOOOOOOOOOOOOOOOOOOOOOOOOOOOOOOOOOOOOOOOOOOOOOOOOOOOOOOOOOOOOOOOOOOOOOOOOOOOOOOOOOOO | OOOOOOOOOOOOOOOOOOOOOOOOOOOOOOOOOOOOOOOOOOOOOOOOOOOOOOOOOOOOOOOOOOOOOOOOOOOOOOOOOOOOOOOOOO | OOOOOOOOOOOOOOOOOOOOOOOOOOOOOOOOOOOOOOOOOOOOOOOOOOOOOOOOOOOOOOOOOOOOOOOOOOOOOOOOOOOOOOOOOO | OOOOOOOOOOOOOOOOOOOOOOOOOOOOOOOOOOOOOOOOOOOOOOOOOOOOOOOOOOOOOOOOOOOOOOOOOOOOOOOOOOOOOOOOOO | OOOOOOOOOOOOOOOOOOOOOOOOOOOOOOOOOOOOOOOOOOOOOOOOOOOOOOOOOOOOOOOOOOOOOOOOOOOOOOOOOOOOOOOOOO | OOOOOOOOOOOOOOOOOOOOOOOOOOOOOOOOOOOOOOOOOOOOOOOOOOOOOOOOOOOOOOOOOOOOOOOOOOOOOOOOOOOOOOOOOO | OOOOOOOOOOOOOOOOOOOOOOOOOOOOOOOOOOOOOOOOOOOOOOOOOOOOOOOOOOOOOOOOOOOOOOOOOOOOOOOOOOOOOOOOOO | OOOOOOOOOOOOOOOOOOOOOOOOOOOOOOOOOOOOOOOOOOOOOOOOOOOOOOOOOOOOOOOOOOOOOOOOOOOOOOOOOOOOOOOOOO | OOOOOOOOOOOOOOOOOOOOOOOOOOOOOOOOOOOOOOOOOOOOOOOOOOOOOOOOOOOOOOOOOOOOOOOOOOOOOOOOOOOOOOOOOO |
| TLA Parts Change |  |  |  |  |  |  |  |  |  |
| Item | Foxconn P/N | Qty | Part Description | Manufacturer Full Name | Manufacturer P/N | RoHS | Location | Remark | BOM |
| BOM Change List Date:Fri Jul 28 17:52:33 GMT+08:00 2017 |  |  |  |  |  |  |  |  |  |
| New BOM file : C:\<user>\ZAIUS-MB-PVT-X04-EBOM_20170728.xls |  |  |  |  |  |  |  |  |  |
| Old BOM file : C:\<user>\Zaius-MB-DVT-HW-EBOM-20170517.xls |  |  |  |  |  |  |  |  |  |
| ##### Add Parts |  |  |  |  |  |  |  |  |  |
| Item | Location | Qty | Foxconn P/N | Part Description | Manufacturer Full Name | Manufacturer P/N | RoHS | Sheet |  |
| 1 | PBMD4,PBFD4,PBED4,PAMD4,PAFD4,PAED4,PBAD5,PAAD5 | 8 | 52030DA00-237-G | DIODE,Schottky,BAT46W-7-F,100V,150mA,G,SOD123-2,SMD | DIODES INEORPORATION | BAT46W-7-F |  | PWA BOM |  |
| 2 | R1850 | 1 | 610107A00-017-G | RES,0 Ohm,+/-5%,1/16W,G,SMD0402 | KOA SPEER ELECTRONICS, INC. | RK73Z1ETTP | N | PWA BOM |  |
| ##### Remove Parts |  |  |  |  |  |  |  |  |  |
| Item | Location | Qty | Foxconn P/N | Part Description | Manufacturer Full Name | Manufacturer P/N | RoHS | Sheet |  |
| 1 | C2184,C2185 | 2 | 620108B00-015-G | CAP,120pF,+/-5%,NPO(C0G),50V,G,SMD0402 | MURATA ELEC. NORTH AMERICA | GRM1555C1H121J | N | PWA BOM |  |
| 2 | ED1 | 1 | 521800900-227-G | DIODE,Array-TVS,SRV05-4.TCT,5V,12A,G,SOT23-6,SMD | SEMTECH CORPORATION. | SRV05-4.TCT | N | PWA BOM |  |
| 3 | R1556 | 1 | 610107A00-017-G | RES,0 Ohm,+/-5%,1/16W,G,SMD0402 | KOA SPEER ELECTRONICS, INC. | RK73Z1ETTP | N | PWA BOM |  |
| 4 | R1838,R1839 | 2 | 610124C00-017-G | RES,57.6 Ohm,+/-1%,1/16W,G,SMD0402 | KOA SPEER ELECTRONICS, INC. | RK73H1ETTP57R6F | N | PWA BOM |  |
| 5 | J3 | 1 | 34068LN00-317-G | CONN,Header,Pin Header,1X3,V/T,2.54mm,30u,G,SMD-3 | MOLEX INCORPORATED | 87898-0315 |  | PWA BOM |  |
| 6 | PSUSW1 | 1 | 34080F500-653-G | CONN,Switch,slide,25mA,24V,G,SMD-8 | DIPTRONICS MANUFACTURING INC. | DHN-04F-T-V-T/R |  | PWA BOM |  |
| ##### Change Parts |  |  |  |  |  |  |  |  |  |
| Item | Location | Qty | Foxconn P/N | Part Description | Manufacturer Full Name | Manufacturer P/N | RoHS | Sheet | Remark |
| 1 | FS5,FS8,FS11,FS14,FS17,FS19,FS20,FS23,FS24,FS25,FS26 | 11 | 0438005.WRGT | Fuse,Fast acting,32V,5A,G,SMD0603 | LITTELFUSE FAR EAST PTE LTD | 0438005.WRGT | Y | PWA BOM | In New BOM |
|  | FS5,FS8,FS11,FS14,FS17,FS19,FS20,FS23,FS24,FS25,FS26 | 11 | 730103M00-086-G | Fuse,Fast acting,32V,5A,G,SMD0603 | LITTELFUSE FAR EAST PTE LTD | 0438005.WR | Y | PWA BOM | In Old BOM |
| 2 | PBMD1,PBFD1,PBED1,PBAD1,PAMD1,PAFD1,PAED1,PAAD1 | 8 | 52030DA00-237-G | DIODE,Schottky,BAT46W-7-F,100V,150mA,G,SOD123-2,SMD | DIODES INEORPORATION | BAT46W-7-F |  | PWA BOM | In New BOM |
|  | PBMD1,PBFD1,PBED1,PBAD1,PAMD1,PAFD1,PAED1,PAAD1 | 8 | 520103B00-185-G | Diode,Rectifier&Switching,MMBD1205,100V,200mA,G,SOT-23-3,SMD | FAIRCHILD SEMICONDUCTOR CORP | MMBD1205 | N | PWA BOM | In Old BOM |
| 3 | R1226,R1502 | 2 | 61011H500-017-G | RES,22 Ohm,+/-1%,1/16W,G,SMD0402 | KOA SPEER ELECTRONICS, INC. | RK73H1ETTP22R0F | N | PWA BOM | In New BOM |
|  | R1226,R1502 | 2 | 610107A00-017-G | RES,0 Ohm,+/-5%,1/16W,G,SMD0402 | KOA SPEER ELECTRONICS, INC. | RK73Z1ETTP | N | PWA BOM | In Old BOM |
| 4 | ED2,ED3 | 2 | SRV05-4ATCT | DIODE,Array-TVS,SRV05-4.TCT,5V,12A,G,SOT23-6,SMD | SEMTECH CORPORATION. | SRV05-4ATCT | N | PWA BOM | In New BOM |
|  | ED2,ED3 | 2 | 521800900-227-G | DIODE,Array-TVS,SRV05-4.TCT,5V,12A,G,SOT23-6,SMD | SEMTECH CORPORATION. | SRV05-4.TCT | N | PWA BOM | In Old BOM |
| ##### Change Revision |  |  |  |  |  |  |  |  |  |
| Sheet | REV OF BOM | CUSTOMER | CUSTOMER P/N | PWA PN | PWA DESCRIPTION | PWA REV | DATE | Remark |  |
| OOOOOOOOOOOOOOOOOOOOOOOOOOOOOOOOOOOOOOOOOOOOOOOOOOOOOOOOOOOOOOOOOOOOOOOOOOOOOOOOOOOOOOOOOO | OOOOOOOOOOOOOOOOOOOOOOOOOOOOOOOOOOOOOOOOOOOOOOOOOOOOOOOOOOOOOOOOOOOOOOOOOOOOOOOOOOOOOOOOOO | OOOOOOOOOOOOOOOOOOOOOOOOOOOOOOOOOOOOOOOOOOOOOOOOOOOOOOOOOOOOOOOOOOOOOOOOOOOOOOOOOOOOOOOOOO | OOOOOOOOOOOOOOOOOOOOOOOOOOOOOOOOOOOOOOOOOOOOOOOOOOOOOOOOOOOOOOOOOOOOOOOOOOOOOOOOOOOOOOOOOO | OOOOOOOOOOOOOOOOOOOOOOOOOOOOOOOOOOOOOOOOOOOOOOOOOOOOOOOOOOOOOOOOOOOOOOOOOOOOOOOOOOOOOOOOOO | OOOOOOOOOOOOOOOOOOOOOOOOOOOOOOOOOOOOOOOOOOOOOOOOOOOOOOOOOOOOOOOOOOOOOOOOOOOOOOOOOOOOOOOOOO | OOOOOOOOOOOOOOOOOOOOOOOOOOOOOOOOOOOOOOOOOOOOOOOOOOOOOOOOOOOOOOOOOOOOOOOOOOOOOOOOOOOOOOOOOO | OOOOOOOOOOOOOOOOOOOOOOOOOOOOOOOOOOOOOOOOOOOOOOOOOOOOOOOOOOOOOOOOOOOOOOOOOOOOOOOOOOOOOOOOOO | OOOOOOOOOOOOOOOOOOOOOOOOOOOOOOOOOOOOOOOOOOOOOOOOOOOOOOOOOOOOOOOOOOOOOOOOOOOOOOOOOOOOOOOOOO | OOOOOOOOOOOOOOOOOOOOOOOOOOOOOOOOOOOOOOOOOOOOOOOOOOOOOOOOOOOOOOOOOOOOOOOOOOOOOOOOOOOOOOOOOO |
| Second Source Change |  |  |  |  |  |  |  |  |  |
| Item | Location | Change Type | Foxconn P/N | Part Description | Manufacturer Full Name | Manufacturer P/N | RoHS | Sheet |  |
| OOOOOOOOOOOOOOOOOOOOOOOOOOOOOOOOOOOOOOOOOOOOOOOOOOOOOOOOOOOOOOOOOOOOOOOOOOOOOOOOOOOOOOOOOO | OOOOOOOOOOOOOOOOOOOOOOOOOOOOOOOOOOOOOOOOOOOOOOOOOOOOOOOOOOOOOOOOOOOOOOOOOOOOOOOOOOOOOOOOOO | OOOOOOOOOOOOOOOOOOOOOOOOOOOOOOOOOOOOOOOOOOOOOOOOOOOOOOOOOOOOOOOOOOOOOOOOOOOOOOOOOOOOOOOOOO | OOOOOOOOOOOOOOOOOOOOOOOOOOOOOOOOOOOOOOOOOOOOOOOOOOOOOOOOOOOOOOOOOOOOOOOOOOOOOOOOOOOOOOOOOO | OOOOOOOOOOOOOOOOOOOOOOOOOOOOOOOOOOOOOOOOOOOOOOOOOOOOOOOOOOOOOOOOOOOOOOOOOOOOOOOOOOOOOOOOOO | OOOOOOOOOOOOOOOOOOOOOOOOOOOOOOOOOOOOOOOOOOOOOOOOOOOOOOOOOOOOOOOOOOOOOOOOOOOOOOOOOOOOOOOOOO | OOOOOOOOOOOOOOOOOOOOOOOOOOOOOOOOOOOOOOOOOOOOOOOOOOOOOOOOOOOOOOOOOOOOOOOOOOOOOOOOOOOOOOOOOO | OOOOOOOOOOOOOOOOOOOOOOOOOOOOOOOOOOOOOOOOOOOOOOOOOOOOOOOOOOOOOOOOOOOOOOOOOOOOOOOOOOOOOOOOOO | OOOOOOOOOOOOOOOOOOOOOOOOOOOOOOOOOOOOOOOOOOOOOOOOOOOOOOOOOOOOOOOOOOOOOOOOOOOOOOOOOOOOOOOOOO | OOOOOOOOOOOOOOOOOOOOOOOOOOOOOOOOOOOOOOOOOOOOOOOOOOOOOOOOOOOOOOOOOOOOOOOOOOOOOOOOOOOOOOOOOO |
| Master Materials Change |  |  |  |  |  |  |  |  |  |
| Item | Foxconn P/N | Orig._Usage | New_Usage | Part Description | Manufacturer Full Name | Manufacturer P/N | RoHS | Location | Sheet |
| 1 | 0438005.WRGT | 0 | 11 | Fuse,Fast acting,32V,5A,G,SMD0603 | LITTELFUSE FAR EAST PTE LTD | 0438005.WRGT | Y | (+)FS5,FS8,FS11,FS14,FS17,FS19,FS20,FS23,FS24,FS25,FS26 | PWA BOM |
| 2 | 52030DA00-237-G | 0 | 16 | DIODE,Schottky,BAT46W-7-F,100V,150mA,G,SOD123-2,SMD | DIODES INEORPORATION | BAT46W-7-F |  | (+)PBMD1,PBFD1,PBED1,PBAD1,PAMD1,PAFD1,PAED1,PAAD1,PBMD4,PBFD4,PBED4,PAMD4,PAFD4,PAED4,PBAD5,PAAD5 | PWA BOM |
| 3 | 610107A00-017-G | 716 | 714 | RES,0 Ohm,+/-5%,1/16W,G,SMD0402 | KOA SPEER ELECTRONICS, INC. | RK73Z1ETTP | N | (+)R1850 (-)R1226,R1502,R1556 | PWA BOM |
| 4 | 61011H500-017-G | 22 | 24 | RES,22 Ohm,+/-1%,1/16W,G,SMD0402 | KOA SPEER ELECTRONICS, INC. | RK73H1ETTP22R0F | N | (+)R1226,R1502 | PWA BOM |
| 5 | SRV05-4ATCT | 0 | 2 | DIODE,Array-TVS,SRV05-4.TCT,5V,12A,G,SOT23-6,SMD | SEMTECH CORPORATION. | SRV05-4ATCT | N | (+)ED2,ED3 | PWA BOM |
| 6 | 34068LN00-317-G | 11 | 10 | CONN,Header,Pin Header,1X3,V/T,2.54mm,30u,G,SMD-3 | MOLEX INCORPORATED | 87898-0315 |  | (-)J3 | PWA BOM |
| 7 | 620108B00-015-G | 2 | 0 | CAP,120pF,+/-5%,NPO(C0G),50V,G,SMD0402 | MURATA ELEC. NORTH AMERICA | GRM1555C1H121J | N | (-)C2184,C2185 | PWA BOM |
| 8 | 521800900-227-G | 3 | 0 | DIODE,Array-TVS,SRV05-4.TCT,5V,12A,G,SOT23-6,SMD | SEMTECH CORPORATION. | SRV05-4.TCT | N | (-)ED1,ED2,ED3 | PWA BOM |
| 9 | 730103M00-086-G | 11 | 0 | Fuse,Fast acting,32V,5A,G,SMD0603 | LITTELFUSE FAR EAST PTE LTD | 0438005.WR | Y | (-)FS5,FS8,FS11,FS14,FS17,FS19,FS20,FS23,FS24,FS25,FS26 | PWA BOM |
| 10 | 520103B00-185-G | 8 | 0 | Diode,Rectifier&Switching,MMBD1205,100V,200mA,G,SOT-23-3,SMD | FAIRCHILD SEMICONDUCTOR CORP | MMBD1205 | N | (-)PBMD1,PBFD1,PBED1,PBAD1,PAMD1,PAFD1,PAED1,PAAD1 | PWA BOM |
| 11 | 610124C00-017-G | 2 | 0 | RES,57.6 Ohm,+/-1%,1/16W,G,SMD0402 | KOA SPEER ELECTRONICS, INC. | RK73H1ETTP57R6F | N | (-)R1838,R1839 | PWA BOM |
| 12 | 34080F500-653-G | 1 | 0 | CONN,Switch,slide,25mA,24V,G,SMD-8 | DIPTRONICS MANUFACTURING INC. | DHN-04F-T-V-T/R |  | (-)PSUSW1 | PWA BOM |
| OOOOOOOOOOOOOOOOOOOOOOOOOOOOOOOOOOOOOOOOOOOOOOOOOOOOOOOOOOOOOOOOOOOOOOOOOOOOOOOOOOOOOOOOOO | OOOOOOOOOOOOOOOOOOOOOOOOOOOOOOOOOOOOOOOOOOOOOOOOOOOOOOOOOOOOOOOOOOOOOOOOOOOOOOOOOOOOOOOOOO | OOOOOOOOOOOOOOOOOOOOOOOOOOOOOOOOOOOOOOOOOOOOOOOOOOOOOOOOOOOOOOOOOOOOOOOOOOOOOOOOOOOOOOOOOO | OOOOOOOOOOOOOOOOOOOOOOOOOOOOOOOOOOOOOOOOOOOOOOOOOOOOOOOOOOOOOOOOOOOOOOOOOOOOOOOOOOOOOOOOOO | OOOOOOOOOOOOOOOOOOOOOOOOOOOOOOOOOOOOOOOOOOOOOOOOOOOOOOOOOOOOOOOOOOOOOOOOOOOOOOOOOOOOOOOOOO | OOOOOOOOOOOOOOOOOOOOOOOOOOOOOOOOOOOOOOOOOOOOOOOOOOOOOOOOOOOOOOOOOOOOOOOOOOOOOOOOOOOOOOOOOO | OOOOOOOOOOOOOOOOOOOOOOOOOOOOOOOOOOOOOOOOOOOOOOOOOOOOOOOOOOOOOOOOOOOOOOOOOOOOOOOOOOOOOOOOOO | OOOOOOOOOOOOOOOOOOOOOOOOOOOOOOOOOOOOOOOOOOOOOOOOOOOOOOOOOOOOOOOOOOOOOOOOOOOOOOOOOOOOOOOOOO | OOOOOOOOOOOOOOOOOOOOOOOOOOOOOOOOOOOOOOOOOOOOOOOOOOOOOOOOOOOOOOOOOOOOOOOOOOOOOOOOOOOOOOOOOO |  |
| TLA Parts Change |  |  |  |  |  |  |  |  |  |
| Item | Foxconn P/N | Qty | Part Description | Manufacturer Full Name | Manufacturer P/N | RoHS | Location | Remark |  |
| BOM Change List Date:Mon Jul 31 17:05:18 CST 2017 |  |  |  |  |  |  |  |  |  |
| New BOM file : C:\<user>\new.xls |  |  |  |  |  |  |  |  |  |
| Old BOM file : C:\<user>\old.xls |  |  |  |  |  |  |  |  |  |
| ##### Add Parts |  |  |  |  |  |  |  |  |  |
| Item | Location | Qty | Foxconn P/N | Part Description | Manufacturer Full Name | Manufacturer P/N | RoHS | Sheet |  |
| 1 | PBMD4,PBFD4,PBED4,PAMD4,PAFD4,PAED4,PBAD5,PAAD5 | 8 | 52030DA00-237-G | DIODE,Schottky,BAT46W-7-F,100V,150mA,G,SOD123-2,SMD | DIODES INEORPORATION | BAT46W-7-F | G | PWA BOM |  |
| 2 | R1850 | 1 | 610107A00-017-G | RES,0 Ohm,+/-5%,1/16W,G,SMD0402 | KOA SPEER ELECTRONICS, INC. | RK73Z1ETTP | G | PWA BOM |  |
|  |  |  | 610107A00-024-G | RES,0 Ohm,+/-5%,1/16W,G,SMD0402 | PANASONIC INDUSTRIAL CO.,LTD. | ERJ2GE0R00X | G | PWA BOM |  |
|  |  |  | 610107A00-029-G | RES,0 Ohm,+/-5%,1/16W,G,SMD0402 | VISHAY ENTER TECHNO LOGY.INC | CRCW04020000Z0ED | G | PWA BOM |  |
| ##### Remove Parts |  |  |  |  |  |  |  |  |  |
| Item | Location | Qty | Foxconn P/N | Part Description | Manufacturer Full Name | Manufacturer P/N | RoHS | Sheet |  |
| 1 | C2184,C2185 | 2 | 620108B00-015-G | CAP,120pF,+/-5%,NPO(C0G),50V,G,SMD0402 | MURATA ELEC. NORTH AMERICA | GRM1555C1H121J | G | PWA BOM |  |
|  |  |  | 620108B00-023-G | CAP,120pF,+/-5%,NPO(C0G),50V,G,SMD0402 | TAIYO ELECTRIC IND.CO.LTD | UMK105CG121JV-F | G | PWA BOM |  |
|  |  |  | 620108B00-026-G | CAP,120pF,+/-5%,NPO(C0G),50V,G,SMD0402 | SAMSUNG SEMICONDUCTOR | CL05C121JB5NNNC | G | PWA BOM |  |
| 2 | ED1 | 1 | 521800900-227-G | DIODE,Array-TVS,SRV05-4.TCT,5V,12A,G,SOT23-6,SMD | SEMTECH CORPORATION. | SRV05-4.TCT | G | PWA BOM |  |
|  |  |  | 52180C200-086-G | Diode,Array-TVS,SRV05-4HTG,SOT-23,6P,G | LITTELFUSE FAR EAST PTE LTD | SRV05-4HTG | G | PWA BOM |  |
| 3 | R1556 | 1 | 610107A00-017-G | RES,0 Ohm,+/-5%,1/16W,G,SMD0402 | KOA SPEER ELECTRONICS, INC. | RK73Z1ETTP | G | PWA BOM |  |
|  |  |  | 610107A00-024-G | RES,0 Ohm,+/-5%,1/16W,G,SMD0402 | PANASONIC INDUSTRIAL CO.,LTD. | ERJ2GE0R00X | G | PWA BOM |  |
|  |  |  | 610107A00-029-G | RES,0 Ohm,+/-5%,1/16W,G,SMD0402 | VISHAY ENTER TECHNO LOGY.INC | CRCW04020000Z0ED | G | PWA BOM |  |
| 4 | R1838,R1839 | 2 | 610124C00-017-G | RES,57.6 Ohm,+/-1%,1/16W,G,SMD0402 | KOA SPEER ELECTRONICS, INC. | RK73H1ETTP57R6F | G | PWA BOM |  |
|  |  |  | 610124C00-024-G | RES,57.6 Ohm,+/-1%,1/16W,G,SMD0402 | PANASONIC INDUSTRIAL CO.,LTD. | ERJ2RKF57R6X | G | PWA BOM |  |
| 5 | J3 | 1 | 34068LN00-317-G | CONN,Header,Pin Header,1X3,V/T,2.54mm,30u,G,SMD-3 | MOLEX INCORPORATED | 87898-0315 | G | PWA BOM |  |
|  |  |  | 34068HT00-245-G | CONN,Header,Pin Header,1X3,V/T,Bla,2.54mm,30u,SMD-3 | AMPHENOL SHANGHAI CORP. | G800MU305010EU | G | PWA BOM |  |
|  |  |  | 34068GU00-309-G | CONN,Header,Pin Header,1X3,V/T,Bla,2.54mm,30u,SMD-3 | SAMTEC INC. | TSM-103-01-S-SV-P-TR | G | PWA BOM |  |
| 6 | PSUSW1 | 1 | 34080F500-653-G | CONN,Switch,slide,25mA,24V,G,SMD-8 | DIPTRONICS MANUFACTURING INC. | DHN-04F-T-V-T/R | G | PWA BOM |  |
| ##### Change Parts |  |  |  |  |  |  |  |  |  |
| Item | Location | Qty | Foxconn P/N | Part Description | Manufacturer Full Name | Manufacturer P/N | RoHS | Sheet | Remark |
| 1 | PCB | 1 | 0101EW800-000-G | PCB,Zaius-MB DVT-X03,OSP,Blu,22L,22.20*13.00,G | GOLD CIRCUIT ELECTRONICS LTD. | 0101EW800-000-G | G | PWA BOM | In New BOM |
|  |  |  | 0101EW800-000-G | PCB,Zaius-MB DVT-X03,OSP,Blu,22L,22.20*13.00,G | ISUPETASYS CO., LTD | 0101EW800-000-G |  | PWA BOM | In New BOM |
|  | PCB | 1 | 0101EW800-000-G | PCB,Zaius-MB DVT-X03,OSP,Blu,22L,22.20*13.00,G | GOLD CIRCUIT ELECTRONICS LTD. | 0101EW800-000-G | G | PWA BOM | In Old BOM |
|  |  |  | 0101EW800-000-G | PCB,Zaius-MB DVT-X03,OSP,Blu,22L,22.20*13.00,G | ISUPETASYS CO., LTD | 0101EW800-000-G | G | PWA BOM | In Old BOM |
| 2 | PBMC6,PBFC6,PBEC6,PBAC6,PAMC6,PAFC6,PAEC6,PAAC6 | 8 | 62011DQ00-015-G | CAP,27nF,+/-10%,X7R,25V,G,SMD0402 | MURATA ELEC. NORTH AMERICA | GRM155R71E273KA88D | G | PWA BOM | In New BOM |
|  |  |  | 62011DQ00-025-G | CAP,27nF,+/-10%,X7R,25V,G,SMD0402 | KEMET ELECTRONICS CORPORATION | C0402C273K3RAC | G | PWA BOM | In New BOM |
|  | PBMC6,PBFC6,PBEC6,PBAC6,PAMC6,PAFC6,PAEC6,PAAC6 | 8 | 62011DQ00-015-G | CAP,27nF,+/-10%,X7R,25V,G,SMD0402 | MURATA ELEC. NORTH AMERICA | GRM155R71E273KA88D | G | PWA BOM | In Old BOM |
|  |  |  | C0402C273K3RAC | CAP,27nF,+/-10%,X7R,25V,G,SMD0402 | KEMET ELECTRONICS CORPORATION | C0402C273K3RAC | G | PWA BOM | In Old BOM |
| 3 | PSUFS1,PBAFS1,PAAFS1,PSUFS2 | 4 | 730100M00-086-G | Fuse,Very fast acting,125V,10A,G,SMD | LITTELFUSE FAR EAST PTE LTD | 0451010.MRL | G | PWA BOM | In New BOM |
|  |  |  | 730109A00-088-G | Fuse,Fast acting,125V,10A,G,SMD | COOPER BUSSMANN, INC. | CB61F10A-TR2 | G | PWA BOM | In New BOM |
|  | PSUFS1,PBAFS1,PAAFS1,PSUFS2 | 4 | 730100M00-086-G | Fuse,Very fast acting,125V,10A,G,SMD | LITTELFUSE FAR EAST PTE LTD | 0451010.MRL | G | PWA BOM | In Old BOM |
|  |  |  | CB61F10A-TR2 | Fuse,CB61F10A-TR2 | COOPER BUSSMANN, INC. | CB61F10A-TR2 | G | PWA BOM | In Old BOM |
| 4 | PBMR41,PBFR41,PBER41,PBAR41,PAMR41,PAFR41,PAER41,PAAR41 | 8 | 611008W00-017-G | RES,73.2KOhm,+/-0.1%,1/16W,G,SMD0402 | KOA SPEER ELECTRONICS, INC. | RN731ETTP7322B25 | G | PWA BOM | In New BOM |
|  |  |  | 611008W00-011-G | RES,73.2KOhm,+/-0.1%,1/16W,G,SMD0402 | YAGEO CORPORATION COMPONENT | RT0402BRD0773K2L | G | PWA BOM | In New BOM |
|  |  |  | 611008W00-024-G | RES,73.2KOhm,+/-0.1%,1/16W,G,SMD0402 | PANASONIC INDUSTRIAL CO.,LTD. | ERA2AEB7322X | G | PWA BOM | In New BOM |
|  | PBMR41,PBFR41,PBER41,PBAR41,PAMR41,PAFR41,PAER41,PAAR41 | 8 | 611008W00-017-G | RES,73.2KOhm,+/-0.1%,1/16W,G,SMD0402 | KOA SPEER ELECTRONICS, INC. | RN731ETTP7322B25 | G | PWA BOM | In Old BOM |
|  |  |  | 611008W00-011-G | RES,73.2KOhm,+/-0.1%,1/16W,G,SMD0402 | YAGEO CORPORATION COMPONENT | RT0402BRD0773K2L | G | PWA BOM | In Old BOM |
|  |  |  | ERA2AEB7322X | RES,73.2KOhm,+/-0.1%,1/16W,G,SMD0402 | PANASONIC INDUSTRIAL CO.,LTD. | ERA2AEB7322X | G | PWA BOM | In Old BOM |
| 5 | PHAR4,PBMR90,PAMR90,PBER92,PBAR92,PAFR92,PAER92,PAAR92,PBFR93,PBAR102,PAAR102 | 11 | 610130Y00-017-G | RES,1 Ohm,+/-1%,1/3W,G,SMD1206 | KOA SPEER ELECTRONICS, INC. | SR732BTTD1R00F | G | PWA BOM | In New BOM |
|  |  |  | 610606F00-029-G | RES,1 Ohm,+/-1%,1/3W,G,SMD1206 | VISHAY ENTER TECHNO LOGY.INC | L1206K1R00FNT | G | PWA BOM | In New BOM |
|  | PHAR4,PBMR90,PAMR90,PBER92,PBAR92,PAFR92,PAER92,PAAR92,PBFR93,PBAR102,PAAR102 | 11 | 610130Y00-017-G | RES,1 Ohm,+/-1%,1/3W,G,SMD1206 | KOA SPEER ELECTRONICS, INC. | SR732BTTD1R00F | G | PWA BOM | In Old BOM |
|  |  |  | L1206K1R00FNT | RES,1 Ohm,+/-1%,1/3W,G,SMD1206 | VISHAY ENTER TECHNO LOGY.INC | L1206K1R00FNT | G | PWA BOM | In Old BOM |
| 6 | PBMR113,PAMR113,PBER115,PAFR115,PAER115,PBFR116,PBAR119,PAAR119 | 8 | 61100RU00-017-G | RES,59 Ohm,+/-1%,1/16W,G,SMD0402 | KOA SPEER ELECTRONICS, INC. | RN731ETTP59R0F25 | G | PWA BOM | In New BOM |
|  |  |  | 611010300-029-G | RES,59 Ohm,+/-1%,1/10W,G,SMD0402 | VISHAY ENTER TECHNO LOGY.INC | TNPW040259R0FEEP | G | PWA BOM | In New BOM |
|  | PBMR113,PAMR113,PBER115,PAFR115,PAER115,PBFR116,PBAR119,PAAR119 | 8 | 61100RU00-017-G | RES,59 Ohm,+/-1%,1/16W,G,SMD0402 | KOA SPEER ELECTRONICS, INC. | RN731ETTP59R0F25 | G | PWA BOM | In Old BOM |
|  |  |  | TNPW040259R0FEEP | RES,59 Ohm,+/-1%,1/10W,G,SMD0402 | VISHAY ENTER TECHNO LOGY.INC | TNPW040259R0FEEP | G | PWA BOM | In Old BOM |
| 7 | PBFL1,PBEL1,PAFL1,PAEL1,PBML2,PAML2 | 6 | 63035NF00-57M-G | IND,1.5uH@100KHz,+/-10%,12A,6mOhm,SHLD,G,SMD | Eaton Corporation | HCV1206-1R5-R | G | PWA BOM | In New BOM |
|  |  |  | 630362H00-065-G | IND,1.5uH@100KHz,+/-10%,12A,6.6mOhm,SHLD,G,SMD | DELTA ELECTRONICS INDUSTRIAL CO.,LTD | HMS1360-1R5 | G | PWA BOM | In New BOM |
|  | PBFL1,PBEL1,PAFL1,PAEL1,PBML2,PAML2 | 6 | 63035NF00-57M-G | IND,1.5uH@100KHz,+/-10%,12A,6mOhm,SHLD,G,SMD | Eaton Corporation | HCV1206-1R5-R | G | PWA BOM | In Old BOM |
|  |  |  | HMS1360-1R5 | IND,1.5uH@100KHz,+/-10%,12A,6mOhm,SHLD,G,SMD | DELTA ELECTRONICS INDUSTRIAL CO.,LTD | HMS1360-1R5 | G | PWA BOM | In Old BOM |
| 8 | PBNL1,PANL1 | 2 | 630330G00-088-G | IND,300nH@100KHz,+/-10%,32.5A,304.5uOhm,SHLD,G,SMD | COOPER BUSSMANN, INC. | FP0906R1-R30-R | G | PWA BOM | In New BOM |
|  |  |  | 630332A01-051-G | Coil Ind,Shielded(SHLD),300nH@100KHz,+/-10%,34A,290uOhm,SMD,9.2*6.2*7.8,G | PULSE ELECTRONICS (SINGAPORE) | PA3288.301HLT | G | PWA BOM | In New BOM |
|  |  |  | 630330G00-129-G | IND,300nH@100KHz,+/-10%,32.5A,290uOhm,SHLD,G,SMD | MAG.LAYERS, SCIENTIFIC-TECHNICS (KUNSHAN) CO., LTD. | MSI-900608-R30K-E | G | PWA BOM | In New BOM |
|  | PBNL1,PANL1 | 2 | 630330G00-088-G | IND,300nH@100KHz,+/-10%,32.5A,304.5uOhm,SHLD,G,SMD | COOPER BUSSMANN, INC. | FP0906R1-R30-R | G | PWA BOM | In Old BOM |
|  |  |  | 630332A01-051-G | Coil Ind,Shielded(SHLD),300nH@100KHz,+/-10%,34A,290uOhm,SMD,9.2*6.2*7.8,G | PULSE ELECTRONICS (SINGAPORE) | PA3288.301HLT | G | PWA BOM | In Old BOM |
|  |  |  | MSI-900608-R30K-E | IND,300nH@100KHz,+/-10%,32.5A,290uOhm,SHLD,G,SMD | MAG.LAYERS, SCIENTIFIC-TECHNICS (KUNSHAN) CO., LTD. | MSI-900608-R30K-E | G | PWA BOM | In Old BOM |
| 9 | PCIE1,PCIE5 | 2 | 10061913-102HLF | CONN,PCIE-8X,V/T,Bla,1mm,30u,G,SMD-98 | FCI CONNECTORS HONGKONG LTD. | 10061913-102HLF | G | PWA BOM | In New BOM |
|  |  |  | 340320R00-278-G | CONN,PCIE-8X,V/T,Bla,1mm,30u,G,SMD-98 | TYCO ELECTRONICS CORPORATION | 2041366-4 | G | PWA BOM | In New BOM |
|  | PCIE1,PCIE5 | 2 | 10061913-102HLF | CONN,PCIE-8X,V/T,Bla,1mm,30u,G,SMD-98 | FCI CONNECTORS HONGKONG LTD. | 10061913-102HLF | G | PWA BOM | In Old BOM |
|  |  |  | 2041366-4 | CONN,PCIE-8X,V/T,Bla,1mm,30u,G,SMD-98 | TYCO ELECTRONICS CORPORATION | 2041366-4 | G | PWA BOM | In Old BOM |
| 10 | PCIE2,PCIE3,PCIE4 | 3 | 10061913-103HLF | CONN,PCIE-16X,V/T,Bla,1mm,30u,G,SMD-164 | FCI CONNECTORS HONGKONG LTD. | 10061913-103HLF | G | PWA BOM | In New BOM |
|  |  |  | 340320Q00-278-G | CONN,PCIE-16X,V/T,Bla,1mm,30u,G,SMD-164 | TYCO ELECTRONICS CORPORATION | 2041366-6 | G | PWA BOM | In New BOM |
|  | PCIE2,PCIE3,PCIE4 | 3 | 10061913-103HLF | CONN,PCIE-16X,V/T,Bla,1mm,30u,G,SMD-164 | FCI CONNECTORS HONGKONG LTD. | 10061913-103HLF | G | PWA BOM | In Old BOM |
|  |  |  | 2041366-6 | CONN,PCIE-16X,V/T,Bla,1mm,30u,G,SMD-164 | TYCO ELECTRONICS CORPORATION | 2041366-6 | G | PWA BOM | In Old BOM |
| 11 | PSTC4,PSLC4,PSFC4,PSEC4,PSDC4,PQPC4,PFRC4,PEEC4,PEDC4,PSPC3003,PIPC3003,PFPC3003,PEPC3003,PSRC3010 | 14 | 62012T300-015-G | CAP,1uF,+/-10%,X7S,25V,G,SMD0402 | MURATA ELEC. NORTH AMERICA | GRM155C71E105KE11D | G | PWA BOM | In New BOM |
|  |  |  | 620138700-026-G | CAP,1uF,+/-10%,X6S,25V,G,SMD0402 | SAMSUNG SEMICONDUCTOR | CL05X105KA5NQNC | G | PWA BOM | In New BOM |
|  |  |  | GRM155C81E105KE11D | CAP,1uF,+/-10%,X6S,25V,G,SMD0402 | MURATA | GRM155C81E105KE11D | G | PWA BOM | In New BOM |
|  | PSTC4,PSLC4,PSFC4,PSEC4,PSDC4,PQPC4,PFRC4,PEEC4,PEDC4,PSPC3003,PIPC3003,PFPC3003,PEPC3003,PSRC3010 | 14 | 62012T300-015-G | CAP,1uF,+/-10%,X7S,25V,G,SMD0402 | MURATA ELEC. NORTH AMERICA | GRM155C71E105KE11D | G | PWA BOM | In Old BOM |
|  |  |  | 620138700-026-G | CAP,1uF,+/-10%,X6S,25V,G,SMD0402 | SAMSUNG | CL05X105KA5NQNC | G | PWA BOM | In Old BOM |
|  |  |  | GRM155C81E105KE11D | CAP,1uF,+/-10%,X6S,25V,G,SMD0402 | MURATA | GRM155C81E105KE11D | G | PWA BOM | In Old BOM |
| 12 | PSPL1,PIPL1,PFPL1,PEPL1 | 4 | 63032CC00-088-G | IND,1uH@100KHz,+/-20%,11A,10mOhm,SHLD,G,SMD | COOPER BUSSMANN, INC. | HCM0703-1R0-R | G | PWA BOM | In New BOM |
|  |  |  | 63035CF00-034-G | Coil Ind,Shielded(SHLD),1uH@100KHz,+/-20%,10A,10mOhm,SMD,6.95*6.6*2.8,,,G | CYNTEC CO. LTD | CMMS063T1R0MS | G | PWA BOM | In New BOM |
|  |  |  | 630362F00-051-G | IND,22nH@100KHz,+/-20%,19A,368uOhm,SHLD,G,SMD | PULSE ELECTRONICS (SINGAPORE) | PA4341.102NLT | G | PWA BOM | In New BOM |
|  | PSPL1,PIPL1,PFPL1,PEPL1 | 4 | 63032CC00-088-G | IND,1uH@100KHz,+/-20%,11A,10mOhm,SHLD,G,SMD | COOPER BUSSMANN, INC. | HCM0703-1R0-R | G | PWA BOM | In Old BOM |
|  |  |  | CMMS063T1R0MS | IND,CMMS063T1R0MS | CYNTEC CO. LTD | CMMS063T1R0MS | G | PWA BOM | In Old BOM |
|  |  |  | PA4341.102NLT | IND,PA4341.102NLT | PULSE ELECTRONICS (SINGAPORE) | PA4341.102NLT | G | PWA BOM | In Old BOM |
| 13 | PSPL2,PIPL2,PFPL2,PEPL2 | 4 | 630341400-088-G | IND,22nH@1MHz,+/-20%,19A,368uOhm,SHLD,G,SMD | COOPER BUSSMANN, INC. | FP0404R1-R022-R | G | PWA BOM | In New BOM |
|  |  |  | 630362G00-065-G | IND,22nH@100KHz,+/-20%,19A,0.32mOhm,SHLD,G,SMD | DELTA ELECTRONICS INDUSTRIAL CO.,LTD | HCB0430-220 | G | PWA BOM | In New BOM |
|  | PSPL2,PIPL2,PFPL2,PEPL2 | 4 | 630341400-088-G | IND,22nH@1MHz,+/-20%,19A,368uOhm,SHLD,G,SMD | COOPER BUSSMANN, INC. | FP0404R1-R022-R | G | PWA BOM | In Old BOM |
|  |  |  | HCB0430-220 | IND,22nH@1MHz,+/-20%,19A,320uOhm,SHLD,G,SMD | DELTA ELECTRONICS INDUSTRIAL CO.,LTD | HCB0430-220 | G | PWA BOM | In Old BOM |
| 14 | PQPL2,PFRL2 | 2 | 63032PP00-088-G | IND,4.7uH@100KHz,+/-20%,5.5A,40mOhm,SHLD,G,SMD | COOPER BUSSMANN, INC. | HCM0703-4R7-R | G | PWA BOM | In New BOM |
|  |  |  | 63030PW00-034-G | Coil Ind,Shielded(SHLD),4.7uH@100KHz,+/-20%,5.5A,40mOhm,SMD,7.3*6.6*3.0,G | CYNTEC CO. LTD | PCMC063T-4R7MN | G | PWA BOM | In New BOM |
|  |  |  | 63031AD04-129-G | IND,4.7uH@100KHz,+/-20%,5.5A,40mOhm,SHLD,G,SMD | MAG.LAYERS, SCIENTIFIC-TECHNICS (KUNSHAN) CO., LTD. | SPS-06CZ-4R7M-V1 | G | PWA BOM | In New BOM |
|  | PQPL2,PFRL2 | 2 | 63032PP00-088-G | IND,4.7uH@100KHz,+/-20%,5.5A,40mOhm,SHLD,G,SMD | COOPER BUSSMANN, INC. | HCM0703-4R7-R | G | PWA BOM | In Old BOM |
|  |  |  | 63030PW00-034-G | Coil Ind,Shielded(SHLD),4.7uH@100KHz,+/-20%,5.5A,40mOhm,SMD,7.3*6.6*3.0,G | CYNTEC CO. LTD | PCMC063T-4R7MN | G | PWA BOM | In Old BOM |
|  |  |  | SPS-06CZ-4R7M-V1 | IND,4.7uH@100KHz,+/-20%,5.5A,40mOhm,SHLD,G,SMD | MAG.LAYERS, SCIENTIFIC-TECHNICS (KUNSHAN) CO., LTD. | SPS-06CZ-4R7M-V1 | G | PWA BOM | In Old BOM |
| 15 | PFRR19 | 1 | 61100YB00-017-G | RES,2.94KOhm,+/-0.1%,1/16W,G,SMD0402 | KOA SPEER ELECTRONICS, INC. | RN731ETTP2941B25 | G | PWA BOM | In New BOM |
|  |  |  | 61100YB00-011-G | RES,2.94KOhm,+/-0.1%,1/16W,SMD0402,G | YAGEO CORPORATION COMPONENT | RT0402BRD072K94L | G | PWA BOM | In New BOM |
|  |  |  | 61100YB00-044-G | RES,2.94KOhm,+/-0.1%,1/16W,G,SMD0402 | TA-I TECHNOLOGY CO., LTD. | RB04BTP2941 | G | PWA BOM | In New BOM |
|  | PFRR19 | 1 | 61100YB00-017-G | RES,2.94KOhm,+/-0.1%,1/16W,G,SMD0402 | KOA SPEER ELECTRONICS, INC. | RN731ETTP2941B25 | G | PWA BOM | In Old BOM |
|  |  |  | 61100YB00-011-G | RES,2.94KOhm,+/-0.1%,1/16W,SMD0402,G | YAGEO CORPORATION COMPONENT | RT0402BRD072K94L | G | PWA BOM | In Old BOM |
|  |  |  | RB04BTP2941 | RES,2.94KOhm,+/-0.1%,1/16W,SMD0402,G | TA-I TECHNOLOGY CO., LTD. | RB04BTP2941 | G | PWA BOM | In Old BOM |
| 16 | PHAC3 | 1 | 620133600-015-G | CAP,1nF,+/-5%,X7R,100V,G,SMD0805 | MURATA ELEC. NORTH AMERICA | GRM219R72A102JA01D | G | PWA BOM | In New BOM |
|  |  |  | 620133600-026-G | CAP,1nF,+/-5%,X7R,100V,G,SMD0805 | SAMSUNG SEMICONDUCTOR | CL21B102JCANNNC | G | PWA BOM | In New BOM |
|  | PHAC3 | 1 | 620133600-015-G | CAP,1nF,+/-5%,X7R,100V,G,SMD0805 | MURATA ELEC. NORTH AMERICA | GRM219R72A102JA01D | G | PWA BOM | In Old BOM |
|  |  |  | CL21B102JCANNNC | CAP,MLCC,1nF,+/-5%,X7R,100V,SMD0805,G | SAMSUNG SEMICONDUCTOR | CL21B102JCANNNC | G | PWA BOM | In Old BOM |
| 17 | PHAQ1,PHAQ2,PHAQ3 | 3 | 51031VY00-031-G | MOS N,PSMN4R8-100BSE,100V,120A,4.8m@10V,G,SOT404-3,SMD | NXP SEMICONDUCTORS | PSMN4R8-100BSE | G | PWA BOM | In New BOM |
|  |  |  | 51032HE00-185-G | MOS N,FDB047N10,100V,120A,3.9m@10V,G,TO263-3,SMD | FAIRCHILD SEMICONDUCTOR CORP | FDB047N10 | G | PWA BOM | In New BOM |
|  |  |  | SUM70040E-GE3 | MOS N,SUM70040E-GE3,100V,120A,4.0m@10V,G,TO263-3,SMD | VISHAY ENTER TECHNO LOGY.INC | SUM70040E-GE3 | G | PWA BOM | In New BOM |
|  | PHAQ1,PHAQ2,PHAQ3 | 3 | 51031VY00-031-G | MOS N,PSMN4R8-100BSE,100V,120A,4.8m@10V,G,SOT404-3,SMD | NXP SEMICONDUCTORS | PSMN4R8-100BSE | G | PWA BOM | In Old BOM |
|  |  |  | FDB047N10 | MOS N,FDB047N10,100V,120A,3.9m@10V,G,TO263-3,SMD | FAIRCHILD SEMICONDUCTOR CORP | FDB047N10 | G | PWA BOM | In Old BOM |
|  |  |  | SUM70040E-GE3 | MOS N,SUM70040E-GE3,100V,120A,4.0m@10V,G,TO263-3,SMD | VISHAY ENTER TECHNO LOGY.INC | SUM70040E-GE3 | G | PWA BOM | In Old BOM |
| 18 | PHAQ4 | 1 | 51020A000-031-G | TRANS P,PBHV9115T,150V,1A,G,SOT23-3,SMD | NXP SEMICONDUCTORS | PBHV9115T | G | PWA BOM | In New BOM |
|  |  |  | 51020BJ00-185-G | Trans PNP,MMBT5401,-150V,-600mA,G,SOT-23-3,SMD | FAIRCHILD SEMICONDUCTOR CORP | MMBT5401 | G | PWA BOM | In New BOM |
|  |  |  | 510204N00-237-G | Trans PNP,MMBT5401-7-F,-150V,-600mA,SOT-23,3P,G | DIODES INCORPORATION | MMBT5401-7-F | G | PWA BOM | In New BOM |
|  | PHAQ4 | 1 | 51020A000-031-G | TRANS P,PBHV9115T,150V,1A,G,SOT23-3,SMD | NXP SEMICONDUCTORS | PBHV9115T | G | PWA BOM | In Old BOM |
|  |  |  | MMBT5401 | TRANS P,150V,1A,G,SOT23-3,SMD | FAIRCHILD SEMICONDUCTOR CORP | MMBT5401 | G | PWA BOM | In Old BOM |
|  |  |  | 510204N00-237-G | Trans PNP,MMBT5401-7-F,-150V,-600mA,SOT-23,3P,G | DIODES INCORPORATION | MMBT5401-7-F | G | PWA BOM | In Old BOM |
| 19 | PHAQ5,PHAQ6 | 2 | 51032D100-237-G | MOS N,DMN10H220L-7,100V,1.6A,220m@10V,G,SOT-23-3,SMD | DIODES INCORPORATION | DMN10H220L-7 | G | PWA BOM | In New BOM |
|  | PHAQ5,PHAQ6 | 2 | 51032D100-237-G | MOS N,DMN10H220L-7,100V,1.6A,220m@10V,G,SOT-23-3,SMD | DIODES INCORPORATION | DMN10H220L-7 | G | PWA BOM | In Old BOM |
|  |  |  | FQT7N10LTF | MOS N,FQT7N10LTF,100V,1.7A,220m@10V,G,SOT-23-3,SMD | FAIRCHILD SEMICONDUCTOR CORP | FQT7N10LTF | G | PWA BOM | In Old BOM |
| 20 | PHAR2 | 1 | 61100DA00-017-G | RES,33KOhm,+/-0.1%,1/16W,G,SMD0402 | KOA SPEER ELECTRONICS, INC. | RN731ETTP3302B25 | G | PWA BOM | In New BOM |
|  |  |  | 61100DA00-011-G | RES,33KOhm,+/-0.1%,1/16W,G,SMD0402 | YAGEO CORPORATION COMPONENT | RT0402BRD0733KL | G | PWA BOM | In New BOM |
|  |  |  | 611010100-029-G | RES,33KOhm,+/-0.1%,1/10W,G,SMD0402 | VISHAY | TNPW040233K0BEED | G | PWA BOM | In New BOM |
|  | PHAR2 | 1 | 61100DA00-017-G | RES,33KOhm,+/-0.1%,1/16W,G,SMD0402 | KOA SPEER ELECTRONICS, INC. | RN731ETTP3302B25 | G | PWA BOM | In Old BOM |
|  |  |  | 61100DA00-011-G | RES,33KOhm,+/-0.1%,1/16W,G,SMD0402 | YAGEO CORPORATION COMPONENT | RT0402BRD0733KL | G | PWA BOM | In Old BOM |
|  |  |  | TNPW040233K0BEED | RES,33KOhm,+/-0.1%,1/16W,G,SMD0402 | VISHAY | TNPW040233K0BEED | G | PWA BOM | In Old BOM |
| 21 | PHAR5 | 1 | 61100QM00-017-G | RES,100KOhm,+/-0.1%,1/10W,G,SMD0603 | KOA SPEER ELECTRONICS, INC. | RN73H1JTTD1003B25 | G | PWA BOM | In New BOM |
|  |  |  | 61100QM00-011-G | RES,100KOhm,+/-0.1%,1/10W,G,SMD0603 | YAGEO CORPORATION COMPONENT | RT0603BRD07100KL | G | PWA BOM | In New BOM |
|  | PHAR5 | 1 | 61100QM00-017-G | RES,100KOhm,+/-0.1%,1/10W,G,SMD0603 | KOA SPEER ELECTRONICS, INC. | RN73H1JTTD1003B25 | G | PWA BOM | In Old BOM |
|  |  |  | 61100QM00-011-G | RES,100KOhm,+/-0.1%,1/10W,G,SMD0603 | YAGEO CORPORATION COMPONENT | RT0603BRD07100KL | G | PWA BOM | In Old BOM |
|  |  |  | TNPW0402100KBEED | RES,100KOhm,+/-0.1%,1/10W,G,SMD0603 | VISHAY | TNPW0402100KBEED | G | PWA BOM | In Old BOM |
| 22 | PSDR19 | 1 | 61100KM01-017-G | RES,15KOhm,+/-0.1%,1/16W,G,SMD0402 | KOA SPEER ELECTRONICS, INC. | RN73H1ETTP1502B25 | G | PWA BOM | In New BOM |
|  |  |  | 61100KM02-024-G | RES,15KOhm,+/-0.1%,1/16W,G,SMD0402 | PANASONIC INDUSTRIAL CO.,LTD. | ERA2AEB153X | G | PWA BOM | In New BOM |
|  | PSDR19 | 1 | 61100KM01-017-G | RES,15KOhm,+/-0.1%,1/16W,G,SMD0402 | KOA SPEER ELECTRONICS, INC. | RN73H1ETTP1502B25 | G | PWA BOM | In Old BOM |
|  |  |  | ERA2AEB153X | RES,15KOhm,+/-0.1%,1/16W,G,SMD0402 | PANASONIC INDUSTRIAL CO.,LTD. | ERA2AEB153X | G | PWA BOM | In Old BOM |
| 23 | PSUU1 | 1 | 880302300-065-G | Converter,input 40V~60V,600W,G,Q54SJ12050NNDH,OVAL | DELTA ELECTRONICS INDUSTRIAL CO.,LTD | Q54SJ12050NNDH | G | PWA BOM | In New BOM |
|  |  |  | 880302100-065-G | Converter,input 40V~60V,600W,G,Q54SH12050NNDH | DELTA ELECTRONICS INDUSTRIAL CO.,LTD | Q54SH12050NNDH | G | PWA BOM | In New BOM |
|  |  |  | 880302A00-462-G | Converter,input 40V~60V,650W,G,BMR458 2130/004 | Ericsson | BMR458 2130/004 | G | PWA BOM | In New BOM |
|  | PSUU1 | 1 | 880302300-065-G | Converter,input 40V~60V,600W,G,Q54SJ12050NNDH,OVAL | DELTA ELECTRONICS INDUSTRIAL CO.,LTD | Q54SJ12050NNDH | G | PWA BOM | In Old BOM |
|  |  |  | 880302100-065-G | Converter,input 40V~60V,600W,G,Q54SH12050NNDH | DELTA ELECTRONICS INDUSTRIAL CO.,LTD | Q54SH12050NNDH | G | PWA BOM | In Old BOM |
|  |  |  | BMR458 2130/004 | Ericsson,BMR458 2130/004 | Ericsson | BMR458 2130/004 | G | PWA BOM | In Old BOM |
| 24 | QN2,QN3 | 2 | 510503B00-223-G | MOS N/N,NTZD3154NT1G,20V,0.54A,550m24.5V,G,SOT563-6,SMD | ON SEMICONDUCTOR CORP | NTZD3154NT1G | G | PWA BOM | In New BOM |
|  |  |  | Si1034CX-T1-GE3 | MOS N/N,Si1034CX,20V,0.5A,1ohm@4V,G,EMT-6,SMD | VISHAY ENTER TECHNO LOGY.INC | Si1034CX-T1-GE3 | G | PWA BOM | In New BOM |
|  |  |  | 51050KW00-131-G | MOS N/N,SSM6N36FE,20V,500mA,0.63@5V,G,ES6-6,SMD | TOSHIBA ELECTRONICS ASIA LTD | SSM6N36FE | G | PWA BOM | In New BOM |
|  | QN2,QN3 | 2 | 510503B00-223-G | MOS N/N,NTZD3154NT1G,20V,0.54A,550m24.5V,G,SOT563-6,SMD | ON SEMICONDUCTOR CORP | NTZD3154NT1G | G | PWA BOM | In Old BOM |
|  |  |  | Si1034CX-T1-GE3 | MOS N/N,Si1034CX,20V,0.5A,1ohm@4V,G,EMT-6,SMD | VISHAY ENTER TECHNO LOGY.INC | Si1034CX-T1-GE3 | G | PWA BOM | In Old BOM |
|  |  |  | SSM6N36FE | MOS N/N,20V,0.54A,550m24.5V,G,SOT563-6,SMD | TOSHIBA ELECTRONICS ASIA LTD | SSM6N36FE | G | PWA BOM | In Old BOM |
| 25 | R11,R12,R13,R373,R374,R375 | 6 | 61100Y400-017-G | RES,169 Ohm,+/-0.1%,1/16W,G,SMD0402 | KOA SPEER ELECTRONICS, INC. | RN731ETTP1690B25 | G | PWA BOM | In New BOM |
|  |  |  | 61100Y400-011-G | RES,169Ohm,+/-0.1%,1/16W,SMD0402,G | YAGEO CORPORATION COMPONENT | RT0402BRD07169RL | G | PWA BOM | In New BOM |
|  |  |  | 61100Y401-044-G | RES,169 Ohm,+/-0.1%,1/16W,G,SMD0402 | TA-I TECHNOLOGY CO., LTD. | RB04BTP1690 | G | PWA BOM | In New BOM |
|  | R11,R12,R13,R373,R374,R375 | 6 | 61100Y400-017-G | RES,169 Ohm,+/-0.1%,1/16W,G,SMD0402 | KOA SPEER ELECTRONICS, INC. | RN731ETTP1690B25 | G | PWA BOM | In Old BOM |
|  |  |  | 61100Y400-011-G | RES,169Ohm,+/-0.1%,1/16W,SMD0402,G | YAGEO CORPORATION COMPONENT | RT0402BRD07169RL | G | PWA BOM | In Old BOM |
|  |  |  | RB04BTP1690 | RES,169Ohm,+/-0.1%,1/16W,SMD0402,G | TA-I TECHNOLOGY CO., LTD. | RB04BTP1690 | G | PWA BOM | In Old BOM |
| 26 | R961,R962,R963,R964,R965,R967,R968,R969,R970,R975,R976,R977,R978,R985,R986,R988,R989,R992,R1003 | 19 | 61100C600-017-G | RES,1KOhm,+/-0.5%,1/16W,G,SMD0402 | KOA SPEER ELECTRONICS, INC. | RN731ETTP1001D25 | G | PWA BOM | In New BOM |
|  |  |  | 61100C603-024-G | RES,1KOhm,+/-0.5%,1/16W,G,SMD0402 | PANASONIC INDUSTRIAL CO.,LTD. | ERA2AED102X | G | PWA BOM | In New BOM |
|  |  |  | 61100C600-029-G | RES,1KOhm,+/-0.5%,1/16W,G,SMD0402 | VISHAY ENTER TECHNO LOGY.INC | MCS04020D1001DE000 | G | PWA BOM | In New BOM |
|  | R961,R962,R963,R964,R965,R967,R968,R969,R970,R975,R976,R977,R978,R985,R986,R988,R989,R992,R1003 | 19 | 61100C600-017-G | RES,1KOhm,+/-0.5%,1/16W,G,SMD0402 | KOA SPEER ELECTRONICS, INC. | RN731ETTP1001D25 | G | PWA BOM | In Old BOM |
|  |  |  | ERA2AED102X | RES,1KOhm,+/-0.5%,1/16W,G,SMD0402 | PANASONIC INDUSTRIAL CO.,LTD. | ERA2AED102X | G | PWA BOM | In Old BOM |
|  |  |  | 61100C600-029-G | RES,1KOhm,+/-0.5%,1/16W,G,SMD0402 | VISHAY ENTER TECHNO LOGY.INC | MCS04020D1001DE000 | G | PWA BOM | In Old BOM |
| 27 | R1769,R1770 | 2 | 610130300-017-G | RES,60.4 Ohm,+/-1%,1/20W,G,SMD0201 | KOA SPEER ELECTRONICS, INC. | RK73H1HTTC60R4F | G | PWA BOM | In New BOM |
|  |  |  | 610130300-024-G | RES,60.4 Ohm,+/-1%,1/20W,G,SMD0201 | PANASONIC INDUSTRIAL CO.,LTD. | ERJ1GNF60R4C | G | PWA BOM | In New BOM |
|  |  |  | 610130300-029-G | RES,60.4 Ohm,+/-1%,1/20W,G,SMD0201 | VISHAY ENTER TECHNO LOGY.INC | CRCW020160R4FKED | G | PWA BOM | In New BOM |
|  | R1769,R1770 | 2 | 610130300-017-G | RES,60.4 Ohm,+/-1%,1/20W,G,SMD0201 | KOA SPEER ELECTRONICS, INC. | RK73H1HTTC60R4F | G | PWA BOM | In Old BOM |
|  |  |  | 610130300-024-G | RES,60.4 Ohm,+/-1%,1/20W,G,SMD0201 | PANASONIC INDUSTRIAL CO.,LTD. | ERJ1GNF60R4C | G | PWA BOM | In Old BOM |
|  |  |  | CRCW020160R4FKED | RES,60.4 Ohm,+/-1%,1/20W,G,SMD0201 | VISHAY ENTER TECHNO LOGY.INC | CRCW020160R4FKED | G | PWA BOM | In Old BOM |
| 28 | U17 | 1 | 420212A00-216-G | DRAM,MT40A512M16JY-083E:B,1.2V,512M*16,1.2GHz,G,FBGA-96,SMD | MICRON SEMICONDUCTOR ASIA PTE.LTD. | MT40A512M16JY-083E:B | G | PWA BOM | In New BOM |
|  |  |  | 420214J00-220-G | DRAM,H5AN8G6NAFR-UHC,1.2V,8G,1.2GHz,G,FBGA-96,SMD | SK HYNIX | H5AN8G6NAFR-UHC | G | PWA BOM | In New BOM |
|  | U17 | 1 | 420212A00-216-G | DRAM,MT40A512M16JY-083E:B,1.2V,512M*16,1.2GHz,G,FBGA-96,SMD | MICRON SEMICONDUCTOR ASIA PTE.LTD. | MT40A512M16JY-083E:B | G | PWA BOM | In Old BOM |
|  |  |  | H5AN8G6NAFR-UHC | DRAM,1.2V,512M*16,1.2GHz,G,FBGA-96,SMD | SK HYNIX | H5AN8G6NAFR-UHC | G | PWA BOM | In Old BOM |
| 29 | U24 | 1 | 41050DL00-233-G | Flash,MX25L6445EMI-10G,2.7~3.6V,64M,SPI,G,SOP-16,SMD | MACRONIX INTERNATIONAL CO.,LTD. | MX25L6445EMI-10G | G | PWA BOM | In New BOM |
|  |  |  | 41050SF00-233-G | Flash,MX25L6435EMI-10G,2.7~3.6V,64M,SPI,G,SOP-16,SMD | MACRONIX INTERNATIONAL CO.,LTD. | MX25L6435EMI-10G | G | PWA BOM | In New BOM |
|  | U24 | 1 | 41050DL00-233-G | Flash,MX25L6445EMI-10G,2.7~3.6V,64M,SPI,G,SOP-16,SMD | MACRONIX INTERNATIONAL CO.,LTD. | MX25L6445EMI-10G | G | PWA BOM | In Old BOM |
|  |  |  | 41050DW00-396-G | Flash,S25FL064P0XMFI001,2.7~3.6V,64M,SPI,G,SO-16,SMD | SPANSION INTERNATIONAL LLC | S25FL064P0XMFI001 | G | PWA BOM | In Old BOM |
|  |  |  | W25Q64JVSFIM | Flash,2.7~3.6V,64M,SPI,G,SOP-16,SMD | WINBOND | W25Q64JVSFIM | G | PWA BOM | In Old BOM |
|  |  |  | 41050SF00-233-G | Flash,MX25L6435EMI-10G,2.7~3.6V,64M,SPI,G,SOP-16,SMD | MACRONIX INTERNATIONAL CO.,LTD. | MX25L6435EMI-10G | G | PWA BOM | In Old BOM |
| 30 | U83,U101,U102 | 3 | 310500F00-031-G | IC,Buffer,74LVC07APW,1.65~5.5V,G,TSSOP-14,SMD | NXP SEMICONDUCTORS | 74LVC07APW | G | PWA BOM | In New BOM |
|  |  |  | 31050LF00-237-G | IC,Buffer,74LVC07AT14-13,1.65V~5.5V,G,TSSOP-14,SMD | DIODES INCORPORATION | 74LVC07AT14-13 | G | PWA BOM | In New BOM |
|  | U83,U101,U102 | 3 | 310500F00-031-G | IC,Buffer,74LVC07APW,1.65~5.5V,G,TSSOP-14,SMD | NXP SEMICONDUCTORS | 74LVC07APW | G | PWA BOM | In Old BOM |
|  |  |  | 74LVC07AT14-13 | IC,Buffer,74LVC07A,1.65~5.5V,G,TSSOP-14,SMD | DIODES INCORPORATION | 74LVC07AT14-13 | G | PWA BOM | In Old BOM |
| 31 | U110 | 1 | 330103N00-426-G | IC,Optocoupler,PS2811-1-F3-A,G,SSOP-4,SMD | RENESAS TECHNOLOGY AMERICA INC | PS2811-1-F3-A | G | PWA BOM | In New BOM |
|  |  |  | 330102900-289-G | OPTO-IC,ISOL,LTV-217-G,SSOP,4P,G | LITE-ON TECHNOLOGY CORPORATION | LTV-217-G | G | PWA BOM | In New BOM |
|  |  |  | 330103T00-029-G | IC,Optocoupler,VOS618A-3X001T,G,SSOP-4,SMD | VISHAY ENTER TECHNO LOGY.INC | VOS618A-3X001T | G | PWA BOM | In New BOM |
|  | U110 | 1 | 330103N00-426-G | IC,Optocoupler,PS2811-1-F3-A,G,SSOP-4,SMD | RENESAS TECHNOLOGY AMERICA INC | PS2811-1-F3-A | G | PWA BOM | In Old BOM |
|  |  |  | 330102900-289-G | OPTO-IC,ISOL,LTV-217-G,SSOP,4P,G | LITE-ON TECHNOLOGY CORPORATION | LTV-217-G | G | PWA BOM | In Old BOM |
|  |  |  | VOS618A-3T | OPTO-IC,VOS618A-3T,SSOP,4P,G | VISHAY ENTER TECHNO LOGY.INC | VOS618A-3T | G | PWA BOM | In Old BOM |
| 32 | U171 | 1 | 31050KL00-031-G | IC,Buffer,74HC75PW,2.0V~6.0V,G,TSSOP-16,SMD | NXP SEMICONDUCTORS | 74HC75PW | G | PWA BOM | In New BOM |
|  |  |  | 311007400-183-G | IC,Translator,CD74HC75PWRG4,2V~6V,G,TSSOP-16,SMD | Texas Instruments | CD74HC75PWRG4 | G | PWA BOM | In New BOM |
|  | U171 | 1 | 31050KL00-031-G | IC,Buffer,74HC75PW,2.0V~6.0V,G,TSSOP-16,SMD | NXP SEMICONDUCTORS | 74HC75PW | G | PWA BOM | In Old BOM |
|  |  |  | CD74HC75PWRG4 | IC,Buffer,CD74HC75PWRG4,2.0V~6.0V,G,TSSOP-16,SMD | Texas Instruments | CD74HC75PWRG4 | G | PWA BOM | In Old BOM |
| 33 | X2 | 1 | 71010SY00-107-G | XTAL,25MHz,+/-30ppm,20pF,G,SMD | DAISHINKU CORPORATION/DAISHINKU SINGAPORE PTE LTD/KDS | 1Y725000CC1G | G | PWA BOM | In New BOM |
|  |  |  | 71012JL00-873-G | XTAL,25MHz,+/-30ppm,20pF,G,SMD-2P | KYOCERA ELCO CORPORATION | CX5032GA25000R0KDQZ1 | G | PWA BOM | In New BOM |
|  | X2 | 1 | 71010SY00-107-G | XTAL,25MHz,+/-30ppm,20pF,G,SMD | DAISHINKU CORPORATION/DAISHINKU SINGAPORE PTE LTD/KDS | 1Y725000CC1G | G | PWA BOM | In Old BOM |
|  |  |  | CX5032GA25000R0KDQ | XTAL,25MHz,+/-30ppm,20pF,G,SMD-2P | Kyocera | CX5032GA25000R0KDQZ1 | G | PWA BOM | In Old BOM |
| 34 | X3 | 1 | 710113800-100-G | XTAL,24MHz,+/-30ppm,20pF,G,SMD | TXC CORPORATION | 7B24000038 | G | PWA BOM | In New BOM |
|  |  |  | 71012JK00-873-G | XTAL,24MHz,+/-30ppm,20pF,G,SMD | KYOCERA ELCO CORPORATION | CX5032SB24000R0KZQ01 | G | PWA BOM | In New BOM |
|  | X3 | 1 | 710113800-100-G | XTAL,24MHz,+/-30ppm,20pF,G,SMD | TXC CORPORATION | 7B24000038 | G | PWA BOM | In Old BOM |
|  |  |  | CX5032SB24000R0KZQ | XTAL,24MHz,+/-30ppm,20pF,G,SMD | Kyocera | CX5032SB24000R0KZQ01 | G | PWA BOM | In Old BOM |
| 35 | X6 | 1 | 710106900-162-G | XTAL,32.768KHz,+/-20ppm,12.5pF,G,SMD | EPSON ELECTRONICS AMERICA,INC. | Q13FC1350000400 | G | PWA BOM | In New BOM |
|  |  |  | 710110M00-873-G | XTAL,32.768KHz,+/-20ppm,12.5pF,G,SMD | KYOCERA ELCO CORPORATION | ST3215SB32768H5HPWAA | G | PWA BOM | In New BOM |
|  |  |  | 710123400-061-G | XTAL,32.768KHz,+/-20ppm,12.5pF,G,SMD | TAITIEN | 06172-W-052-3 | G | PWA BOM | In New BOM |
|  | X6 | 1 | 710106900-162-G | XTAL,32.768KHz,+/-20ppm,12.5pF,G,SMD | EPSON ELECTRONICS AMERICA,INC. | Q13FC1350000400 | G | PWA BOM | In Old BOM |
|  |  |  | ST3215SB32768H5HPW | XTAL,32.768KHz,+/-20ppm,12.5pF,G,SMD | Kyocera | ST3215SB32768H5HPWAA | G | PWA BOM | In Old BOM |
|  |  |  | 710123400-061-G | XTAL,32.768KHz,+/-20ppm,12.5pF,G,SMD | TAITIEN | 06172-W-052-3 | G | PWA BOM | In Old BOM |
| 36 | Y2 | 1 | 71020Q600-16G-G | OSC,50MHz,50ppm,3.3V,G,SMD | SiTime Corporation | SIT1602AC-23-33E-50.000000T | G | PWA BOM | In New BOM |
|  |  |  | 71012DA00-100-G | OSC,50MHz,+/-25ppm,15pF,G,SMD | TXC CORPORATION | 7X50000015 | G | PWA BOM | In New BOM |
|  |  |  | 710216Q00-098-G | OSC,50MHz,+/-50ppm,3.3V,15pF,G,SMD | HARMONY (HELE) | SSW050000I3CHE-ST7R2 | G | PWA BOM | In New BOM |
|  |  |  | 710216P00-873-G | OSC,50MHz,+/-50ppm,3.3V,15pF,G,SMD | KYOCERA ELCO CORPORATION | KC3225K50.0000C1GE00 | G | PWA BOM | In New BOM |
|  | Y2 | 1 | 71020Q600-16G-G | OSC,50MHz,50ppm,3.3V,G,SMD | SiTime Corporation | SIT1602AC-23-33E-50.000000T | G | PWA BOM | In Old BOM |
|  |  |  | 71012DA00-100-G | OSC,50MHz,+/-25ppm,15pF,G,SMD | TXC CORPORATION | 7X50000015 | G | PWA BOM | In Old BOM |
|  |  |  | SSW050000I3CHE | OSC,50MHz,50ppm,3.3V,G,SMD | HARMONY (HELE) | SSW050000I3CHE-ST7R2 | G | PWA BOM | In Old BOM |
|  |  |  | KC3225K50.0000C1GE | OSC,50MHz,50ppm,3.3V,G,SMD | Kyocera | KC3225K50.0000C1GE00 | G | PWA BOM | In Old BOM |
| 37 | Y4 | 1 | 71020KL00-100-G | OSC,33MHz,+/-50ppm,3.3V,15pF,G,SMD | TXC CORPORATION | 7X33000013 | G | PWA BOM | In New BOM |
|  |  |  | 710211800-967-G | OSC,33MHz,+/-50ppm,3.3V,15pF,G,SMD | eCERA | FK3300011 | G | PWA BOM | In New BOM |
|  |  |  | 710216N00-873-G | OSC,33MHz,+/-50ppm,3.3V,15pF,G,SMD | KYOCERA ELCO CORPORATION | KC3225K33.0000C10E00 | G | PWA BOM | In New BOM |
|  | Y4 | 1 | 71020KL00-100-G | OSC,33MHz,+/-50ppm,3.3V,15pF,G,SMD | TXC CORPORATION | 7X33000013 | G | PWA BOM | In Old BOM |
|  |  |  | 710211800-967-G | OSC,33MHz,+/-50ppm,3.3V,15pF,G,SMD | eCERA | FK3300011 | G | PWA BOM | In Old BOM |
|  |  |  | KC3225K33.0000C10E | OSC,33MHz,+/-50ppm,3.3V,15pF,G,SMD | Kyocera | KC3225K33.0000C10E00 | G | PWA BOM | In Old BOM |
| 38 | J19,J20,J21,J22 | 4 | 340604M00-600-G | CONN,Header,Friction,1X3,V/T,Ivo,2.54mm,G,DIP-3 | FOXCONN TECHNOLOGY CO.,LTD. | HF2803E-P1 | G | PWA BOM | In New BOM |
|  |  |  | 3406AYL00-GRT-G | CONN,Header,WTB,1X3,V/T,Whi,2.54mm,G/F,G,DIP-3 | PINREX TECHNOLOGY CORP. | 744-81-03GW10 | G | PWA BOM | In New BOM |
|  |  |  | 3406AYF00-637-G | CONN,Header,WTB,1X3,V/T,Whi,2.54mm,G,DIP-3 | LONG SHOUNG CO.,LTD. | 2111110300-0212 | G | PWA BOM | In New BOM |
|  |  |  | 34060G600-317-G | Header&Socket Connector,22-23-2031,Wire-to-Board Header,3,DIP,NYLON,2.54mm,200u",White,G | MOLEX INCORPORATED | 22-23-2031 | G | PWA BOM | In New BOM |
|  | J19,J20,J21,J22 | 4 | 340604M00-600-G | CONN,Header,Friction,1X3,V/T,Ivo,2.54mm,G,DIP-3 | FOXCONN TECHNOLOGY CO.,LTD. | HF2803E-P1 | G | PWA BOM | In Old BOM |
|  |  |  | 744-81-03GW10 | CONN,Header,Friction,1X3,V/T,2.54mm,G,DIP-3 | PINREX TECHNOLOGY CORP. | 744-81-03GW10 | G | PWA BOM | In Old BOM |
|  |  |  | 2111110300-0212 | CONN,Header,Friction,1X3,V/T,2.54mm,G,DIP-3 | LONG SHOUNG CO.,LTD. | 2111110300-0212 | G | PWA BOM | In Old BOM |
|  |  |  | 22-23-2031 | CONN,Header,Friction,1X3,V/T,2.54mm,G,DIP-3 | MOLEX INCORPORATED | 22-23-2031 | G | PWA BOM | In Old BOM |
| 39 | J27 | 1 | 3406AMV00-317-G | CONN,Header,MINFIT,2X4,V/T,Bla,10mm,30u,G,DIP-8 | MOLEX INCORPORATED | 42819-4233 | G | PWA BOM | In New BOM |
|  |  |  | 3406AYH00-971-G | Header&Socket Connector,C23709-10433-Y,Power Connector,4,DIP,LCP,10mm,30u",Black,G | ALLTOP TECHNOLOGY CO.,LTD | C23709-10433-Y | G | PWA BOM | In New BOM |
|  | J27 | 1 | 3406AMV00-317-G | CONN,Header,MINFIT,2X4,V/T,Bla,10mm,30u,G,DIP-8 | MOLEX INCORPORATED | 42819-4233 | G | PWA BOM | In Old BOM |
|  |  |  | 3406AYH00-971-G | Header&Socket Connector,C23709-10433-Y,Power Connector,4,DIP,LCP,10mm,30u",Black,G | ALLTOP TECHNOLOGY CO.,LTD | C23709-10433-Y |  | PWA BOM | In Old BOM |
| 40 | J35,J37,J39,J42,J45 | 5 | 3406AQH00-317-G | CONN,Header,Pin Header,1X6,V/T,Bla,2.54mm,G,SMD-6 | MOLEX INCORPORATED | 87898-0656 | G | PWA BOM | In New BOM |
|  |  |  | 3406BAS00-245-G | CONN,Header,Pin Header,1X6,V/T,Bla,2.54mm,G,SMD-6 | AMPHENOL SHANGHAI CORP. | G800MR302032HR | G | PWA BOM | In New BOM |
|  |  |  | 3406A9F00-GRT-G | Header&Socket Connector,212-91-06GBE2,Pin Header,6,SMD,NY6T,2.54mm,3u",Black,G | PINREX TECHNOLOGY CORP. | 212-91-06GBE2 | G | PWA BOM | In New BOM |
|  | J35,J37,J39,J42,J45 | 5 | 3406AQH00-317-G | CONN,Header,Pin Header,1X6,V/T,Bla,2.54mm,G,SMD-6 | MOLEX INCORPORATED | 87898-0656 | G | PWA BOM | In Old BOM |
|  |  |  | G800MR302032HR | Header&Socket Connector,G800MR302032EU,Pin Header,6,DIP,LCP,2.54mm,999.9999u",Black,G | AMPHENOL SHANGHAI CORP. | G800MR302032HR | G | PWA BOM | In Old BOM |
|  |  |  | 3406A9F00-GRT-G | Header&Socket Connector,212-91-06GBE2,Pin Header,6,SMD,NY6T,2.54mm,3u",Black,G | PINREX TECHNOLOGY CORP. | 212-91-06GBE2 | G | PWA BOM | In Old BOM |
| 41 | PBAR65,PAAR65 | 2 | TLRH3APTTE20L0F | RES,20mOhm,+/-1%,2W,G,SMD2512 | KOA SPEER ELECTRONICS, INC. | TLRH3APTTE20L0F | G | PWA BOM | In New BOM |
|  |  |  | LRMAP2512-R02FT4 | RES,20mOhm,+/-1%,2W,G,SMD2512 | INTERNATIONAL RESISTIVE COMPANY, INC. | LRMAP2512-R02FT4 |  | PWA BOM | In New BOM |
|  | PBAR65,PAAR65 | 2 | TLRH3APTTE20L0F | RES,20mOhm,+/-1%,2W,G,SMD2512 | KOA SPEER ELECTRONICS, INC. | TLRH3APTTE20L0F | G | PWA BOM | In Old BOM |
|  |  |  | LRMAP2512-R01FT4 | RES,20mOhm,+/-1%,2W,G,SMD2512 | INTERNATIONAL RESISTIVE COMPANY, INC. | LRMAP2512-R01FT4 | G | PWA BOM | In Old BOM |
| 42 | PBER65,PAFR65,PAER65,PBFR66 | 4 | SLW1TTE50L0F | RES,50mOhm,+/-1%,1.5W,G,SMD2512 | KOA SPEER ELECTRONICS, INC. | SLW1TTE50L0F | G | PWA BOM | In New BOM |
|  |  |  | LRMAP2512-R05FT4 | RES,50mOhm,+/-1%,1.5W,G,SMD2512 | INTERNATIONAL RESISTIVE COMPANY, INC. | LRMAP2512-R05FT4 |  | PWA BOM | In New BOM |
|  | PBER65,PAFR65,PAER65,PBFR66 | 4 | SLW1TTE50L0F | RES,50mOhm,+/-1%,1.5W,G,SMD2512 | KOA SPEER ELECTRONICS, INC. | SLW1TTE50L0F | G | PWA BOM | In Old BOM |
|  |  |  | LRMAP2512-R05FT4 | RES,50mOhm,+/-1%,1.5W,G,SMD2512 | INTERNATIONAL RESISTIVE COMPANY, INC. | LRMAP2512-R05FT4 | G | PWA BOM | In Old BOM |
| 43 | PBMR65,PAMR65 | 2 | SLW1TTE75L0F | RES,75mOhm,+/-1%,1.5W,G,SMD2512 | KOA SPEER ELECTRONICS, INC. | SLW1TTE75L0F | G | PWA BOM | In New BOM |
|  |  |  | LRMAP2512-R075FT4 | RES,75mOhm,+/-1%,1.5W,G,SMD2512 | INTERNATIONAL RESISTIVE COMPANY, INC. | LRMAP2512-R075FT4 |  | PWA BOM | In New BOM |
|  | PBMR65,PAMR65 | 2 | SLW1TTE75L0F | RES,75mOhm,+/-1%,1.5W,G,SMD2512 | KOA SPEER ELECTRONICS, INC. | SLW1TTE75L0F | G | PWA BOM | In Old BOM |
|  |  |  | LRMAP2512-R075FT4 | RES,75mOhm,+/-1%,1.5W,G,SMD2512 | INTERNATIONAL RESISTIVE COMPANY, INC. | LRMAP2512-R075FT4 | G | PWA BOM | In Old BOM |
| 44 | FS5,FS8,FS11,FS14,FS17,FS19,FS20,FS23,FS24,FS25,FS26 | 11 | 0438005.WRGT | Fuse,Fast acting,32V,5A,G,SMD0603 | LITTELFUSE FAR EAST PTE LTD | 0438005.WRGT | G | PWA BOM | In New BOM |
|  |  |  | 730103M00-088-G | Fuse,Fast acting,32V,5A,SMD0603,G | COOPER BUSSMANN, INC. | CC06H5A-TR | G | PWA BOM | In New BOM |
|  | FS5,FS8,FS11,FS14,FS17,FS19,FS20,FS23,FS24,FS25,FS26 | 11 | 730103M00-086-G | Fuse,Fast acting,32V,5A,G,SMD0603 | LITTELFUSE FAR EAST PTE LTD | 0438005.WR | G | PWA BOM | In Old BOM |
|  |  |  | 730103M00-088-G | Fuse,Fast acting,32V,5A,SMD0603,G | COOPER BUSSMANN, INC. | CC06H5A-TR | G | PWA BOM | In Old BOM |
| 45 | PBMD1,PBFD1,PBED1,PBAD1,PAMD1,PAFD1,PAED1,PAAD1 | 8 | 52030DA00-237-G | DIODE,Schottky,BAT46W-7-F,100V,150mA,G,SOD123-2,SMD | DIODES INEORPORATION | BAT46W-7-F | G | PWA BOM | In New BOM |
|  | PBMD1,PBFD1,PBED1,PBAD1,PAMD1,PAFD1,PAED1,PAAD1 | 8 | 520103B00-185-G | Diode,Rectifier&Switching,MMBD1205,100V,200mA,G,SOT-23-3,SMD | FAIRCHILD SEMICONDUCTOR CORP | MMBD1205 | G | PWA BOM | In Old BOM |
|  |  |  | 52010A100-237-G | Diode,Rectifier&Switching,100V,200mA,G,SOT-23-3,SMD | DIODES INCORPORATION | MMBD3004A-7-F | G | PWA BOM | In Old BOM |
| 46 | PBMU1,PBFU1,PBEU1,PBAU1,PAMU1,PAFU1,PAEU1,PAAU1 | 8 | 320242200-230-G | IC,PWM Controller,ISL68137IRAZ-T,G,QFN-48,SMD | INTERSIL CORPORATION | ISL68137IRAZ-T | G | PWA BOM | In New BOM |
|  | PBMU1,PBFU1,PBEU1,PBAU1,PAMU1,PAFU1,PAEU1,PAAU1 | 8 | ISL68137IRAZ-GG04 | IC,PWM Controller,ISL68137IRAZ-T,G,QFN-48,SMD | INTERSIL CORPORATION | ISL68137IRAZ-GG04 | G | PWA BOM | In Old BOM |
| 47 | R1226,R1502 | 2 | 61011H500-017-G | RES,22 Ohm,+/-1%,1/16W,G,SMD0402 | KOA SPEER ELECTRONICS, INC. | RK73H1ETTP22R0F | G | PWA BOM | In New BOM |
|  |  |  | 61011H500-024-G | RES,22 Ohm,+/-1%,1/16W,G,SMD0402 | PANASONIC INDUSTRIAL CO.,LTD. | ERJ2RKF22R0X | G | PWA BOM | In New BOM |
|  | R1226,R1502 | 2 | 610107A00-017-G | RES,0 Ohm,+/-5%,1/16W,G,SMD0402 | KOA SPEER ELECTRONICS, INC. | RK73Z1ETTP | G | PWA BOM | In Old BOM |
|  |  |  | 610107A00-024-G | RES,0 Ohm,+/-5%,1/16W,G,SMD0402 | PANASONIC INDUSTRIAL CO.,LTD. | ERJ2GE0R00X | G | PWA BOM | In Old BOM |
|  |  |  | 610107A00-029-G | RES,0 Ohm,+/-5%,1/16W,G,SMD0402 | VISHAY ENTER TECHNO LOGY.INC | CRCW04020000Z0ED | G | PWA BOM | In Old BOM |
| 48 | U5 | 1 | 320241C00-183-G | IC,Power Controller,UCD90160RGCR,G,VQFN-64,SMD | TEXAS INSTRUMENTS | UCD90160RGCR | G | PWA BOM | In New BOM |
|  | U5 | 1 | UCD90160RGCR-C10 | IC,Power Controller,UCD90160RGCR,G,VQFN-64,SMD | TEXAS INSTRUMENTS | UCD90160RGCR-C10 | G | PWA BOM | In Old BOM |
| 49 | ED2,ED3 | 2 | SRV05-4ATCT | DIODE,Array-TVS,SRV05-4.TCT,5V,12A,G,SOT23-6,SMD | SEMTECH CORPORATION. | SRV05-4ATCT | G | PWA BOM | In New BOM |
|  | ED2,ED3 | 2 | 521800900-227-G | DIODE,Array-TVS,SRV05-4.TCT,5V,12A,G,SOT23-6,SMD | SEMTECH CORPORATION. | SRV05-4.TCT | G | PWA BOM | In Old BOM |
|  |  |  | 52180C200-086-G | Diode,Array-TVS,SRV05-4HTG,SOT-23,6P,G | LITTELFUSE FAR EAST PTE LTD | SRV05-4HTG | G | PWA BOM | In Old BOM |
| 50 | PBMR34,PAMR34 | 2 | RN731ETTP3160B25 | RES,316 Ohm,+/-0.1%,1/16W,G,SMD0402 | KOA SPEER ELECTRONICS, INC. | RN731ETTP3160B25 | G | PWA BOM | In New BOM |
|  | PBMR34,PAMR34 | 2 | 61011H300-017-G | RES,316 Ohm,+/-1%,1/16W,G,SMD0402 | KOA SPEER ELECTRONICS, INC. | RK73H1ETTP3160F | G | PWA BOM | In Old BOM |
|  |  |  | 61011H300-029-G | RES,316 Ohm,+/-1%,1/16W,G,SMD0402 | VISHAY ENTER TECHNO LOGY.INC | CRCW0402316RFKEDC | G | PWA BOM | In Old BOM |
| ##### Change Revision |  |  |  |  |  |  |  |  |  |
| Sheet | REV OF BOM | CUSTOMER | CUSTOMER P/N | PWA PN | PWA DESCRIPTION | PWA REV | DATE | Remark |  |
| OOOOOOOOOOOOOOOOOOOOOOOOOOOOOOOOOOOOOOOOOOOOOOOOOOOOOOOOOOOOOOOOOOOOOOOOOOOOOOOOOOOOOOOOOO | OOOOOOOOOOOOOOOOOOOOOOOOOOOOOOOOOOOOOOOOOOOOOOOOOOOOOOOOOOOOOOOOOOOOOOOOOOOOOOOOOOOOOOOOOO | OOOOOOOOOOOOOOOOOOOOOOOOOOOOOOOOOOOOOOOOOOOOOOOOOOOOOOOOOOOOOOOOOOOOOOOOOOOOOOOOOOOOOOOOOO | OOOOOOOOOOOOOOOOOOOOOOOOOOOOOOOOOOOOOOOOOOOOOOOOOOOOOOOOOOOOOOOOOOOOOOOOOOOOOOOOOOOOOOOOOO | OOOOOOOOOOOOOOOOOOOOOOOOOOOOOOOOOOOOOOOOOOOOOOOOOOOOOOOOOOOOOOOOOOOOOOOOOOOOOOOOOOOOOOOOOO | OOOOOOOOOOOOOOOOOOOOOOOOOOOOOOOOOOOOOOOOOOOOOOOOOOOOOOOOOOOOOOOOOOOOOOOOOOOOOOOOOOOOOOOOOO | OOOOOOOOOOOOOOOOOOOOOOOOOOOOOOOOOOOOOOOOOOOOOOOOOOOOOOOOOOOOOOOOOOOOOOOOOOOOOOOOOOOOOOOOOO | OOOOOOOOOOOOOOOOOOOOOOOOOOOOOOOOOOOOOOOOOOOOOOOOOOOOOOOOOOOOOOOOOOOOOOOOOOOOOOOOOOOOOOOOOO | OOOOOOOOOOOOOOOOOOOOOOOOOOOOOOOOOOOOOOOOOOOOOOOOOOOOOOOOOOOOOOOOOOOOOOOOOOOOOOOOOOOOOOOOOO | OOOOOOOOOOOOOOOOOOOOOOOOOOOOOOOOOOOOOOOOOOOOOOOOOOOOOOOOOOOOOOOOOOOOOOOOOOOOOOOOOOOOOOOOOO |
| Second Source Change |  |  |  |  |  |  |  |  |  |
| Item | Location | Change Type | Foxconn P/N | Part Description | Manufacturer Full Name | Manufacturer P/N | RoHS | Sheet |  |
| 1 | PBMC6,PBFC6,PBEC6,PBAC6,PAMC6,PAFC6,PAEC6,PAAC6 |  | 62011DQ00-015-G | CAP,27nF,+/-10%,X7R,25V,G,SMD0402 | MURATA ELEC. NORTH AMERICA | GRM155R71E273KA88D | G | PWA BOM |  |
|  |  | ADD | 62011DQ00-025-G | CAP,27nF,+/-10%,X7R,25V,G,SMD0402 | KEMET ELECTRONICS CORPORATION | C0402C273K3RAC | G | PWA BOM |  |
|  |  | Delete | C0402C273K3RAC | CAP,27nF,+/-10%,X7R,25V,G,SMD0402 | KEMET ELECTRONICS CORPORATION | C0402C273K3RAC | G | PWA BOM |  |
| 2 | PSUFS1,PBAFS1,PAAFS1,PSUFS2 |  | 730100M00-086-G | Fuse,Very fast acting,125V,10A,G,SMD | LITTELFUSE FAR EAST PTE LTD | 0451010.MRL | G | PWA BOM |  |
|  |  | ADD | 730109A00-088-G | Fuse,Fast acting,125V,10A,G,SMD | COOPER BUSSMANN, INC. | CB61F10A-TR2 | G | PWA BOM |  |
|  |  | Delete | CB61F10A-TR2 | Fuse,CB61F10A-TR2 | COOPER BUSSMANN, INC. | CB61F10A-TR2 | G | PWA BOM |  |
| 3 | PBMR41,PBFR41,PBER41,PBAR41,PAMR41,PAFR41,PAER41,PAAR41 |  | 611008W00-017-G | RES,73.2KOhm,+/-0.1%,1/16W,G,SMD0402 | KOA SPEER ELECTRONICS, INC. | RN731ETTP7322B25 | G | PWA BOM |  |
|  |  | NO | 611008W00-011-G | RES,73.2KOhm,+/-0.1%,1/16W,G,SMD0402 | YAGEO CORPORATION COMPONENT | RT0402BRD0773K2L | G | PWA BOM |  |
|  |  | ADD | 611008W00-024-G | RES,73.2KOhm,+/-0.1%,1/16W,G,SMD0402 | PANASONIC INDUSTRIAL CO.,LTD. | ERA2AEB7322X | G | PWA BOM |  |
|  |  | Delete | ERA2AEB7322X | RES,73.2KOhm,+/-0.1%,1/16W,G,SMD0402 | PANASONIC INDUSTRIAL CO.,LTD. | ERA2AEB7322X | G | PWA BOM |  |
| 4 | PHAR4,PBMR90,PAMR90,PBER92,PBAR92,PAFR92,PAER92,PAAR92,PBFR93,PBAR102,PAAR102 |  | 610130Y00-017-G | RES,1 Ohm,+/-1%,1/3W,G,SMD1206 | KOA SPEER ELECTRONICS, INC. | SR732BTTD1R00F | G | PWA BOM |  |
|  |  | ADD | 610606F00-029-G | RES,1 Ohm,+/-1%,1/3W,G,SMD1206 | VISHAY ENTER TECHNO LOGY.INC | L1206K1R00FNT | G | PWA BOM |  |
|  |  | Delete | L1206K1R00FNT | RES,1 Ohm,+/-1%,1/3W,G,SMD1206 | VISHAY ENTER TECHNO LOGY.INC | L1206K1R00FNT | G | PWA BOM |  |
| 5 | PBMR113,PAMR113,PBER115,PAFR115,PAER115,PBFR116,PBAR119,PAAR119 |  | 61100RU00-017-G | RES,59 Ohm,+/-1%,1/16W,G,SMD0402 | KOA SPEER ELECTRONICS, INC. | RN731ETTP59R0F25 | G | PWA BOM |  |
|  |  | ADD | 611010300-029-G | RES,59 Ohm,+/-1%,1/10W,G,SMD0402 | VISHAY ENTER TECHNO LOGY.INC | TNPW040259R0FEEP | G | PWA BOM |  |
|  |  | Delete | TNPW040259R0FEEP | RES,59 Ohm,+/-1%,1/10W,G,SMD0402 | VISHAY ENTER TECHNO LOGY.INC | TNPW040259R0FEEP | G | PWA BOM |  |
| 6 | PBFL1,PBEL1,PAFL1,PAEL1,PBML2,PAML2 |  | 63035NF00-57M-G | IND,1.5uH@100KHz,+/-10%,12A,6mOhm,SHLD,G,SMD | Eaton Corporation | HCV1206-1R5-R | G | PWA BOM |  |
|  |  | ADD | 630362H00-065-G | IND,1.5uH@100KHz,+/-10%,12A,6.6mOhm,SHLD,G,SMD | DELTA ELECTRONICS INDUSTRIAL CO.,LTD | HMS1360-1R5 | G | PWA BOM |  |
|  |  | Delete | HMS1360-1R5 | IND,1.5uH@100KHz,+/-10%,12A,6mOhm,SHLD,G,SMD | DELTA ELECTRONICS INDUSTRIAL CO.,LTD | HMS1360-1R5 | G | PWA BOM |  |
| 7 | PBNL1,PANL1 |  | 630330G00-088-G | IND,300nH@100KHz,+/-10%,32.5A,304.5uOhm,SHLD,G,SMD | COOPER BUSSMANN, INC. | FP0906R1-R30-R | G | PWA BOM |  |
|  |  | NO | 630332A01-051-G | Coil Ind,Shielded(SHLD),300nH@100KHz,+/-10%,34A,290uOhm,SMD,9.2*6.2*7.8,G | PULSE ELECTRONICS (SINGAPORE) | PA3288.301HLT | G | PWA BOM |  |
|  |  | ADD | 630330G00-129-G | IND,300nH@100KHz,+/-10%,32.5A,290uOhm,SHLD,G,SMD | MAG.LAYERS, SCIENTIFIC-TECHNICS (KUNSHAN) CO., LTD. | MSI-900608-R30K-E | G | PWA BOM |  |
|  |  | Delete | MSI-900608-R30K-E | IND,300nH@100KHz,+/-10%,32.5A,290uOhm,SHLD,G,SMD | MAG.LAYERS, SCIENTIFIC-TECHNICS (KUNSHAN) CO., LTD. | MSI-900608-R30K-E | G | PWA BOM |  |
| 8 | PCIE1,PCIE5 |  | 10061913-102HLF | CONN,PCIE-8X,V/T,Bla,1mm,30u,G,SMD-98 | FCI CONNECTORS HONGKONG LTD. | 10061913-102HLF | G | PWA BOM |  |
|  |  | ADD | 340320R00-278-G | CONN,PCIE-8X,V/T,Bla,1mm,30u,G,SMD-98 | TYCO ELECTRONICS CORPORATION | 2041366-4 | G | PWA BOM |  |
|  |  | Delete | 2041366-4 | CONN,PCIE-8X,V/T,Bla,1mm,30u,G,SMD-98 | TYCO ELECTRONICS CORPORATION | 2041366-4 | G | PWA BOM |  |
| 9 | PCIE2,PCIE3,PCIE4 |  | 10061913-103HLF | CONN,PCIE-16X,V/T,Bla,1mm,30u,G,SMD-164 | FCI CONNECTORS HONGKONG LTD. | 10061913-103HLF | G | PWA BOM |  |
|  |  | ADD | 340320Q00-278-G | CONN,PCIE-16X,V/T,Bla,1mm,30u,G,SMD-164 | TYCO ELECTRONICS CORPORATION | 2041366-6 | G | PWA BOM |  |
|  |  | Delete | 2041366-6 | CONN,PCIE-16X,V/T,Bla,1mm,30u,G,SMD-164 | TYCO ELECTRONICS CORPORATION | 2041366-6 | G | PWA BOM |  |
| 10 | PSPL1,PIPL1,PFPL1,PEPL1 |  | 63032CC00-088-G | IND,1uH@100KHz,+/-20%,11A,10mOhm,SHLD,G,SMD | COOPER BUSSMANN, INC. | HCM0703-1R0-R | G | PWA BOM |  |
|  |  | ADD | 63035CF00-034-G | Coil Ind,Shielded(SHLD),1uH@100KHz,+/-20%,10A,10mOhm,SMD,6.95*6.6*2.8,,,G | CYNTEC CO. LTD | CMMS063T1R0MS | G | PWA BOM |  |
|  |  | ADD | 630362F00-051-G | IND,22nH@100KHz,+/-20%,19A,368uOhm,SHLD,G,SMD | PULSE ELECTRONICS (SINGAPORE) | PA4341.102NLT | G | PWA BOM |  |
|  |  | Delete | CMMS063T1R0MS | IND,CMMS063T1R0MS | CYNTEC CO. LTD | CMMS063T1R0MS | G | PWA BOM |  |
|  |  | Delete | PA4341.102NLT | IND,PA4341.102NLT | PULSE ELECTRONICS (SINGAPORE) | PA4341.102NLT | G | PWA BOM |  |
| 11 | PSPL2,PIPL2,PFPL2,PEPL2 |  | 630341400-088-G | IND,22nH@1MHz,+/-20%,19A,368uOhm,SHLD,G,SMD | COOPER BUSSMANN, INC. | FP0404R1-R022-R | G | PWA BOM |  |
|  |  | ADD | 630362G00-065-G | IND,22nH@100KHz,+/-20%,19A,0.32mOhm,SHLD,G,SMD | DELTA ELECTRONICS INDUSTRIAL CO.,LTD | HCB0430-220 | G | PWA BOM |  |
|  |  | Delete | HCB0430-220 | IND,22nH@1MHz,+/-20%,19A,320uOhm,SHLD,G,SMD | DELTA ELECTRONICS INDUSTRIAL CO.,LTD | HCB0430-220 | G | PWA BOM |  |
| 12 | PQPL2,PFRL2 |  | 63032PP00-088-G | IND,4.7uH@100KHz,+/-20%,5.5A,40mOhm,SHLD,G,SMD | COOPER BUSSMANN, INC. | HCM0703-4R7-R | G | PWA BOM |  |
|  |  | NO | 63030PW00-034-G | Coil Ind,Shielded(SHLD),4.7uH@100KHz,+/-20%,5.5A,40mOhm,SMD,7.3*6.6*3.0,G | CYNTEC CO. LTD | PCMC063T-4R7MN | G | PWA BOM |  |
|  |  | ADD | 63031AD04-129-G | IND,4.7uH@100KHz,+/-20%,5.5A,40mOhm,SHLD,G,SMD | MAG.LAYERS, SCIENTIFIC-TECHNICS (KUNSHAN) CO., LTD. | SPS-06CZ-4R7M-V1 | G | PWA BOM |  |
|  |  | Delete | SPS-06CZ-4R7M-V1 | IND,4.7uH@100KHz,+/-20%,5.5A,40mOhm,SHLD,G,SMD | MAG.LAYERS, SCIENTIFIC-TECHNICS (KUNSHAN) CO., LTD. | SPS-06CZ-4R7M-V1 | G | PWA BOM |  |
| 13 | PFRR19 |  | 61100YB00-017-G | RES,2.94KOhm,+/-0.1%,1/16W,G,SMD0402 | KOA SPEER ELECTRONICS, INC. | RN731ETTP2941B25 | G | PWA BOM |  |
|  |  | NO | 61100YB00-011-G | RES,2.94KOhm,+/-0.1%,1/16W,SMD0402,G | YAGEO CORPORATION COMPONENT | RT0402BRD072K94L | G | PWA BOM |  |
|  |  | ADD | 61100YB00-044-G | RES,2.94KOhm,+/-0.1%,1/16W,G,SMD0402 | TA-I TECHNOLOGY CO., LTD. | RB04BTP2941 | G | PWA BOM |  |
|  |  | Delete | RB04BTP2941 | RES,2.94KOhm,+/-0.1%,1/16W,SMD0402,G | TA-I TECHNOLOGY CO., LTD. | RB04BTP2941 | G | PWA BOM |  |
| 14 | PHAC3 |  | 620133600-015-G | CAP,1nF,+/-5%,X7R,100V,G,SMD0805 | MURATA ELEC. NORTH AMERICA | GRM219R72A102JA01D | G | PWA BOM |  |
|  |  | ADD | 620133600-026-G | CAP,1nF,+/-5%,X7R,100V,G,SMD0805 | SAMSUNG SEMICONDUCTOR | CL21B102JCANNNC | G | PWA BOM |  |
|  |  | Delete | CL21B102JCANNNC | CAP,MLCC,1nF,+/-5%,X7R,100V,SMD0805,G | SAMSUNG SEMICONDUCTOR | CL21B102JCANNNC | G | PWA BOM |  |
| 15 | PHAQ1,PHAQ2,PHAQ3 |  | 51031VY00-031-G | MOS N,PSMN4R8-100BSE,100V,120A,4.8m@10V,G,SOT404-3,SMD | NXP SEMICONDUCTORS | PSMN4R8-100BSE | G | PWA BOM |  |
|  |  | ADD | 51032HE00-185-G | MOS N,FDB047N10,100V,120A,3.9m@10V,G,TO263-3,SMD | FAIRCHILD SEMICONDUCTOR CORP | FDB047N10 | G | PWA BOM |  |
|  |  | NO | SUM70040E-GE3 | MOS N,SUM70040E-GE3,100V,120A,4.0m@10V,G,TO263-3,SMD | VISHAY ENTER TECHNO LOGY.INC | SUM70040E-GE3 | G | PWA BOM |  |
|  |  | Delete | FDB047N10 | MOS N,FDB047N10,100V,120A,3.9m@10V,G,TO263-3,SMD | FAIRCHILD SEMICONDUCTOR CORP | FDB047N10 | G | PWA BOM |  |
| 16 | PHAQ4 |  | 51020A000-031-G | TRANS P,PBHV9115T,150V,1A,G,SOT23-3,SMD | NXP SEMICONDUCTORS | PBHV9115T | G | PWA BOM |  |
|  |  | ADD | 51020BJ00-185-G | Trans PNP,MMBT5401,-150V,-600mA,G,SOT-23-3,SMD | FAIRCHILD SEMICONDUCTOR CORP | MMBT5401 | G | PWA BOM |  |
|  |  | NO | 510204N00-237-G | Trans PNP,MMBT5401-7-F,-150V,-600mA,SOT-23,3P,G | DIODES INCORPORATION | MMBT5401-7-F | G | PWA BOM |  |
|  |  | Delete | MMBT5401 | TRANS P,150V,1A,G,SOT23-3,SMD | FAIRCHILD SEMICONDUCTOR CORP | MMBT5401 | G | PWA BOM |  |
| 17 | PHAQ5,PHAQ6 |  | 51032D100-237-G | MOS N,DMN10H220L-7,100V,1.6A,220m@10V,G,SOT-23-3,SMD | DIODES INCORPORATION | DMN10H220L-7 | G | PWA BOM |  |
|  |  | Delete | FQT7N10LTF | MOS N,FQT7N10LTF,100V,1.7A,220m@10V,G,SOT-23-3,SMD | FAIRCHILD SEMICONDUCTOR CORP | FQT7N10LTF | G | PWA BOM |  |
| 18 | PHAR2 |  | 61100DA00-017-G | RES,33KOhm,+/-0.1%,1/16W,G,SMD0402 | KOA SPEER ELECTRONICS, INC. | RN731ETTP3302B25 | G | PWA BOM |  |
|  |  | NO | 61100DA00-011-G | RES,33KOhm,+/-0.1%,1/16W,G,SMD0402 | YAGEO CORPORATION COMPONENT | RT0402BRD0733KL | G | PWA BOM |  |
|  |  | ADD | 611010100-029-G | RES,33KOhm,+/-0.1%,1/10W,G,SMD0402 | VISHAY | TNPW040233K0BEED | G | PWA BOM |  |
|  |  | Delete | TNPW040233K0BEED | RES,33KOhm,+/-0.1%,1/16W,G,SMD0402 | VISHAY | TNPW040233K0BEED | G | PWA BOM |  |
| 19 | PHAR5 |  | 61100QM00-017-G | RES,100KOhm,+/-0.1%,1/10W,G,SMD0603 | KOA SPEER ELECTRONICS, INC. | RN73H1JTTD1003B25 | G | PWA BOM |  |
|  |  | NO | 61100QM00-011-G | RES,100KOhm,+/-0.1%,1/10W,G,SMD0603 | YAGEO CORPORATION COMPONENT | RT0603BRD07100KL | G | PWA BOM |  |
|  |  | Delete | TNPW0402100KBEED | RES,100KOhm,+/-0.1%,1/10W,G,SMD0603 | VISHAY | TNPW0402100KBEED | G | PWA BOM |  |
| 20 | PSDR19 |  | 61100KM01-017-G | RES,15KOhm,+/-0.1%,1/16W,G,SMD0402 | KOA SPEER ELECTRONICS, INC. | RN73H1ETTP1502B25 | G | PWA BOM |  |
|  |  | ADD | 61100KM02-024-G | RES,15KOhm,+/-0.1%,1/16W,G,SMD0402 | PANASONIC INDUSTRIAL CO.,LTD. | ERA2AEB153X | G | PWA BOM |  |
|  |  | Delete | ERA2AEB153X | RES,15KOhm,+/-0.1%,1/16W,G,SMD0402 | PANASONIC INDUSTRIAL CO.,LTD. | ERA2AEB153X | G | PWA BOM |  |
| 21 | PSUU1 |  | 880302300-065-G | Converter,input 40V~60V,600W,G,Q54SJ12050NNDH,OVAL | DELTA ELECTRONICS INDUSTRIAL CO.,LTD | Q54SJ12050NNDH | G | PWA BOM |  |
|  |  | NO | 880302100-065-G | Converter,input 40V~60V,600W,G,Q54SH12050NNDH | DELTA ELECTRONICS INDUSTRIAL CO.,LTD | Q54SH12050NNDH | G | PWA BOM |  |
|  |  | ADD | 880302A00-462-G | Converter,input 40V~60V,650W,G,BMR458 2130/004 | Ericsson | BMR458 2130/004 | G | PWA BOM |  |
|  |  | Delete | BMR458 2130/004 | Ericsson,BMR458 2130/004 | Ericsson | BMR458 2130/004 | G | PWA BOM |  |
| 22 | QN2,QN3 |  | 510503B00-223-G | MOS N/N,NTZD3154NT1G,20V,0.54A,550m24.5V,G,SOT563-6,SMD | ON SEMICONDUCTOR CORP | NTZD3154NT1G | G | PWA BOM |  |
|  |  | NO | Si1034CX-T1-GE3 | MOS N/N,Si1034CX,20V,0.5A,1ohm@4V,G,EMT-6,SMD | VISHAY ENTER TECHNO LOGY.INC | Si1034CX-T1-GE3 | G | PWA BOM |  |
|  |  | ADD | 51050KW00-131-G | MOS N/N,SSM6N36FE,20V,500mA,0.63@5V,G,ES6-6,SMD | TOSHIBA ELECTRONICS ASIA LTD | SSM6N36FE | G | PWA BOM |  |
|  |  | Delete | SSM6N36FE | MOS N/N,20V,0.54A,550m24.5V,G,SOT563-6,SMD | TOSHIBA ELECTRONICS ASIA LTD | SSM6N36FE | G | PWA BOM |  |
| 23 | R11,R12,R13,R373,R374,R375 |  | 61100Y400-017-G | RES,169 Ohm,+/-0.1%,1/16W,G,SMD0402 | KOA SPEER ELECTRONICS, INC. | RN731ETTP1690B25 | G | PWA BOM |  |
|  |  | NO | 61100Y400-011-G | RES,169Ohm,+/-0.1%,1/16W,SMD0402,G | YAGEO CORPORATION COMPONENT | RT0402BRD07169RL | G | PWA BOM |  |
|  |  | ADD | 61100Y401-044-G | RES,169 Ohm,+/-0.1%,1/16W,G,SMD0402 | TA-I TECHNOLOGY CO., LTD. | RB04BTP1690 | G | PWA BOM |  |
|  |  | Delete | RB04BTP1690 | RES,169Ohm,+/-0.1%,1/16W,SMD0402,G | TA-I TECHNOLOGY CO., LTD. | RB04BTP1690 | G | PWA BOM |  |
| 24 | R961,R962,R963,R964,R965,R967,R968,R969,R970,R975,R976,R977,R978,R985,R986,R988,R989,R992,R1003 |  | 61100C600-017-G | RES,1KOhm,+/-0.5%,1/16W,G,SMD0402 | KOA SPEER ELECTRONICS, INC. | RN731ETTP1001D25 | G | PWA BOM |  |
|  |  | ADD | 61100C603-024-G | RES,1KOhm,+/-0.5%,1/16W,G,SMD0402 | PANASONIC INDUSTRIAL CO.,LTD. | ERA2AED102X | G | PWA BOM |  |
|  |  | NO | 61100C600-029-G | RES,1KOhm,+/-0.5%,1/16W,G,SMD0402 | VISHAY ENTER TECHNO LOGY.INC | MCS04020D1001DE000 | G | PWA BOM |  |
|  |  | Delete | ERA2AED102X | RES,1KOhm,+/-0.5%,1/16W,G,SMD0402 | PANASONIC INDUSTRIAL CO.,LTD. | ERA2AED102X | G | PWA BOM |  |
| 25 | R1769,R1770 |  | 610130300-017-G | RES,60.4 Ohm,+/-1%,1/20W,G,SMD0201 | KOA SPEER ELECTRONICS, INC. | RK73H1HTTC60R4F | G | PWA BOM |  |
|  |  | NO | 610130300-024-G | RES,60.4 Ohm,+/-1%,1/20W,G,SMD0201 | PANASONIC INDUSTRIAL CO.,LTD. | ERJ1GNF60R4C | G | PWA BOM |  |
|  |  | ADD | 610130300-029-G | RES,60.4 Ohm,+/-1%,1/20W,G,SMD0201 | VISHAY ENTER TECHNO LOGY.INC | CRCW020160R4FKED | G | PWA BOM |  |
|  |  | Delete | CRCW020160R4FKED | RES,60.4 Ohm,+/-1%,1/20W,G,SMD0201 | VISHAY ENTER TECHNO LOGY.INC | CRCW020160R4FKED | G | PWA BOM |  |
| 26 | U17 |  | 420212A00-216-G | DRAM,MT40A512M16JY-083E:B,1.2V,512M*16,1.2GHz,G,FBGA-96,SMD | MICRON SEMICONDUCTOR ASIA PTE.LTD. | MT40A512M16JY-083E:B | G | PWA BOM |  |
|  |  | ADD | 420214J00-220-G | DRAM,H5AN8G6NAFR-UHC,1.2V,8G,1.2GHz,G,FBGA-96,SMD | SK HYNIX | H5AN8G6NAFR-UHC | G | PWA BOM |  |
|  |  | Delete | H5AN8G6NAFR-UHC | DRAM,1.2V,512M*16,1.2GHz,G,FBGA-96,SMD | SK HYNIX | H5AN8G6NAFR-UHC | G | PWA BOM |  |
| 27 | U24 |  | 41050DL00-233-G | Flash,MX25L6445EMI-10G,2.7~3.6V,64M,SPI,G,SOP-16,SMD | MACRONIX INTERNATIONAL CO.,LTD. | MX25L6445EMI-10G | G | PWA BOM |  |
|  |  | NO | 41050SF00-233-G | Flash,MX25L6435EMI-10G,2.7~3.6V,64M,SPI,G,SOP-16,SMD | MACRONIX INTERNATIONAL CO.,LTD. | MX25L6435EMI-10G | G | PWA BOM |  |
|  |  | Delete | 41050DW00-396-G | Flash,S25FL064P0XMFI001,2.7~3.6V,64M,SPI,G,SO-16,SMD | SPANSION INTERNATIONAL LLC | S25FL064P0XMFI001 | G | PWA BOM |  |
|  |  | Delete | W25Q64JVSFIM | Flash,2.7~3.6V,64M,SPI,G,SOP-16,SMD | WINBOND | W25Q64JVSFIM | G | PWA BOM |  |
| 28 | U83,U101,U102 |  | 310500F00-031-G | IC,Buffer,74LVC07APW,1.65~5.5V,G,TSSOP-14,SMD | NXP SEMICONDUCTORS | 74LVC07APW | G | PWA BOM |  |
|  |  | ADD | 31050LF00-237-G | IC,Buffer,74LVC07AT14-13,1.65V~5.5V,G,TSSOP-14,SMD | DIODES INCORPORATION | 74LVC07AT14-13 | G | PWA BOM |  |
|  |  | Delete | 74LVC07AT14-13 | IC,Buffer,74LVC07A,1.65~5.5V,G,TSSOP-14,SMD | DIODES INCORPORATION | 74LVC07AT14-13 | G | PWA BOM |  |
| 29 | U110 |  | 330103N00-426-G | IC,Optocoupler,PS2811-1-F3-A,G,SSOP-4,SMD | RENESAS TECHNOLOGY AMERICA INC | PS2811-1-F3-A | G | PWA BOM |  |
|  |  | NO | 330102900-289-G | OPTO-IC,ISOL,LTV-217-G,SSOP,4P,G | LITE-ON TECHNOLOGY CORPORATION | LTV-217-G | G | PWA BOM |  |
|  |  | ADD | 330103T00-029-G | IC,Optocoupler,VOS618A-3X001T,G,SSOP-4,SMD | VISHAY ENTER TECHNO LOGY.INC | VOS618A-3X001T | G | PWA BOM |  |
|  |  | Delete | VOS618A-3T | OPTO-IC,VOS618A-3T,SSOP,4P,G | VISHAY ENTER TECHNO LOGY.INC | VOS618A-3T | G | PWA BOM |  |
| 30 | U171 |  | 31050KL00-031-G | IC,Buffer,74HC75PW,2.0V~6.0V,G,TSSOP-16,SMD | NXP SEMICONDUCTORS | 74HC75PW | G | PWA BOM |  |
|  |  | ADD | 311007400-183-G | IC,Translator,CD74HC75PWRG4,2V~6V,G,TSSOP-16,SMD | Texas Instruments | CD74HC75PWRG4 | G | PWA BOM |  |
|  |  | Delete | CD74HC75PWRG4 | IC,Buffer,CD74HC75PWRG4,2.0V~6.0V,G,TSSOP-16,SMD | Texas Instruments | CD74HC75PWRG4 | G | PWA BOM |  |
| 31 | X2 |  | 71010SY00-107-G | XTAL,25MHz,+/-30ppm,20pF,G,SMD | DAISHINKU CORPORATION/DAISHINKU SINGAPORE PTE LTD/KDS | 1Y725000CC1G | G | PWA BOM |  |
|  |  | ADD | 71012JL00-873-G | XTAL,25MHz,+/-30ppm,20pF,G,SMD-2P | KYOCERA ELCO CORPORATION | CX5032GA25000R0KDQZ1 | G | PWA BOM |  |
|  |  | Delete | CX5032GA25000R0KDQ | XTAL,25MHz,+/-30ppm,20pF,G,SMD-2P | Kyocera | CX5032GA25000R0KDQZ1 | G | PWA BOM |  |
| 32 | X3 |  | 710113800-100-G | XTAL,24MHz,+/-30ppm,20pF,G,SMD | TXC CORPORATION | 7B24000038 | G | PWA BOM |  |
|  |  | ADD | 71012JK00-873-G | XTAL,24MHz,+/-30ppm,20pF,G,SMD | KYOCERA ELCO CORPORATION | CX5032SB24000R0KZQ01 | G | PWA BOM |  |
|  |  | Delete | CX5032SB24000R0KZQ | XTAL,24MHz,+/-30ppm,20pF,G,SMD | Kyocera | CX5032SB24000R0KZQ01 | G | PWA BOM |  |
| 33 | X6 |  | 710106900-162-G | XTAL,32.768KHz,+/-20ppm,12.5pF,G,SMD | EPSON ELECTRONICS AMERICA,INC. | Q13FC1350000400 | G | PWA BOM |  |
|  |  | ADD | 710110M00-873-G | XTAL,32.768KHz,+/-20ppm,12.5pF,G,SMD | KYOCERA ELCO CORPORATION | ST3215SB32768H5HPWAA | G | PWA BOM |  |
|  |  | NO | 710123400-061-G | XTAL,32.768KHz,+/-20ppm,12.5pF,G,SMD | TAITIEN | 06172-W-052-3 | G | PWA BOM |  |
|  |  | Delete | ST3215SB32768H5HPW | XTAL,32.768KHz,+/-20ppm,12.5pF,G,SMD | Kyocera | ST3215SB32768H5HPWAA | G | PWA BOM |  |
| 34 | Y2 |  | 71020Q600-16G-G | OSC,50MHz,50ppm,3.3V,G,SMD | SiTime Corporation | SIT1602AC-23-33E-50.000000T | G | PWA BOM |  |
|  |  | NO | 71012DA00-100-G | OSC,50MHz,+/-25ppm,15pF,G,SMD | TXC CORPORATION | 7X50000015 | G | PWA BOM |  |
|  |  | ADD | 710216Q00-098-G | OSC,50MHz,+/-50ppm,3.3V,15pF,G,SMD | HARMONY (HELE) | SSW050000I3CHE-ST7R2 | G | PWA BOM |  |
|  |  | ADD | 710216P00-873-G | OSC,50MHz,+/-50ppm,3.3V,15pF,G,SMD | KYOCERA ELCO CORPORATION | KC3225K50.0000C1GE00 | G | PWA BOM |  |
|  |  | Delete | SSW050000I3CHE | OSC,50MHz,50ppm,3.3V,G,SMD | HARMONY (HELE) | SSW050000I3CHE-ST7R2 | G | PWA BOM |  |
|  |  | Delete | KC3225K50.0000C1GE | OSC,50MHz,50ppm,3.3V,G,SMD | Kyocera | KC3225K50.0000C1GE00 | G | PWA BOM |  |
| 35 | Y4 |  | 71020KL00-100-G | OSC,33MHz,+/-50ppm,3.3V,15pF,G,SMD | TXC CORPORATION | 7X33000013 | G | PWA BOM |  |
|  |  | NO | 710211800-967-G | OSC,33MHz,+/-50ppm,3.3V,15pF,G,SMD | eCERA | FK3300011 | G | PWA BOM |  |
|  |  | ADD | 710216N00-873-G | OSC,33MHz,+/-50ppm,3.3V,15pF,G,SMD | KYOCERA ELCO CORPORATION | KC3225K33.0000C10E00 | G | PWA BOM |  |
|  |  | Delete | KC3225K33.0000C10E | OSC,33MHz,+/-50ppm,3.3V,15pF,G,SMD | Kyocera | KC3225K33.0000C10E00 | G | PWA BOM |  |
| 36 | J19,J20,J21,J22 |  | 340604M00-600-G | CONN,Header,Friction,1X3,V/T,Ivo,2.54mm,G,DIP-3 | FOXCONN TECHNOLOGY CO.,LTD. | HF2803E-P1 | G | PWA BOM |  |
|  |  | ADD | 3406AYL00-GRT-G | CONN,Header,WTB,1X3,V/T,Whi,2.54mm,G/F,G,DIP-3 | PINREX TECHNOLOGY CORP. | 744-81-03GW10 | G | PWA BOM |  |
|  |  | ADD | 3406AYF00-637-G | CONN,Header,WTB,1X3,V/T,Whi,2.54mm,G,DIP-3 | LONG SHOUNG CO.,LTD. | 2111110300-0212 | G | PWA BOM |  |
|  |  | ADD | 34060G600-317-G | Header&Socket Connector,22-23-2031,Wire-to-Board Header,3,DIP,NYLON,2.54mm,200u",White,G | MOLEX INCORPORATED | 22-23-2031 | G | PWA BOM |  |
|  |  | Delete | 744-81-03GW10 | CONN,Header,Friction,1X3,V/T,2.54mm,G,DIP-3 | PINREX TECHNOLOGY CORP. | 744-81-03GW10 | G | PWA BOM |  |
|  |  | Delete | 2111110300-0212 | CONN,Header,Friction,1X3,V/T,2.54mm,G,DIP-3 | LONG SHOUNG CO.,LTD. | 2111110300-0212 | G | PWA BOM |  |
|  |  | Delete | 22-23-2031 | CONN,Header,Friction,1X3,V/T,2.54mm,G,DIP-3 | MOLEX INCORPORATED | 22-23-2031 | G | PWA BOM |  |
| 37 | J35,J37,J39,J42,J45 |  | 3406AQH00-317-G | CONN,Header,Pin Header,1X6,V/T,Bla,2.54mm,G,SMD-6 | MOLEX INCORPORATED | 87898-0656 | G | PWA BOM |  |
|  |  | ADD | 3406BAS00-245-G | CONN,Header,Pin Header,1X6,V/T,Bla,2.54mm,G,SMD-6 | AMPHENOL SHANGHAI CORP. | G800MR302032HR | G | PWA BOM |  |
|  |  | NO | 3406A9F00-GRT-G | Header&Socket Connector,212-91-06GBE2,Pin Header,6,SMD,NY6T,2.54mm,3u",Black,G | PINREX TECHNOLOGY CORP. | 212-91-06GBE2 | G | PWA BOM |  |
|  |  | Delete | G800MR302032HR | Header&Socket Connector,G800MR302032EU,Pin Header,6,DIP,LCP,2.54mm,999.9999u",Black,G | AMPHENOL SHANGHAI CORP. | G800MR302032HR | G | PWA BOM |  |
| 38 | PBAR65,PAAR65 |  | TLRH3APTTE20L0F | RES,20mOhm,+/-1%,2W,G,SMD2512 | KOA SPEER ELECTRONICS, INC. | TLRH3APTTE20L0F | G | PWA BOM |  |
|  |  | ADD | LRMAP2512-R02FT4 | RES,20mOhm,+/-1%,2W,G,SMD2512 | INTERNATIONAL RESISTIVE COMPANY, INC. | LRMAP2512-R02FT4 |  | PWA BOM |  |
|  |  | Delete | LRMAP2512-R01FT4 | RES,20mOhm,+/-1%,2W,G,SMD2512 | INTERNATIONAL RESISTIVE COMPANY, INC. | LRMAP2512-R01FT4 | G | PWA BOM |  |
| OOOOOOOOOOOOOOOOOOOOOOOOOOOOOOOOOOOOOOOOOOOOOOOOOOOOOOOOOOOOOOOOOOOOOOOOOOOOOOOOOOOOOOOOOO | OOOOOOOOOOOOOOOOOOOOOOOOOOOOOOOOOOOOOOOOOOOOOOOOOOOOOOOOOOOOOOOOOOOOOOOOOOOOOOOOOOOOOOOOOO | OOOOOOOOOOOOOOOOOOOOOOOOOOOOOOOOOOOOOOOOOOOOOOOOOOOOOOOOOOOOOOOOOOOOOOOOOOOOOOOOOOOOOOOOOO | OOOOOOOOOOOOOOOOOOOOOOOOOOOOOOOOOOOOOOOOOOOOOOOOOOOOOOOOOOOOOOOOOOOOOOOOOOOOOOOOOOOOOOOOOO | OOOOOOOOOOOOOOOOOOOOOOOOOOOOOOOOOOOOOOOOOOOOOOOOOOOOOOOOOOOOOOOOOOOOOOOOOOOOOOOOOOOOOOOOOO | OOOOOOOOOOOOOOOOOOOOOOOOOOOOOOOOOOOOOOOOOOOOOOOOOOOOOOOOOOOOOOOOOOOOOOOOOOOOOOOOOOOOOOOOOO | OOOOOOOOOOOOOOOOOOOOOOOOOOOOOOOOOOOOOOOOOOOOOOOOOOOOOOOOOOOOOOOOOOOOOOOOOOOOOOOOOOOOOOOOOO | OOOOOOOOOOOOOOOOOOOOOOOOOOOOOOOOOOOOOOOOOOOOOOOOOOOOOOOOOOOOOOOOOOOOOOOOOOOOOOOOOOOOOOOOOO | OOOOOOOOOOOOOOOOOOOOOOOOOOOOOOOOOOOOOOOOOOOOOOOOOOOOOOOOOOOOOOOOOOOOOOOOOOOOOOOOOOOOOOOOOO | OOOOOOOOOOOOOOOOOOOOOOOOOOOOOOOOOOOOOOOOOOOOOOOOOOOOOOOOOOOOOOOOOOOOOOOOOOOOOOOOOOOOOOOOOO |
| Master Materials Change |  |  |  |  |  |  |  |  |  |
| Item | Foxconn P/N | Orig._Usage | New_Usage | Part Description | Manufacturer Full Name | Manufacturer P/N | RoHS | Location | Sheet |
| 1 | 0438005.WRGT | 0 | 11 | Fuse,Fast acting,32V,5A,G,SMD0603 | LITTELFUSE FAR EAST PTE LTD | 0438005.WRGT | G | (+)FS5,FS8,FS11,FS14,FS17,FS19,FS20,FS23,FS24,FS25,FS26 | PWA BOM |
|  | 730103M00-088-G |  |  | Fuse,Fast acting,32V,5A,SMD0603,G | COOPER BUSSMANN, INC. | CC06H5A-TR |  |  | PWA BOM |
| 2 | 52030DA00-237-G | 0 | 16 | DIODE,Schottky,BAT46W-7-F,100V,150mA,G,SOD123-2,SMD | DIODES INEORPORATION | BAT46W-7-F | G | (+)PBMD1,PBFD1,PBED1,PBAD1,PAMD1,PAFD1,PAED1,PAAD1,PBMD4,PBFD4,PBED4,PAMD4,PAFD4,PAED4,PBAD5,PAAD5 | PWA BOM |
| 3 | 610107A00-017-G | 716 | 714 | RES,0 Ohm,+/-5%,1/16W,G,SMD0402 | KOA SPEER ELECTRONICS, INC. | RK73Z1ETTP | G | (+)R1850 (-)R1226,R1502,R1556 | PWA BOM |
|  | 610107A00-024-G |  |  | RES,0 Ohm,+/-5%,1/16W,G,SMD0402 | PANASONIC INDUSTRIAL CO.,LTD. | ERJ2GE0R00X |  |  | PWA BOM |
|  | 610107A00-029-G |  |  | RES,0 Ohm,+/-5%,1/16W,G,SMD0402 | VISHAY ENTER TECHNO LOGY.INC | CRCW04020000Z0ED |  |  | PWA BOM |
| 4 | 320242200-230-G | 0 | 8 | IC,PWM Controller,ISL68137IRAZ-T,G,QFN-48,SMD | INTERSIL CORPORATION | ISL68137IRAZ-T | G | (+)PBMU1,PBFU1,PBEU1,PBAU1,PAMU1,PAFU1,PAEU1,PAAU1 | PWA BOM |
| 5 | 61011H300-017-G | 6 | 4 | RES,316 Ohm,+/-1%,1/16W,G,SMD0402 | KOA SPEER ELECTRONICS, INC. | RK73H1ETTP3160F | G | (-)PBMR34,PAMR34 | PWA BOM |
|  | 61011H300-029-G |  |  | RES,316 Ohm,+/-1%,1/16W,G,SMD0402 | VISHAY ENTER TECHNO LOGY.INC | CRCW0402316RFKEDC |  |  | PWA BOM |
| 6 | 61011H500-017-G | 22 | 24 | RES,22 Ohm,+/-1%,1/16W,G,SMD0402 | KOA SPEER ELECTRONICS, INC. | RK73H1ETTP22R0F | G | (+)R1226,R1502 | PWA BOM |
|  | 61011H500-024-G |  |  | RES,22 Ohm,+/-1%,1/16W,G,SMD0402 | PANASONIC INDUSTRIAL CO.,LTD. | ERJ2RKF22R0X |  |  | PWA BOM |
| 7 | 320241C00-183-G | 0 | 1 | IC,Power Controller,UCD90160RGCR,G,VQFN-64,SMD | TEXAS INSTRUMENTS | UCD90160RGCR | G | (+)U5 | PWA BOM |
| 8 | SRV05-4ATCT | 0 | 2 | DIODE,Array-TVS,SRV05-4.TCT,5V,12A,G,SOT23-6,SMD | SEMTECH CORPORATION. | SRV05-4ATCT | G | (+)ED2,ED3 | PWA BOM |
| 9 | 34068LN00-317-G | 11 | 10 | CONN,Header,Pin Header,1X3,V/T,2.54mm,30u,G,SMD-3 | MOLEX INCORPORATED | 87898-0315 | G | (-)J3 | PWA BOM |
|  | 34068HT00-245-G |  |  | CONN,Header,Pin Header,1X3,V/T,Bla,2.54mm,30u,SMD-3 | AMPHENOL SHANGHAI CORP. | G800MU305010EU |  |  | PWA BOM |
|  | 34068GU00-309-G |  |  | CONN,Header,Pin Header,1X3,V/T,Bla,2.54mm,30u,SMD-3 | SAMTEC INC. | TSM-103-01-S-SV-P-TR |  |  | PWA BOM |
| 10 | RN731ETTP3160B25 | 0 | 2 | RES,316 Ohm,+/-0.1%,1/16W,G,SMD0402 | KOA SPEER ELECTRONICS, INC. | RN731ETTP3160B25 | G | (+)PBMR34,PAMR34 | PWA BOM |
| 11 | 620108B00-015-G | 2 | 0 | CAP,120pF,+/-5%,NPO(C0G),50V,G,SMD0402 | MURATA ELEC. NORTH AMERICA | GRM1555C1H121J | G | (-)C2184,C2185 | PWA BOM |
|  | 620108B00-023-G |  |  | CAP,120pF,+/-5%,NPO(C0G),50V,G,SMD0402 | TAIYO ELECTRIC IND.CO.LTD | UMK105CG121JV-F |  |  | PWA BOM |
|  | 620108B00-026-G |  |  | CAP,120pF,+/-5%,NPO(C0G),50V,G,SMD0402 | SAMSUNG SEMICONDUCTOR | CL05C121JB5NNNC |  |  | PWA BOM |
| 12 | 521800900-227-G | 3 | 0 | DIODE,Array-TVS,SRV05-4.TCT,5V,12A,G,SOT23-6,SMD | SEMTECH CORPORATION. | SRV05-4.TCT | G | (-)ED1,ED2,ED3 | PWA BOM |
|  | 52180C200-086-G |  |  | Diode,Array-TVS,SRV05-4HTG,SOT-23,6P,G | LITTELFUSE FAR EAST PTE LTD | SRV05-4HTG |  |  | PWA BOM |
| 13 | 730103M00-086-G | 11 | 0 | Fuse,Fast acting,32V,5A,G,SMD0603 | LITTELFUSE FAR EAST PTE LTD | 0438005.WR | G | (-)FS5,FS8,FS11,FS14,FS17,FS19,FS20,FS23,FS24,FS25,FS26 | PWA BOM |
|  | 730103M00-088-G |  |  | Fuse,Fast acting,32V,5A,SMD0603,G | COOPER BUSSMANN, INC. | CC06H5A-TR |  |  | PWA BOM |
| 14 | 520103B00-185-G | 8 | 0 | Diode,Rectifier&Switching,MMBD1205,100V,200mA,G,SOT-23-3,SMD | FAIRCHILD SEMICONDUCTOR CORP | MMBD1205 | G | (-)PBMD1,PBFD1,PBED1,PBAD1,PAMD1,PAFD1,PAED1,PAAD1 | PWA BOM |
|  | 52010A100-237-G |  |  | Diode,Rectifier&Switching,100V,200mA,G,SOT-23-3,SMD | DIODES INCORPORATION | MMBD3004A-7-F |  |  | PWA BOM |
| 15 | ISL68137IRAZ-GG04 | 8 | 0 | IC,PWM Controller,ISL68137IRAZ-T,G,QFN-48,SMD | INTERSIL CORPORATION | ISL68137IRAZ-GG04 | G | (-)PBMU1,PBFU1,PBEU1,PBAU1,PAMU1,PAFU1,PAEU1,PAAU1 | PWA BOM |
| 16 | 610124C00-017-G | 2 | 0 | RES,57.6 Ohm,+/-1%,1/16W,G,SMD0402 | KOA SPEER ELECTRONICS, INC. | RK73H1ETTP57R6F | G | (-)R1838,R1839 | PWA BOM |
|  | 610124C00-024-G |  |  | RES,57.6 Ohm,+/-1%,1/16W,G,SMD0402 | PANASONIC INDUSTRIAL CO.,LTD. | ERJ2RKF57R6X |  |  | PWA BOM |
| 17 | UCD90160RGCR-C10 | 1 | 0 | IC,Power Controller,UCD90160RGCR,G,VQFN-64,SMD | TEXAS INSTRUMENTS | UCD90160RGCR-C10 | G | (-)U5 | PWA BOM |
| 18 | 34080F500-653-G | 1 | 0 | CONN,Switch,slide,25mA,24V,G,SMD-8 | DIPTRONICS MANUFACTURING INC. | DHN-04F-T-V-T/R | G | (-)PSUSW1 | PWA BOM |
| OOOOOOOOOOOOOOOOOOOOOOOOOOOOOOOOOOOOOOOOOOOOOOOOOOOOOOOOOOOOOOOOOOOOOOOOOOOOOOOOOOOOOOOOOO | OOOOOOOOOOOOOOOOOOOOOOOOOOOOOOOOOOOOOOOOOOOOOOOOOOOOOOOOOOOOOOOOOOOOOOOOOOOOOOOOOOOOOOOOOO | OOOOOOOOOOOOOOOOOOOOOOOOOOOOOOOOOOOOOOOOOOOOOOOOOOOOOOOOOOOOOOOOOOOOOOOOOOOOOOOOOOOOOOOOOO | OOOOOOOOOOOOOOOOOOOOOOOOOOOOOOOOOOOOOOOOOOOOOOOOOOOOOOOOOOOOOOOOOOOOOOOOOOOOOOOOOOOOOOOOOO | OOOOOOOOOOOOOOOOOOOOOOOOOOOOOOOOOOOOOOOOOOOOOOOOOOOOOOOOOOOOOOOOOOOOOOOOOOOOOOOOOOOOOOOOOO | OOOOOOOOOOOOOOOOOOOOOOOOOOOOOOOOOOOOOOOOOOOOOOOOOOOOOOOOOOOOOOOOOOOOOOOOOOOOOOOOOOOOOOOOOO | OOOOOOOOOOOOOOOOOOOOOOOOOOOOOOOOOOOOOOOOOOOOOOOOOOOOOOOOOOOOOOOOOOOOOOOOOOOOOOOOOOOOOOOOOO | OOOOOOOOOOOOOOOOOOOOOOOOOOOOOOOOOOOOOOOOOOOOOOOOOOOOOOOOOOOOOOOOOOOOOOOOOOOOOOOOOOOOOOOOOO | OOOOOOOOOOOOOOOOOOOOOOOOOOOOOOOOOOOOOOOOOOOOOOOOOOOOOOOOOOOOOOOOOOOOOOOOOOOOOOOOOOOOOOOOOO | OOOOOOOOOOOOOOOOOOOOOOOOOOOOOOOOOOOOOOOOOOOOOOOOOOOOOOOOOOOOOOOOOOOOOOOOOOOOOOOOOOOOOOOOOO |
| TLA Parts Change |  |  |  |  |  |  |  |  |  |
| Item | Foxconn P/N | Qty | Part Description | Manufacturer Full Name | Manufacturer P/N | RoHS | Location | Remark | BOM |
| BOM Change List Date:Wed Aug 02 14:43:02 GMT+08:00 2017 |  |  |  |  |  |  |  |  |  |
| New BOM file : E:\barreleye g2\0801\foxbis\new .xls |  |  |  |  |  |  |  |  |  |
| Old BOM file : E:\barreleye g2\0801\foxbis\old .xls |  |  |  |  |  |  |  |  |  |
| ##### Add Parts |  |  |  |  |  |  |  |  |  |
| Item | Location | Qty | Foxconn P/N | Part Description | Manufacturer Full Name | Manufacturer P/N | RoHS | Sheet |  |
| ##### Remove Parts |  |  |  |  |  |  |  |  |  |
| Item | Location | Qty | Foxconn P/N | Part Description | Manufacturer Full Name | Manufacturer P/N | RoHS | Sheet |  |
| ##### Change Parts |  |  |  |  |  |  |  |  |  |
| Item | Location | Qty | Foxconn P/N | Part Description | Manufacturer Full Name | Manufacturer P/N | RoHS | Sheet | Remark |
| 1 | FS5,FS8,FS11,FS14,FS17,FS19,FS20,FS23,FS24,FS25,FS26 | 11 | 0438005.WRGT | Fuse,Fast acting,32V,5A,G,SMD0603 | LITTELFUSE FAR EAST PTE LTD | 0438005.WRGT | G | PWA BOM | In New BOM |
|  |  |  | 730103M00-086-G | Fuse,Fast acting,32V,5A,G,SMD0603 | LITTELFUSE FAR EAST PTE LTD | 0438005.WR | G | PWA BOM | In New BOM |
|  |  |  | 730103M00-088-G | Fuse,Fast acting,32V,5A,SMD0603,G | COOPER BUSSMANN, INC. | CC06H5A-TR | G | PWA BOM | In New BOM |
|  | FS5,FS8,FS11,FS14,FS17,FS19,FS20,FS23,FS24,FS25,FS26 | 11 | 0438005.WRGT | Fuse,Fast acting,32V,5A,G,SMD0603 | LITTELFUSE FAR EAST PTE LTD | 0438005.WRGT | G | PWA BOM | In Old BOM |
|  |  |  | 730103M00-088-G | Fuse,Fast acting,32V,5A,SMD0603,G | COOPER BUSSMANN, INC. | CC06H5A-TR | G | PWA BOM | In Old BOM |
| 2 | ED2,ED3 | 2 | SRV05-4ATCT | DIODE,Array-TVS,SRV05-4.TCT,5V,12A,G,SOT23-6,SMD | SEMTECH CORPORATION. | SRV05-4ATCT | G | PWA BOM | In New BOM |
|  |  |  | 521800900-227-G | DIODE,Array-TVS,SRV05-4.TCT,5V,12A,G,SOT23-6,SMD | SEMTECH CORPORATION. | SRV05-4.TCT | G | PWA BOM | In New BOM |
|  |  |  | 52180C200-086-G | Diode,Array-TVS,SRV05-4HTG,SOT-23,6P,G | LITTELFUSE FAR EAST PTE LTD | SRV05-4HTG | G | PWA BOM | In New BOM |
|  | ED2,ED3 | 2 | SRV05-4ATCT | DIODE,Array-TVS,SRV05-4.TCT,5V,12A,G,SOT23-6,SMD | SEMTECH CORPORATION. | SRV05-4ATCT | G | PWA BOM | In Old BOM |
| ##### Change Revision |  |  |  |  |  |  |  |  |  |
| Sheet | REV OF BOM | CUSTOMER | CUSTOMER P/N | PWA PN | PWA DESCRIPTION | PWA REV | DATE | Remark |  |
| OOOOOOOOOOOOOOOOOOOOOOOOOOOOOOOOOOOOOOOOOOOOOOOOOOOOOOOOOOOOOOOOOOOOOOOOOOOOOOOOOOOOOOOOOO | OOOOOOOOOOOOOOOOOOOOOOOOOOOOOOOOOOOOOOOOOOOOOOOOOOOOOOOOOOOOOOOOOOOOOOOOOOOOOOOOOOOOOOOOOO | OOOOOOOOOOOOOOOOOOOOOOOOOOOOOOOOOOOOOOOOOOOOOOOOOOOOOOOOOOOOOOOOOOOOOOOOOOOOOOOOOOOOOOOOOO | OOOOOOOOOOOOOOOOOOOOOOOOOOOOOOOOOOOOOOOOOOOOOOOOOOOOOOOOOOOOOOOOOOOOOOOOOOOOOOOOOOOOOOOOOO | OOOOOOOOOOOOOOOOOOOOOOOOOOOOOOOOOOOOOOOOOOOOOOOOOOOOOOOOOOOOOOOOOOOOOOOOOOOOOOOOOOOOOOOOOO | OOOOOOOOOOOOOOOOOOOOOOOOOOOOOOOOOOOOOOOOOOOOOOOOOOOOOOOOOOOOOOOOOOOOOOOOOOOOOOOOOOOOOOOOOO | OOOOOOOOOOOOOOOOOOOOOOOOOOOOOOOOOOOOOOOOOOOOOOOOOOOOOOOOOOOOOOOOOOOOOOOOOOOOOOOOOOOOOOOOOO | OOOOOOOOOOOOOOOOOOOOOOOOOOOOOOOOOOOOOOOOOOOOOOOOOOOOOOOOOOOOOOOOOOOOOOOOOOOOOOOOOOOOOOOOOO | OOOOOOOOOOOOOOOOOOOOOOOOOOOOOOOOOOOOOOOOOOOOOOOOOOOOOOOOOOOOOOOOOOOOOOOOOOOOOOOOOOOOOOOOOO | OOOOOOOOOOOOOOOOOOOOOOOOOOOOOOOOOOOOOOOOOOOOOOOOOOOOOOOOOOOOOOOOOOOOOOOOOOOOOOOOOOOOOOOOOO |
| Second Source Change |  |  |  |  |  |  |  |  |  |
| Item | Location | Change Type | Foxconn P/N | Part Description | Manufacturer Full Name | Manufacturer P/N | RoHS | Sheet |  |
| 1 | FS5,FS8,FS11,FS14,FS17,FS19,FS20,FS23,FS24,FS25,FS26 |  | 0438005.WRGT | Fuse,Fast acting,32V,5A,G,SMD0603 | LITTELFUSE FAR EAST PTE LTD | 0438005.WRGT | G | PWA BOM |  |
|  |  | ADD | 730103M00-086-G | Fuse,Fast acting,32V,5A,G,SMD0603 | LITTELFUSE FAR EAST PTE LTD | 0438005.WR | G | PWA BOM |  |
|  |  | NO | 730103M00-088-G | Fuse,Fast acting,32V,5A,SMD0603,G | COOPER BUSSMANN, INC. | CC06H5A-TR | G | PWA BOM |  |
| 2 | ED2,ED3 |  | SRV05-4ATCT | DIODE,Array-TVS,SRV05-4.TCT,5V,12A,G,SOT23-6,SMD | SEMTECH CORPORATION. | SRV05-4ATCT | G | PWA BOM |  |
|  |  | ADD | 521800900-227-G | DIODE,Array-TVS,SRV05-4.TCT,5V,12A,G,SOT23-6,SMD | SEMTECH CORPORATION. | SRV05-4.TCT | G | PWA BOM |  |
|  |  | ADD | 52180C200-086-G | Diode,Array-TVS,SRV05-4HTG,SOT-23,6P,G | LITTELFUSE FAR EAST PTE LTD | SRV05-4HTG | G | PWA BOM |  |
| OOOOOOOOOOOOOOOOOOOOOOOOOOOOOOOOOOOOOOOOOOOOOOOOOOOOOOOOOOOOOOOOOOOOOOOOOOOOOOOOOOOOOOOOOO | OOOOOOOOOOOOOOOOOOOOOOOOOOOOOOOOOOOOOOOOOOOOOOOOOOOOOOOOOOOOOOOOOOOOOOOOOOOOOOOOOOOOOOOOOO | OOOOOOOOOOOOOOOOOOOOOOOOOOOOOOOOOOOOOOOOOOOOOOOOOOOOOOOOOOOOOOOOOOOOOOOOOOOOOOOOOOOOOOOOOO | OOOOOOOOOOOOOOOOOOOOOOOOOOOOOOOOOOOOOOOOOOOOOOOOOOOOOOOOOOOOOOOOOOOOOOOOOOOOOOOOOOOOOOOOOO | OOOOOOOOOOOOOOOOOOOOOOOOOOOOOOOOOOOOOOOOOOOOOOOOOOOOOOOOOOOOOOOOOOOOOOOOOOOOOOOOOOOOOOOOOO | OOOOOOOOOOOOOOOOOOOOOOOOOOOOOOOOOOOOOOOOOOOOOOOOOOOOOOOOOOOOOOOOOOOOOOOOOOOOOOOOOOOOOOOOOO | OOOOOOOOOOOOOOOOOOOOOOOOOOOOOOOOOOOOOOOOOOOOOOOOOOOOOOOOOOOOOOOOOOOOOOOOOOOOOOOOOOOOOOOOOO | OOOOOOOOOOOOOOOOOOOOOOOOOOOOOOOOOOOOOOOOOOOOOOOOOOOOOOOOOOOOOOOOOOOOOOOOOOOOOOOOOOOOOOOOOO | OOOOOOOOOOOOOOOOOOOOOOOOOOOOOOOOOOOOOOOOOOOOOOOOOOOOOOOOOOOOOOOOOOOOOOOOOOOOOOOOOOOOOOOOOO | OOOOOOOOOOOOOOOOOOOOOOOOOOOOOOOOOOOOOOOOOOOOOOOOOOOOOOOOOOOOOOOOOOOOOOOOOOOOOOOOOOOOOOOOOO |
| Master Materials Change |  |  |  |  |  |  |  |  |  |
| Item | Foxconn P/N | Orig._Usage | New_Usage | Part Description | Manufacturer Full Name | Manufacturer P/N | RoHS | Location | Sheet |
| OOOOOOOOOOOOOOOOOOOOOOOOOOOOOOOOOOOOOOOOOOOOOOOOOOOOOOOOOOOOOOOOOOOOOOOOOOOOOOOOOOOOOOOOOO | OOOOOOOOOOOOOOOOOOOOOOOOOOOOOOOOOOOOOOOOOOOOOOOOOOOOOOOOOOOOOOOOOOOOOOOOOOOOOOOOOOOOOOOOOO | OOOOOOOOOOOOOOOOOOOOOOOOOOOOOOOOOOOOOOOOOOOOOOOOOOOOOOOOOOOOOOOOOOOOOOOOOOOOOOOOOOOOOOOOOO | OOOOOOOOOOOOOOOOOOOOOOOOOOOOOOOOOOOOOOOOOOOOOOOOOOOOOOOOOOOOOOOOOOOOOOOOOOOOOOOOOOOOOOOOOO | OOOOOOOOOOOOOOOOOOOOOOOOOOOOOOOOOOOOOOOOOOOOOOOOOOOOOOOOOOOOOOOOOOOOOOOOOOOOOOOOOOOOOOOOOO | OOOOOOOOOOOOOOOOOOOOOOOOOOOOOOOOOOOOOOOOOOOOOOOOOOOOOOOOOOOOOOOOOOOOOOOOOOOOOOOOOOOOOOOOOO | OOOOOOOOOOOOOOOOOOOOOOOOOOOOOOOOOOOOOOOOOOOOOOOOOOOOOOOOOOOOOOOOOOOOOOOOOOOOOOOOOOOOOOOOOO | OOOOOOOOOOOOOOOOOOOOOOOOOOOOOOOOOOOOOOOOOOOOOOOOOOOOOOOOOOOOOOOOOOOOOOOOOOOOOOOOOOOOOOOOOO | OOOOOOOOOOOOOOOOOOOOOOOOOOOOOOOOOOOOOOOOOOOOOOOOOOOOOOOOOOOOOOOOOOOOOOOOOOOOOOOOOOOOOOOOOO | OOOOOOOOOOOOOOOOOOOOOOOOOOOOOOOOOOOOOOOOOOOOOOOOOOOOOOOOOOOOOOOOOOOOOOOOOOOOOOOOOOOOOOOOOO |
| TLA Parts Change |  |  |  |  |  |  |  |  |  |
| Item | Foxconn P/N | Qty | Part Description | Manufacturer Full Name | Manufacturer P/N | RoHS | Location | Remark | BOM |
| BOM Change List Date:Fri Aug 11 10:21:26 GMT+08:00 2017 |  |  |  |  |  |  |  |  |  |
| New BOM file : E:\barreleye g2\0810\foxbis zaius\zaius 0810.xls |  |  |  |  |  |  |  |  |  |
| Old BOM file : E:\barreleye g2\0810\foxbis zaius\zaius 0802.xls |  |  |  |  |  |  |  |  |  |
| ##### Add Parts |  |  |  |  |  |  |  |  |  |
| Item | Location | Qty | Foxconn P/N | Part Description | Manufacturer Full Name | Manufacturer P/N | RoHS | Sheet |  |
| ##### Remove Parts |  |  |  |  |  |  |  |  |  |
| Item | Location | Qty | Foxconn P/N | Part Description | Manufacturer Full Name | Manufacturer P/N | RoHS | Sheet |  |
| 1 | R1093,R1114 | 2 | 61100QH00-017-G | RES,510 Ohm,+/-0.1%,1/16W,G,SMD0402 | KOA SPEER ELECTRONICS, INC. | RN731ETTP5100B25 | G | PWA BOM |  |
|  |  |  | 61100QH00-011-G | RES,510 Ohm,+/-0.1%,1/16W,G,SMD0402 | YAGEO CORPORATION COMPONENT | RT0402BRD07510RL | G | PWA BOM |  |
| ##### Change Parts |  |  |  |  |  |  |  |  |  |
| Item | Location | Qty | Foxconn P/N | Part Description | Manufacturer Full Name | Manufacturer P/N | RoHS | Sheet | Remark |
| 1 | PSUCE1,PBACE1,PAACE1,PSUCE2,PBACE2,PAACE2 | 6 | EEEFK2A680AQ | ECAP,68uF,+/-20%,100V,105C,G,SMD12.5*13.5,ESR<=320mOhm | PANASONIC INDUSTRIAL CO.,LTD. | EEEFK2A680AQ | G | PWA BOM | In New BOM |
|  | PSUCE1,PBACE1,PAACE1,PSUCE2,PBACE2,PAACE2 | 6 | 62111CS00-024-G | ECAP,68uF,+/-20%,100V,105C,G,SMD12.5*13.5,ESR<=320mOhm | PANASONIC INDUSTRIAL CO.,LTD. | EEVFK2A680Q | G | PWA BOM | In Old BOM |
|  |  |  | 62111RR00-025-G | ECAP,68uF,+/-20%,100V,105C,G,SMD12.5*13.5,ESR<=320mOhm | KEMET ELECTRONICS CORPORATION | EXV686M100A9RAA | G | PWA BOM | In Old BOM |
|  |  |  | 62111SK00-021-G | ECAP,68uF,+/-20%,100V,105C,G,SMD12.5*13.5,ESR<=320mOhm | NIPPON CHEMI-CON CORPORATION | EMVY101ARA680MKE0S | G | PWA BOM | In Old BOM |
| ##### Change Revision |  |  |  |  |  |  |  |  |  |
| Sheet | REV OF BOM | CUSTOMER | CUSTOMER P/N | PWA PN | PWA DESCRIPTION | PWA REV | DATE | Remark |  |
| OOOOOOOOOOOOOOOOOOOOOOOOOOOOOOOOOOOOOOOOOOOOOOOOOOOOOOOOOOOOOOOOOOOOOOOOOOOOOOOOOOOOOOOOOO | OOOOOOOOOOOOOOOOOOOOOOOOOOOOOOOOOOOOOOOOOOOOOOOOOOOOOOOOOOOOOOOOOOOOOOOOOOOOOOOOOOOOOOOOOO | OOOOOOOOOOOOOOOOOOOOOOOOOOOOOOOOOOOOOOOOOOOOOOOOOOOOOOOOOOOOOOOOOOOOOOOOOOOOOOOOOOOOOOOOOO | OOOOOOOOOOOOOOOOOOOOOOOOOOOOOOOOOOOOOOOOOOOOOOOOOOOOOOOOOOOOOOOOOOOOOOOOOOOOOOOOOOOOOOOOOO | OOOOOOOOOOOOOOOOOOOOOOOOOOOOOOOOOOOOOOOOOOOOOOOOOOOOOOOOOOOOOOOOOOOOOOOOOOOOOOOOOOOOOOOOOO | OOOOOOOOOOOOOOOOOOOOOOOOOOOOOOOOOOOOOOOOOOOOOOOOOOOOOOOOOOOOOOOOOOOOOOOOOOOOOOOOOOOOOOOOOO | OOOOOOOOOOOOOOOOOOOOOOOOOOOOOOOOOOOOOOOOOOOOOOOOOOOOOOOOOOOOOOOOOOOOOOOOOOOOOOOOOOOOOOOOOO | OOOOOOOOOOOOOOOOOOOOOOOOOOOOOOOOOOOOOOOOOOOOOOOOOOOOOOOOOOOOOOOOOOOOOOOOOOOOOOOOOOOOOOOOOO | OOOOOOOOOOOOOOOOOOOOOOOOOOOOOOOOOOOOOOOOOOOOOOOOOOOOOOOOOOOOOOOOOOOOOOOOOOOOOOOOOOOOOOOOOO | OOOOOOOOOOOOOOOOOOOOOOOOOOOOOOOOOOOOOOOOOOOOOOOOOOOOOOOOOOOOOOOOOOOOOOOOOOOOOOOOOOOOOOOOOO |
| Second Source Change |  |  |  |  |  |  |  |  |  |
| Item | Location | Change Type | Foxconn P/N | Part Description | Manufacturer Full Name | Manufacturer P/N | RoHS | Sheet |  |
| OOOOOOOOOOOOOOOOOOOOOOOOOOOOOOOOOOOOOOOOOOOOOOOOOOOOOOOOOOOOOOOOOOOOOOOOOOOOOOOOOOOOOOOOOO | OOOOOOOOOOOOOOOOOOOOOOOOOOOOOOOOOOOOOOOOOOOOOOOOOOOOOOOOOOOOOOOOOOOOOOOOOOOOOOOOOOOOOOOOOO | OOOOOOOOOOOOOOOOOOOOOOOOOOOOOOOOOOOOOOOOOOOOOOOOOOOOOOOOOOOOOOOOOOOOOOOOOOOOOOOOOOOOOOOOOO | OOOOOOOOOOOOOOOOOOOOOOOOOOOOOOOOOOOOOOOOOOOOOOOOOOOOOOOOOOOOOOOOOOOOOOOOOOOOOOOOOOOOOOOOOO | OOOOOOOOOOOOOOOOOOOOOOOOOOOOOOOOOOOOOOOOOOOOOOOOOOOOOOOOOOOOOOOOOOOOOOOOOOOOOOOOOOOOOOOOOO | OOOOOOOOOOOOOOOOOOOOOOOOOOOOOOOOOOOOOOOOOOOOOOOOOOOOOOOOOOOOOOOOOOOOOOOOOOOOOOOOOOOOOOOOOO | OOOOOOOOOOOOOOOOOOOOOOOOOOOOOOOOOOOOOOOOOOOOOOOOOOOOOOOOOOOOOOOOOOOOOOOOOOOOOOOOOOOOOOOOOO | OOOOOOOOOOOOOOOOOOOOOOOOOOOOOOOOOOOOOOOOOOOOOOOOOOOOOOOOOOOOOOOOOOOOOOOOOOOOOOOOOOOOOOOOOO | OOOOOOOOOOOOOOOOOOOOOOOOOOOOOOOOOOOOOOOOOOOOOOOOOOOOOOOOOOOOOOOOOOOOOOOOOOOOOOOOOOOOOOOOOO | OOOOOOOOOOOOOOOOOOOOOOOOOOOOOOOOOOOOOOOOOOOOOOOOOOOOOOOOOOOOOOOOOOOOOOOOOOOOOOOOOOOOOOOOOO |
| Master Materials Change |  |  |  |  |  |  |  |  |  |
| Item | Foxconn P/N | Orig._Usage | New_Usage | Part Description | Manufacturer Full Name | Manufacturer P/N | RoHS | Location | Sheet |
| 1 | EEEFK2A680AQ | 0 | 6 | ECAP,68uF,+/-20%,100V,105C,G,SMD12.5*13.5,ESR<=320mOhm | PANASONIC INDUSTRIAL CO.,LTD. | EEEFK2A680AQ | G | (+)PSUCE1,PBACE1,PAACE1,PSUCE2,PBACE2,PAACE2 | PWA BOM |
| 2 | 61100QH00-017-G | 4 | 2 | RES,510 Ohm,+/-0.1%,1/16W,G,SMD0402 | KOA SPEER ELECTRONICS, INC. | RN731ETTP5100B25 | G | (-)R1093,R1114 | PWA BOM |
|  | 61100QH00-011-G |  |  | RES,510 Ohm,+/-0.1%,1/16W,G,SMD0402 | YAGEO CORPORATION COMPONENT | RT0402BRD07510RL |  |  | PWA BOM |
| 3 | 62111CS00-024-G | 6 | 0 | ECAP,68uF,+/-20%,100V,105C,G,SMD12.5*13.5,ESR<=320mOhm | PANASONIC INDUSTRIAL CO.,LTD. | EEVFK2A680Q | G | (-)PSUCE1,PBACE1,PAACE1,PSUCE2,PBACE2,PAACE2 | PWA BOM |
|  | 62111RR00-025-G |  |  | ECAP,68uF,+/-20%,100V,105C,G,SMD12.5*13.5,ESR<=320mOhm | KEMET ELECTRONICS CORPORATION | EXV686M100A9RAA |  |  | PWA BOM |
|  | 62111SK00-021-G |  |  | ECAP,68uF,+/-20%,100V,105C,G,SMD12.5*13.5,ESR<=320mOhm | NIPPON CHEMI-CON CORPORATION | EMVY101ARA680MKE0S |  |  | PWA BOM |
| OOOOOOOOOOOOOOOOOOOOOOOOOOOOOOOOOOOOOOOOOOOOOOOOOOOOOOOOOOOOOOOOOOOOOOOOOOOOOOOOOOOOOOOOOO | OOOOOOOOOOOOOOOOOOOOOOOOOOOOOOOOOOOOOOOOOOOOOOOOOOOOOOOOOOOOOOOOOOOOOOOOOOOOOOOOOOOOOOOOOO | OOOOOOOOOOOOOOOOOOOOOOOOOOOOOOOOOOOOOOOOOOOOOOOOOOOOOOOOOOOOOOOOOOOOOOOOOOOOOOOOOOOOOOOOOO | OOOOOOOOOOOOOOOOOOOOOOOOOOOOOOOOOOOOOOOOOOOOOOOOOOOOOOOOOOOOOOOOOOOOOOOOOOOOOOOOOOOOOOOOOO | OOOOOOOOOOOOOOOOOOOOOOOOOOOOOOOOOOOOOOOOOOOOOOOOOOOOOOOOOOOOOOOOOOOOOOOOOOOOOOOOOOOOOOOOOO | OOOOOOOOOOOOOOOOOOOOOOOOOOOOOOOOOOOOOOOOOOOOOOOOOOOOOOOOOOOOOOOOOOOOOOOOOOOOOOOOOOOOOOOOOO | OOOOOOOOOOOOOOOOOOOOOOOOOOOOOOOOOOOOOOOOOOOOOOOOOOOOOOOOOOOOOOOOOOOOOOOOOOOOOOOOOOOOOOOOOO | OOOOOOOOOOOOOOOOOOOOOOOOOOOOOOOOOOOOOOOOOOOOOOOOOOOOOOOOOOOOOOOOOOOOOOOOOOOOOOOOOOOOOOOOOO | OOOOOOOOOOOOOOOOOOOOOOOOOOOOOOOOOOOOOOOOOOOOOOOOOOOOOOOOOOOOOOOOOOOOOOOOOOOOOOOOOOOOOOOOOO | OOOOOOOOOOOOOOOOOOOOOOOOOOOOOOOOOOOOOOOOOOOOOOOOOOOOOOOOOOOOOOOOOOOOOOOOOOOOOOOOOOOOOOOOOO |
| TLA Parts Change |  |  |  |  |  |  |  |  |  |
| Item | Foxconn P/N | Qty | Part Description | Manufacturer Full Name | Manufacturer P/N | RoHS | Location | Remark | BOM |
| BOM Change List Date:Fri Aug 18 15:46:09 GMT+08:00 2017 |  |  |  |  |  |  |  |  |  |
| New BOM file : C:\<user>\ZAIUS-MB-PVT-HW-EBOM-X04-20170818.xls |  |  |  |  |  |  |  |  |  |
| Old BOM file : C:\<user>\ZAIUS-MB-PVT-HW-EBOM-20170811.xls |  |  |  |  |  |  |  |  |  |
| ##### Add Parts |  |  |  |  |  |  |  |  |  |
| Item | Location | Qty | Foxconn P/N | Part Description | Manufacturer Full Name | Manufacturer P/N | RoHS | Sheet |  |
| ##### Remove Parts |  |  |  |  |  |  |  |  |  |
| Item | Location | Qty | Foxconn P/N | Part Description | Manufacturer Full Name | Manufacturer P/N | RoHS | Sheet |  |
| 1 | PBMD4,PBFD4,PBED4,PAMD4,PAFD4,PAED4,PBAD5,PAAD5 | 8 | 52030DA00-237-G | DIODE,Schottky,BAT46W-7-F,100V,150mA,G,SOD123-2,SMD | DIODES INEORPORATION | BAT46W-7-F |  | PWA BOM |  |
| ##### Change Parts |  |  |  |  |  |  |  |  |  |
| Item | Location | Qty | Foxconn P/N | Part Description | Manufacturer Full Name | Manufacturer P/N | RoHS | Sheet | Remark |
| 1 | PSUCE1,PBACE1,PAACE1,PSUCE2,PBACE2,PAACE2 | 6 | 62111U700-024-G | ECAP,68uF,+/-20%,100V,105C,320mOhm,G,SMD12.5*13.5 | PANASONIC INDUSTRIAL CO.,LTD. | EEEFK2A680AQ |  | PWA BOM | In New BOM |
|  | PSUCE1,PBACE1,PAACE1,PSUCE2,PBACE2,PAACE2 | 6 | 62111CS00-024-G | ECAP,68uF,+/-20%,100V,105C,G,SMD12.5*13.5,ESR<=320mOhm | PANASONIC INDUSTRIAL CO.,LTD. | EEVFK2A680Q |  | PWA BOM | In Old BOM |
| 2 | PBMD1,PBFD1,PBED1,PBAD1,PAMD1,PAFD1,PAED1,PAAD1 | 8 | 520103B00-185-G | Diode,Rectifier&Switching,MMBD1205,100V,200mA,G,SOT-23-3,SMD | FAIRCHILD SEMICONDUCTOR CORP | MMBD1205 | N | PWA BOM | In New BOM |
|  | PBMD1,PBFD1,PBED1,PBAD1,PAMD1,PAFD1,PAED1,PAAD1 | 8 | 52030DA00-237-G | DIODE,Schottky,BAT46W-7-F,100V,150mA,G,SOD123-2,SMD | DIODES INEORPORATION | BAT46W-7-F |  | PWA BOM | In Old BOM |
| 3 | U1,U10 | 2 | PE38993-51BC1-1H | POWER9 CPU Socket for LGA3899-HYBRID | FOXCONN TECHNOLOGY CO.,LTD. | PE38993-51BC1-1H |  | PWA BOM | In New BOM |
|  | U1,U10 | 2 | 340108S00-600-G | POWER9 CPU Socket for LGA3899-HYBRID | FOXCONN TECHNOLOGY CO.,LTD. | PE38993-51BC0-1H |  | PWA BOM | In Old BOM |
| ##### Change Revision |  |  |  |  |  |  |  |  |  |
| Sheet | REV OF BOM | CUSTOMER | CUSTOMER P/N | PWA PN | PWA DESCRIPTION | PWA REV | DATE | Remark |  |
| OOOOOOOOOOOOOOOOOOOOOOOOOOOOOOOOOOOOOOOOOOOOOOOOOOOOOOOOOOOOOOOOOOOOOOOOOOOOOOOOOOOOOOOOOO | OOOOOOOOOOOOOOOOOOOOOOOOOOOOOOOOOOOOOOOOOOOOOOOOOOOOOOOOOOOOOOOOOOOOOOOOOOOOOOOOOOOOOOOOOO | OOOOOOOOOOOOOOOOOOOOOOOOOOOOOOOOOOOOOOOOOOOOOOOOOOOOOOOOOOOOOOOOOOOOOOOOOOOOOOOOOOOOOOOOOO | OOOOOOOOOOOOOOOOOOOOOOOOOOOOOOOOOOOOOOOOOOOOOOOOOOOOOOOOOOOOOOOOOOOOOOOOOOOOOOOOOOOOOOOOOO | OOOOOOOOOOOOOOOOOOOOOOOOOOOOOOOOOOOOOOOOOOOOOOOOOOOOOOOOOOOOOOOOOOOOOOOOOOOOOOOOOOOOOOOOOO | OOOOOOOOOOOOOOOOOOOOOOOOOOOOOOOOOOOOOOOOOOOOOOOOOOOOOOOOOOOOOOOOOOOOOOOOOOOOOOOOOOOOOOOOOO | OOOOOOOOOOOOOOOOOOOOOOOOOOOOOOOOOOOOOOOOOOOOOOOOOOOOOOOOOOOOOOOOOOOOOOOOOOOOOOOOOOOOOOOOOO | OOOOOOOOOOOOOOOOOOOOOOOOOOOOOOOOOOOOOOOOOOOOOOOOOOOOOOOOOOOOOOOOOOOOOOOOOOOOOOOOOOOOOOOOOO | OOOOOOOOOOOOOOOOOOOOOOOOOOOOOOOOOOOOOOOOOOOOOOOOOOOOOOOOOOOOOOOOOOOOOOOOOOOOOOOOOOOOOOOOOO | OOOOOOOOOOOOOOOOOOOOOOOOOOOOOOOOOOOOOOOOOOOOOOOOOOOOOOOOOOOOOOOOOOOOOOOOOOOOOOOOOOOOOOOOOO |
| Second Source Change |  |  |  |  |  |  |  |  |  |
| Item | Location | Change Type | Foxconn P/N | Part Description | Manufacturer Full Name | Manufacturer P/N | RoHS | Sheet |  |
| OOOOOOOOOOOOOOOOOOOOOOOOOOOOOOOOOOOOOOOOOOOOOOOOOOOOOOOOOOOOOOOOOOOOOOOOOOOOOOOOOOOOOOOOOO | OOOOOOOOOOOOOOOOOOOOOOOOOOOOOOOOOOOOOOOOOOOOOOOOOOOOOOOOOOOOOOOOOOOOOOOOOOOOOOOOOOOOOOOOOO | OOOOOOOOOOOOOOOOOOOOOOOOOOOOOOOOOOOOOOOOOOOOOOOOOOOOOOOOOOOOOOOOOOOOOOOOOOOOOOOOOOOOOOOOOO | OOOOOOOOOOOOOOOOOOOOOOOOOOOOOOOOOOOOOOOOOOOOOOOOOOOOOOOOOOOOOOOOOOOOOOOOOOOOOOOOOOOOOOOOOO | OOOOOOOOOOOOOOOOOOOOOOOOOOOOOOOOOOOOOOOOOOOOOOOOOOOOOOOOOOOOOOOOOOOOOOOOOOOOOOOOOOOOOOOOOO | OOOOOOOOOOOOOOOOOOOOOOOOOOOOOOOOOOOOOOOOOOOOOOOOOOOOOOOOOOOOOOOOOOOOOOOOOOOOOOOOOOOOOOOOOO | OOOOOOOOOOOOOOOOOOOOOOOOOOOOOOOOOOOOOOOOOOOOOOOOOOOOOOOOOOOOOOOOOOOOOOOOOOOOOOOOOOOOOOOOOO | OOOOOOOOOOOOOOOOOOOOOOOOOOOOOOOOOOOOOOOOOOOOOOOOOOOOOOOOOOOOOOOOOOOOOOOOOOOOOOOOOOOOOOOOOO | OOOOOOOOOOOOOOOOOOOOOOOOOOOOOOOOOOOOOOOOOOOOOOOOOOOOOOOOOOOOOOOOOOOOOOOOOOOOOOOOOOOOOOOOOO | OOOOOOOOOOOOOOOOOOOOOOOOOOOOOOOOOOOOOOOOOOOOOOOOOOOOOOOOOOOOOOOOOOOOOOOOOOOOOOOOOOOOOOOOOO |
| Master Materials Change |  |  |  |  |  |  |  |  |  |
| Item | Foxconn P/N | Orig._Usage | New_Usage | Part Description | Manufacturer Full Name | Manufacturer P/N | RoHS | Location | Sheet |
| 1 | 62111U700-024-G | 0 | 6 | ECAP,68uF,+/-20%,100V,105C,320mOhm,G,SMD12.5*13.5 | PANASONIC INDUSTRIAL CO.,LTD. | EEEFK2A680AQ |  | (+)PSUCE1,PBACE1,PAACE1,PSUCE2,PBACE2,PAACE2 | PWA BOM |
| 2 | 520103B00-185-G | 0 | 8 | Diode,Rectifier&Switching,MMBD1205,100V,200mA,G,SOT-23-3,SMD | FAIRCHILD SEMICONDUCTOR CORP | MMBD1205 | N | (+)PBMD1,PBFD1,PBED1,PBAD1,PAMD1,PAFD1,PAED1,PAAD1 | PWA BOM |
| 3 | PE38993-51BC1-1H | 0 | 2 | POWER9 CPU Socket for LGA3899-HYBRID | FOXCONN TECHNOLOGY CO.,LTD. | PE38993-51BC1-1H |  | (+)U1,U10 | PWA BOM |
| 4 | 62111CS00-024-G | 6 | 0 | ECAP,68uF,+/-20%,100V,105C,G,SMD12.5*13.5,ESR<=320mOhm | PANASONIC INDUSTRIAL CO.,LTD. | EEVFK2A680Q |  | (-)PSUCE1,PBACE1,PAACE1,PSUCE2,PBACE2,PAACE2 | PWA BOM |
| 5 | 52030DA00-237-G | 16 | 0 | DIODE,Schottky,BAT46W-7-F,100V,150mA,G,SOD123-2,SMD | DIODES INEORPORATION | BAT46W-7-F |  | (-)PBMD1,PBFD1,PBED1,PBAD1,PAMD1,PAFD1,PAED1,PAAD1,PBMD4,PBFD4,PBED4,PAMD4,PAFD4,PAED4,PBAD5,PAAD5 | PWA BOM |
| 6 | 340108S00-600-G | 2 | 0 | POWER9 CPU Socket for LGA3899-HYBRID | FOXCONN TECHNOLOGY CO.,LTD. | PE38993-51BC0-1H |  | (-)U1,U10 | PWA BOM |
| OOOOOOOOOOOOOOOOOOOOOOOOOOOOOOOOOOOOOOOOOOOOOOOOOOOOOOOOOOOOOOOOOOOOOOOOOOOOOOOOOOOOOOOOOO | OOOOOOOOOOOOOOOOOOOOOOOOOOOOOOOOOOOOOOOOOOOOOOOOOOOOOOOOOOOOOOOOOOOOOOOOOOOOOOOOOOOOOOOOOO | OOOOOOOOOOOOOOOOOOOOOOOOOOOOOOOOOOOOOOOOOOOOOOOOOOOOOOOOOOOOOOOOOOOOOOOOOOOOOOOOOOOOOOOOOO | OOOOOOOOOOOOOOOOOOOOOOOOOOOOOOOOOOOOOOOOOOOOOOOOOOOOOOOOOOOOOOOOOOOOOOOOOOOOOOOOOOOOOOOOOO | OOOOOOOOOOOOOOOOOOOOOOOOOOOOOOOOOOOOOOOOOOOOOOOOOOOOOOOOOOOOOOOOOOOOOOOOOOOOOOOOOOOOOOOOOO | OOOOOOOOOOOOOOOOOOOOOOOOOOOOOOOOOOOOOOOOOOOOOOOOOOOOOOOOOOOOOOOOOOOOOOOOOOOOOOOOOOOOOOOOOO | OOOOOOOOOOOOOOOOOOOOOOOOOOOOOOOOOOOOOOOOOOOOOOOOOOOOOOOOOOOOOOOOOOOOOOOOOOOOOOOOOOOOOOOOOO | OOOOOOOOOOOOOOOOOOOOOOOOOOOOOOOOOOOOOOOOOOOOOOOOOOOOOOOOOOOOOOOOOOOOOOOOOOOOOOOOOOOOOOOOOO | OOOOOOOOOOOOOOOOOOOOOOOOOOOOOOOOOOOOOOOOOOOOOOOOOOOOOOOOOOOOOOOOOOOOOOOOOOOOOOOOOOOOOOOOOO |  |
| TLA Parts Change |  |  |  |  |  |  |  |  |  |
| Item | Foxconn P/N | Qty | Part Description | Manufacturer Full Name | Manufacturer P/N | RoHS | Location | Remark |  |
| BOM Change List Date:Mon Aug 21 16:49:27 CST 2017 |  |  |  |  |  |  |  |  |  |
| New BOM file : E:\barreleye g2\0821\zaius\ZAIUS-MB-PVT-X04-BOM_X24_20170818.xls |  |  |  |  |  |  |  |  |  |
| Old BOM file : E:\barreleye g2\0821\zaius\zaius0811.xls |  |  |  |  |  |  |  |  |  |
| ##### Add Parts |  |  |  |  |  |  |  |  |  |
| Item | Location | Qty | Foxconn P/N | Part Description | Manufacturer Full Name | Manufacturer P/N | RoHS | Sheet |  |
| ##### Remove Parts |  |  |  |  |  |  |  |  |  |
| Item | Location | Qty | Foxconn P/N | Part Description | Manufacturer Full Name | Manufacturer P/N | RoHS | Sheet |  |
| 1 | PBMD4,PBFD4,PBED4,PAMD4,PAFD4,PAED4,PBAD5,PAAD5 | 8 | 52030DA00-237-G | DIODE,Schottky,BAT46W-7-F,100V,150mA,G,SOD123-2,SMD | DIODES INEORPORATION | BAT46W-7-F | G | PWA BOM |  |
| ##### Change Parts |  |  |  |  |  |  |  |  |  |
| Item | Location | Qty | Foxconn P/N | Part Description | Manufacturer Full Name | Manufacturer P/N | RoHS | Sheet | Remark |
| 1 | L34,L36 | 2 | 72010A400-023-G | FB,80Ohm@100MHz,+/-25%,4A,10mOhm,G,SMD1206 | TAIYO ELECTRIC IND.CO.LTD | FBMJ3216HS800-T | G | PWA BOM | In New BOM |
|  |  |  | 72010A400-025-G | FB,Multilayer,10mOhm,80Ohm@100MHz,+/-25%,4A,,SMD1206,G | KEMET ELECTRONICS CORPORATION | Z1206C800APWST | G | PWA BOM | In New BOM |
|  | L34,L36 | 2 | 72010A400-023-G | FB,80Ohm@100MHz,+/-25%,4A,10mOhm,G,SMD1206 | TAIYO ELECTRIC IND.CO.LTD | FBMJ3216HS800-T | G | PWA BOM | In Old BOM |
|  |  |  | Z1206C800APWST | FB,80Ohm@100MHz,+/-25%,4A,10mOhm,G,SMD1206 | KEMET ELECTRONICS CORPORATION | Z1206C800APWST | G | PWA BOM | In Old BOM |
| 2 | PBMQ10,PBAQ10,PAMQ10,PAAQ10,PBFQ11,PBEQ11,PAFQ11,PAEQ11 | 8 | 51032DL00-237-G | MOS N,DMT10H014LSS-13,100V,8.9A,15m@10V,G,SO-8,SMD | DIODES INCORPORATION | DMT10H014LSS-13 | G | PWA BOM | In New BOM |
|  |  |  | 51032FL00-029-G | MOS N,Si4190ADY-T1-GE3,100V,18.4A,8.8m@10V,G,SO-8,SMD | VISHAY ENTER TECHNO LOGY.INC | Si4190ADY-T1-GE3 | G | PWA BOM | In New BOM |
|  | PBMQ10,PBAQ10,PAMQ10,PAAQ10,PBFQ11,PBEQ11,PAFQ11,PAEQ11 | 8 | 51032DL00-237-G | MOS N,DMT10H014LSS-13,100V,8.9A,15m@10V,G,SO-8,SMD | DIODES INCORPORATION | DMT10H014LSS-13 | G | PWA BOM | In Old BOM |
|  |  |  | Si4190ADY-T1-GE3 | MOS N,Si4190ADY-T1-GE3,100V,18.4A,8.8m@10V,G,SO-8,SMD | VISHAY ENTER TECHNO LOGY.INC | Si4190ADY-T1-GE3 | G | PWA BOM | In Old BOM |
| 3 | PAMR66,PBMR69,PBMR76,PAMR76 | 4 | 61010R900-017-G | RES,27.4KOhm,+/-1%,1/10W,G,SMD0603 | KOA SPEER ELECTRONICS, INC. | RK73H1JTTD2742F | G | PWA BOM | In New BOM |
|  |  |  | 61010R900-011-G | RES,27.4KOhm,+/-1%,1/10W,G,SMD0603 | YAGEO CORPORATION COMPONENT | RC0603FR-0727K4L | G | PWA BOM | In New BOM |
|  |  |  | 61010R901-029-G | RES,thick film,27.4KOhm,+/-1%,1/10W,SMD0603,G | VISHAY ENTER TECHNO LOGY.INC | CRCW060327K4FKEB | G | PWA BOM | In New BOM |
|  | PAMR66,PBMR69,PBMR76,PAMR76 | 4 | 61010R900-017-G | RES,27.4KOhm,+/-1%,1/10W,G,SMD0603 | KOA SPEER ELECTRONICS, INC. | RK73H1JTTD2742F | G | PWA BOM | In Old BOM |
|  |  |  | 61010R900-011-G | RES,27.4KOhm,+/-1%,1/10W,G,SMD0603 | YAGEO CORPORATION COMPONENT | RC0603FR-0727K4L | G | PWA BOM | In Old BOM |
|  |  |  | CRCW06032742FKEB | RES,27.4KOhm,+/-1%,1/10W,G,SMD0603 | VISHAY ENTER TECHNO LOGY.INC | CRCW06032742FKEB | G | PWA BOM | In Old BOM |
| 4 | PBNR24,PANR24 | 2 | 61011CS00-017-G | RES,750KOhm,+/-1%,1/16W,G,SMD0402 | KOA SPEER ELECTRONICS, INC. | RK73H1ETTP7503F | G | PWA BOM | In New BOM |
|  |  |  | 61011CS00-011-G | RES,750KOhm,+/-1%,1/16W,G,SMD0402 | YAGEO CORPORATION COMPONENT | RC0402FR-07750KL | G | PWA BOM | In New BOM |
|  |  |  | 61011CS00-029-G | RES,thick film,750KOhm,+/-1%,1/16W,SMD0402,G | VISHAY ENTER TECHNO LOGY.INC | CRCW0402750KFKED | G | PWA BOM | In New BOM |
|  | PBNR24,PANR24 | 2 | 61011CS00-017-G | RES,750KOhm,+/-1%,1/16W,G,SMD0402 | KOA SPEER ELECTRONICS, INC. | RK73H1ETTP7503F | G | PWA BOM | In Old BOM |
|  |  |  | 61011CS00-011-G | RES,750KOhm,+/-1%,1/16W,G,SMD0402 | YAGEO CORPORATION COMPONENT | RC0402FR-07750KL | G | PWA BOM | In Old BOM |
|  |  |  | CRCW04027503FKED | RES,750KOhm,+/-1%,1/16W,G,SMD0402 | VISHAY ENTER TECHNO LOGY.INC | CRCW04027503FKED | G | PWA BOM | In Old BOM |
| 5 | PSTC4,PSLC4,PSFC4,PSEC4,PSDC4,PQPC4,PFRC4,PEEC4,PEDC4,PSPC3003,PIPC3003,PFPC3003,PEPC3003,PSRC3010 | 14 | 62012T300-015-G | CAP,1uF,+/-10%,X7S,25V,G,SMD0402 | MURATA ELEC. NORTH AMERICA | GRM155C71E105KE11D | G | PWA BOM | In New BOM |
|  |  |  | 620138700-026-G | CAP,1uF,+/-10%,X6S,25V,G,SMD0402 | SAMSUNG SEMICONDUCTOR | CL05X105KA5NQNC | G | PWA BOM | In New BOM |
|  |  |  | 620138700-015-G | CAP,1uF,+/-10%,X6S,25V,G,SMD0402 | MURATA | GRM155C81E105KE11D | G | PWA BOM | In New BOM |
|  | PSTC4,PSLC4,PSFC4,PSEC4,PSDC4,PQPC4,PFRC4,PEEC4,PEDC4,PSPC3003,PIPC3003,PFPC3003,PEPC3003,PSRC3010 | 14 | 62012T300-015-G | CAP,1uF,+/-10%,X7S,25V,G,SMD0402 | MURATA ELEC. NORTH AMERICA | GRM155C71E105KE11D | G | PWA BOM | In Old BOM |
|  |  |  | 620138700-026-G | CAP,1uF,+/-10%,X6S,25V,G,SMD0402 | SAMSUNG SEMICONDUCTOR | CL05X105KA5NQNC | G | PWA BOM | In Old BOM |
|  |  |  | GRM155C81E105KE11D | CAP,1uF,+/-10%,X6S,25V,G,SMD0402 | MURATA | GRM155C81E105KE11D | G | PWA BOM | In Old BOM |
| 6 | PETL1,PERL1,PSFL2,PEEL2,PEDL2 | 5 | 63032CD00-088-G | IND,2.2uH@100KHz,+/-20%,8A,20mOhm,SHLD,G,SMD | COOPER BUSSMANN, INC. | HCM0703-2R2-R | G | PWA BOM | In New BOM |
|  |  |  | 630365J00-034-G | IND,2.2uH@100KHz,+/-20%,9A,12.8mOhm,SHLD,G,SMD | CYNTEC CO. LTD | CMLE063T-2R2MS | G | PWA BOM | In New BOM |
|  | PETL1,PERL1,PSFL2,PEEL2,PEDL2 | 5 | 63032CD00-088-G | IND,2.2uH@100KHz,+/-20%,8A,20mOhm,SHLD,G,SMD | COOPER BUSSMANN, INC. | HCM0703-2R2-R | G | PWA BOM | In Old BOM |
|  |  |  | CMLE063T-2R2MS | IND,CMLE063T-2R2MS | CYNTEC CO. LTD | CMLE063T-2R2MS | G | PWA BOM | In Old BOM |
| 7 | PHAQ1,PHAQ2,PHAQ3 | 3 | 51031VY00-031-G | MOS N,PSMN4R8-100BSE,100V,120A,4.8m@10V,G,SOT404-3,SMD | NXP SEMICONDUCTORS | PSMN4R8-100BSE | G | PWA BOM | In New BOM |
|  |  |  | 51032HE00-185-G | MOS N,FDB047N10,100V,120A,3.9m@10V,G,TO263-3,SMD | FAIRCHILD SEMICONDUCTOR CORP | FDB047N10 | G | PWA BOM | In New BOM |
|  |  |  | 51032JY00-029-G | MOS N,SUM70040E-GE3,100V,120A,G,TO-263-3,SMD | VISHAY ENTER TECHNO LOGY.INC | SUM70040E-GE3 | G | PWA BOM | In New BOM |
|  | PHAQ1,PHAQ2,PHAQ3 | 3 | 51031VY00-031-G | MOS N,PSMN4R8-100BSE,100V,120A,4.8m@10V,G,SOT404-3,SMD | NXP SEMICONDUCTORS | PSMN4R8-100BSE | G | PWA BOM | In Old BOM |
|  |  |  | 51032HE00-185-G | MOS N,FDB047N10,100V,120A,3.9m@10V,G,TO263-3,SMD | FAIRCHILD SEMICONDUCTOR CORP | FDB047N10 | G | PWA BOM | In Old BOM |
|  |  |  | SUM70040E-GE3 | MOS N,SUM70040E-GE3,100V,120A,4.0m@10V,G,TO263-3,SMD | VISHAY ENTER TECHNO LOGY.INC | SUM70040E-GE3 | G | PWA BOM | In Old BOM |
| 8 | PSRL2 | 1 | 63034GW00-088-G | IND,680nH@100KHz,+/-20%,34A,1.33mOhm,SHLD,G,SMD | COOPER BUSSMANN, INC. | HCM1305-R68-R | G | PWA BOM | In New BOM |
|  |  |  | 630365H00-034-G | IND,680nH@100KHz,+/-20%,29.5A,1.55mOhm,SHLD,G,SMD | CYNTEC CO. LTD | CMLB135T-R68MS | G | PWA BOM | In New BOM |
|  | PSRL2 | 1 | 63034GW00-088-G | IND,680nH@100KHz,+/-20%,34A,1.33mOhm,SHLD,G,SMD | COOPER BUSSMANN, INC. | HCM1305-R68-R | G | PWA BOM | In Old BOM |
|  |  |  | CMLB135T-R68MS | IND,680nH@100KHz,+/-20%,34A,1.33mOhm,SHLD,G,SMD | CYNTEC CO. LTD | CMLB135T-R68MS | G | PWA BOM | In Old BOM |
| 9 | PSTR17 | 1 | 61100QA00-017-G | RES,16KOhm,+/-0.1%,1/16W,G,SMD0402 | KOA SPEER ELECTRONICS, INC. | RN731ETTP1602B25 | G | PWA BOM | In New BOM |
|  |  |  | 61100QA01-024-G | RES,16KOhm,+/-0.1%,1/16W,G,SMD0402 | PANASONIC INDUSTRIAL CO.,LTD. | ERA2AEB163X | G | PWA BOM | In New BOM |
|  |  |  | 61100QA00-029-G | RES,16KOhm,+/-0.1%,1/16W,G,SMD0402 | VISHAY ENTER TECHNO LOGY.INC | TNPW040216K0BEED | G | PWA BOM | In New BOM |
|  | PSTR17 | 1 | 61100QA00-017-G | RES,16KOhm,+/-0.1%,1/16W,G,SMD0402 | KOA SPEER ELECTRONICS, INC. | RN731ETTP1602B25 | G | PWA BOM | In Old BOM |
|  |  |  | ERA2AEB163X | RES,16KOhm,+/-0.1%,1/16W,G,SMD0402 | PANASONIC INDUSTRIAL CO.,LTD. | ERA2AEB163X | G | PWA BOM | In Old BOM |
|  |  |  | 61100QA00-029-G | RES,16KOhm,+/-0.1%,1/16W,G,SMD0402 | VISHAY ENTER TECHNO LOGY.INC | TNPW040216K0BEED | G | PWA BOM | In Old BOM |
| 10 | PSTR19 | 1 | 61100J401-017-G | RES,1.78KOhm,+/-0.1%,1/16W,G,SMD0402 | KOA SPEER ELECTRONICS, INC. | RN73H1ETTP1781B25 | G | PWA BOM | In New BOM |
|  |  |  | 61100J400-024-G | RES,1.78KOhm,+/-0.1%,1/16W,G,SMD0402 | PANASONIC INDUSTRIAL CO.,LTD. | ERA2AEB1781X | G | PWA BOM | In New BOM |
|  |  |  | 61100J400-029-G | RES,1.78KOhm,+/-0.1%,1/16W,G,SMD0402 | VISHAY ENTER TECHNO LOGY.INC | MCS0402MD1781BE000 | G | PWA BOM | In New BOM |
|  | PSTR19 | 1 | 61100J401-017-G | RES,1.78KOhm,+/-0.1%,1/16W,G,SMD0402 | KOA SPEER ELECTRONICS, INC. | RN73H1ETTP1781B25 | G | PWA BOM | In Old BOM |
|  |  |  | 61100J400-024-G | RES,1.78KOhm,+/-0.1%,1/16W,G,SMD0402 | PANASONIC INDUSTRIAL CO.,LTD. | ERA2AEB1781X | G | PWA BOM | In Old BOM |
|  |  |  | MCS0402MD1781BE000 | RES,1.78KOhm,+/-0.1%,1/16W,G,SMD0402 | VISHAY ENTER TECHNO LOGY.INC | MCS0402MD1781BE000 | G | PWA BOM | In Old BOM |
| 11 | QN2,QN3 | 2 | 510503B00-223-G | MOS N/N,NTZD3154NT1G,20V,0.54A,550m24.5V,G,SOT563-6,SMD | ON SEMICONDUCTOR CORP | NTZD3154NT1G | G | PWA BOM | In New BOM |
|  |  |  | 51050L500-029-G | MOS,N/N,Si1034CX-T1-GE3,20V,0.61A,G,SC-89-6,SMD | VISHAY ENTER TECHNO LOGY.INC | Si1034CX-T1-GE3 | G | PWA BOM | In New BOM |
|  |  |  | 51050KW00-131-G | MOS N/N,SSM6N36FE,20V,500mA,0.63@5V,G,ES6-6,SMD | TOSHIBA ELECTRONICS ASIA LTD | SSM6N36FE | G | PWA BOM | In New BOM |
|  | QN2,QN3 | 2 | 510503B00-223-G | MOS N/N,NTZD3154NT1G,20V,0.54A,550m24.5V,G,SOT563-6,SMD | ON SEMICONDUCTOR CORP | NTZD3154NT1G | G | PWA BOM | In Old BOM |
|  |  |  | Si1034CX-T1-GE3 | MOS N/N,Si1034CX,20V,0.5A,1ohm@4V,G,EMT-6,SMD | VISHAY ENTER TECHNO LOGY.INC | Si1034CX-T1-GE3 | G | PWA BOM | In Old BOM |
|  |  |  | 51050KW00-131-G | MOS N/N,SSM6N36FE,20V,500mA,0.63@5V,G,ES6-6,SMD | TOSHIBA ELECTRONICS ASIA LTD | SSM6N36FE | G | PWA BOM | In Old BOM |
| 12 | Q5,Q7 | 2 | 510406000-185-G | MOS P,FDD6685,30V,11A,30m@4.5V,G,TO252-3,SMD | FAIRCHILD SEMICONDUCTOR CORP | FDD6685 | G | PWA BOM | In New BOM |
|  |  |  | 510410800-221-G | MOS P,IPD042P03L3G,-30V,-70A,4.2m@-10V,G,TO-252-3,SMD | INFINEON TECHNOLOGIES CORP. | IPD042P03L3G | G | PWA BOM | In New BOM |
|  |  |  | 51040WQ00-131-G | MOS P,TJ40S04M3L,-40V,-40A,9.1m@-10V,G,SMD-3 | TOSHIBA ELECTRONICS ASIA LTD | TJ40S04M3L | G | PWA BOM | In New BOM |
|  | Q5,Q7 | 2 | 510406000-185-G | MOS P,FDD6685,30V,11A,30m@4.5V,G,TO252-3,SMD | FAIRCHILD SEMICONDUCTOR CORP | FDD6685 | G | PWA BOM | In Old BOM |
|  |  |  | IPD042P03L3 | MOS P,30V,11A,30m@4.5V,G,TO252-3,SMD | INFINEON TECHNOLOGIES CORP. | IPD042P03L3 | G | PWA BOM | In Old BOM |
|  |  |  | 51040WQ00-131-G | MOS P,TJ40S04M3L,-40V,-40A,9.1m@-10V,G,SMD-3 | TOSHIBA ELECTRONICS ASIA LTD | TJ40S04M3L | G | PWA BOM | In Old BOM |
| 13 | J23,J24,J25,J26 | 4 | 3406A2B00-317-G | CONN,Header,WTB,1X4,V/T,Bla,2.54mm,15u,G,DIP-4 | MOLEX INCORPORATED | 171856-1104 | G | PWA BOM | In New BOM |
|  |  |  | 3406BJ100-278-G | CONN,Header,WTB,1X4,V/T,Bla,2.54mm,15u,G,DIP-4 | TYCO ELECTRONICS CORPORATION | 640456-4 | G | PWA BOM | In New BOM |
|  |  |  | 3406AYG00-637-G | Header&Socket Connector,2111100400-0141,Wire-to-Board Header,4,DIP,NY66,2.54mm,15u",Black,G | LONG SHOUNG CO.,LTD. | 2111100400-0141 | G | PWA BOM | In New BOM |
|  | J23,J24,J25,J26 | 4 | 3406A2B00-317-G | CONN,Header,WTB,1X4,V/T,Bla,2.54mm,15u,G,DIP-4 | MOLEX INCORPORATED | 171856-1104 | G | PWA BOM | In Old BOM |
|  |  |  | 640456-4 | CONN,Header,WTB,1X4,V/T,Bla,2.54mm,15u,G,DIP-4 | TYCO ELECTRONICS CORPORATION | 640456-4 | G | PWA BOM | In Old BOM |
|  |  |  | 3406AYG00-637-G | Header&Socket Connector,2111100400-0141,Wire-to-Board Header,4,DIP,NY66,2.54mm,15u",Black,G | LONG SHOUNG CO.,LTD. | 2111100400-0141 | G | PWA BOM | In Old BOM |
| 14 | PSUCE1,PBACE1,PAACE1,PSUCE2,PBACE2,PAACE2 | 6 | 62111U700-024-G | ECAP,68uF,+/-20%,100V,105C,320mOhm,G,SMD12.5*13.5 | PANASONIC INDUSTRIAL CO.,LTD. | EEEFK2A680AQ | G | PWA BOM | In New BOM |
|  | PSUCE1,PBACE1,PAACE1,PSUCE2,PBACE2,PAACE2 | 6 | EEEFK2A680AQ | ECAP,68uF,+/-20%,100V,105C,G,SMD12.5*13.5,ESR<=320mOhm | PANASONIC INDUSTRIAL CO.,LTD. | EEEFK2A680AQ | G | PWA BOM | In Old BOM |
| 15 | PBMD1,PBFD1,PBED1,PBAD1,PAMD1,PAFD1,PAED1,PAAD1 | 8 | 520103B00-185-G | Diode,Rectifier&Switching,MMBD1205,100V,200mA,G,SOT-23-3,SMD | FAIRCHILD SEMICONDUCTOR CORP | MMBD1205 | G | PWA BOM | In New BOM |
|  | PBMD1,PBFD1,PBED1,PBAD1,PAMD1,PAFD1,PAED1,PAAD1 | 8 | 52030DA00-237-G | DIODE,Schottky,BAT46W-7-F,100V,150mA,G,SOD123-2,SMD | DIODES INEORPORATION | BAT46W-7-F | G | PWA BOM | In Old BOM |
| 16 | PBER65,PAFR65,PAER65,PBFR66 | 4 | SLW1TTE50L0F | RES,50mOhm,+/-1%,1.5W,G,SMD2512 | KOA | SLW1TTE50L0F | G | PWA BOM | In New BOM |
|  |  |  | LRMAP2512-R05FT4 | RES,50mOhm,+/-1%,1.5W,G,SMD2512 | INTERNATIONAL RESISTIVE COMPANY, INC. | LRMAP2512-R05FT4 | G | PWA BOM | In New BOM |
|  | PBER65,PAFR65,PAER65,PBFR66 | 4 | SLW1TTE50L0F | RES,50mOhm,+/-1%,1.5W,G,SMD2512 | KOA SPEER ELECTRONICS, INC. | SLW1TTE50L0F | G | PWA BOM | In Old BOM |
|  |  |  | LRMAP2512-R05FT4 | RES,50mOhm,+/-1%,1.5W,G,SMD2512 | INTERNATIONAL RESISTIVE COMPANY, INC. | LRMAP2512-R05FT4 | G | PWA BOM | In Old BOM |
| 17 | PBMR65,PAMR65 | 2 | SLW1TTE75L0F | RES,75mOhm,+/-1%,1.5W,G,SMD2512 | KOA | SLW1TTE75L0F | G | PWA BOM | In New BOM |
|  |  |  | LRMAP2512-R075FT4 | RES,75mOhm,+/-1%,1.5W,G,SMD2512 | INTERNATIONAL RESISTIVE COMPANY, INC. | LRMAP2512-R075FT4 | G | PWA BOM | In New BOM |
|  | PBMR65,PAMR65 | 2 | SLW1TTE75L0F | RES,75mOhm,+/-1%,1.5W,G,SMD2512 | KOA SPEER ELECTRONICS, INC. | SLW1TTE75L0F | G | PWA BOM | In Old BOM |
|  |  |  | LRMAP2512-R075FT4 | RES,75mOhm,+/-1%,1.5W,G,SMD2512 | INTERNATIONAL RESISTIVE COMPANY, INC. | LRMAP2512-R075FT4 | G | PWA BOM | In Old BOM |
| 18 | U1,U10 | 2 | PE38993-51BC1-1H | POWER9 CPU Socket for LGA3899-HYBRID | FOXCONN TECHNOLOGY CO.,LTD. | PE38993-51BC1-1H | G | PWA BOM | In New BOM |
|  | U1,U10 | 2 | 340108S00-600-G | POWER9 CPU Socket for LGA3899-HYBRID | FOXCONN TECHNOLOGY CO.,LTD. | PE38993-51BC0-1H | G | PWA BOM | In Old BOM |
| ##### Change Revision |  |  |  |  |  |  |  |  |  |
| Sheet | REV OF BOM | CUSTOMER | CUSTOMER P/N | PWA PN | PWA DESCRIPTION | PWA REV | DATE | Remark |  |
| OOOOOOOOOOOOOOOOOOOOOOOOOOOOOOOOOOOOOOOOOOOOOOOOOOOOOOOOOOOOOOOOOOOOOOOOOOOOOOOOOOOOOOOOOO | OOOOOOOOOOOOOOOOOOOOOOOOOOOOOOOOOOOOOOOOOOOOOOOOOOOOOOOOOOOOOOOOOOOOOOOOOOOOOOOOOOOOOOOOOO | OOOOOOOOOOOOOOOOOOOOOOOOOOOOOOOOOOOOOOOOOOOOOOOOOOOOOOOOOOOOOOOOOOOOOOOOOOOOOOOOOOOOOOOOOO | OOOOOOOOOOOOOOOOOOOOOOOOOOOOOOOOOOOOOOOOOOOOOOOOOOOOOOOOOOOOOOOOOOOOOOOOOOOOOOOOOOOOOOOOOO | OOOOOOOOOOOOOOOOOOOOOOOOOOOOOOOOOOOOOOOOOOOOOOOOOOOOOOOOOOOOOOOOOOOOOOOOOOOOOOOOOOOOOOOOOO | OOOOOOOOOOOOOOOOOOOOOOOOOOOOOOOOOOOOOOOOOOOOOOOOOOOOOOOOOOOOOOOOOOOOOOOOOOOOOOOOOOOOOOOOOO | OOOOOOOOOOOOOOOOOOOOOOOOOOOOOOOOOOOOOOOOOOOOOOOOOOOOOOOOOOOOOOOOOOOOOOOOOOOOOOOOOOOOOOOOOO | OOOOOOOOOOOOOOOOOOOOOOOOOOOOOOOOOOOOOOOOOOOOOOOOOOOOOOOOOOOOOOOOOOOOOOOOOOOOOOOOOOOOOOOOOO | OOOOOOOOOOOOOOOOOOOOOOOOOOOOOOOOOOOOOOOOOOOOOOOOOOOOOOOOOOOOOOOOOOOOOOOOOOOOOOOOOOOOOOOOOO | OOOOOOOOOOOOOOOOOOOOOOOOOOOOOOOOOOOOOOOOOOOOOOOOOOOOOOOOOOOOOOOOOOOOOOOOOOOOOOOOOOOOOOOOOO |
| Second Source Change |  |  |  |  |  |  |  |  |  |
| Item | Location | Change Type | Foxconn P/N | Part Description | Manufacturer Full Name | Manufacturer P/N | RoHS | Sheet |  |
| 1 | PCB |  | 0101FBQ00-000-G | PCB,Zaius-MB PVT-X04,OSP,Gre,22L,22.20*13.00,G | GOLD CIRCUIT ELECTRONICS LTD. | 0101FBQ00-000-G | G | PWA BOM |  |
|  |  | ADD | 0101FBQ00-000-G | PCB,Zaius-MB PVT-X04,OSP,Gre,22L,22.20*13.00,G | ISUPETASYS CO., LTD | 0101FBQ00-000-G | G | PWA BOM |  |
| 2 | L34,L36 |  | 72010A400-023-G | FB,80Ohm@100MHz,+/-25%,4A,10mOhm,G,SMD1206 | TAIYO ELECTRIC IND.CO.LTD | FBMJ3216HS800-T | G | PWA BOM |  |
|  |  | ADD | 72010A400-025-G | FB,Multilayer,10mOhm,80Ohm@100MHz,+/-25%,4A,,SMD1206,G | KEMET ELECTRONICS CORPORATION | Z1206C800APWST | G | PWA BOM |  |
|  |  | Delete | Z1206C800APWST | FB,80Ohm@100MHz,+/-25%,4A,10mOhm,G,SMD1206 | KEMET ELECTRONICS CORPORATION | Z1206C800APWST | G | PWA BOM |  |
| 3 | PBMQ10,PBAQ10,PAMQ10,PAAQ10,PBFQ11,PBEQ11,PAFQ11,PAEQ11 |  | 51032DL00-237-G | MOS N,DMT10H014LSS-13,100V,8.9A,15m@10V,G,SO-8,SMD | DIODES INCORPORATION | DMT10H014LSS-13 | G | PWA BOM |  |
|  |  | ADD | 51032FL00-029-G | MOS N,Si4190ADY-T1-GE3,100V,18.4A,8.8m@10V,G,SO-8,SMD | VISHAY ENTER TECHNO LOGY.INC | Si4190ADY-T1-GE3 | G | PWA BOM |  |
|  |  | Delete | Si4190ADY-T1-GE3 | MOS N,Si4190ADY-T1-GE3,100V,18.4A,8.8m@10V,G,SO-8,SMD | VISHAY ENTER TECHNO LOGY.INC | Si4190ADY-T1-GE3 | G | PWA BOM |  |
| 4 | PAMR66,PBMR69,PBMR76,PAMR76 |  | 61010R900-017-G | RES,27.4KOhm,+/-1%,1/10W,G,SMD0603 | KOA SPEER ELECTRONICS, INC. | RK73H1JTTD2742F | G | PWA BOM |  |
|  |  | NO | 61010R900-011-G | RES,27.4KOhm,+/-1%,1/10W,G,SMD0603 | YAGEO CORPORATION COMPONENT | RC0603FR-0727K4L | G | PWA BOM |  |
|  |  | ADD | 61010R901-029-G | RES,thick film,27.4KOhm,+/-1%,1/10W,SMD0603,G | VISHAY ENTER TECHNO LOGY.INC | CRCW060327K4FKEB | G | PWA BOM |  |
|  |  | Delete | CRCW06032742FKEB | RES,27.4KOhm,+/-1%,1/10W,G,SMD0603 | VISHAY ENTER TECHNO LOGY.INC | CRCW06032742FKEB | G | PWA BOM |  |
| 5 | PBNR24,PANR24 |  | 61011CS00-017-G | RES,750KOhm,+/-1%,1/16W,G,SMD0402 | KOA SPEER ELECTRONICS, INC. | RK73H1ETTP7503F | G | PWA BOM |  |
|  |  | NO | 61011CS00-011-G | RES,750KOhm,+/-1%,1/16W,G,SMD0402 | YAGEO CORPORATION COMPONENT | RC0402FR-07750KL | G | PWA BOM |  |
|  |  | ADD | 61011CS00-029-G | RES,thick film,750KOhm,+/-1%,1/16W,SMD0402,G | VISHAY ENTER TECHNO LOGY.INC | CRCW0402750KFKED | G | PWA BOM |  |
|  |  | Delete | CRCW04027503FKED | RES,750KOhm,+/-1%,1/16W,G,SMD0402 | VISHAY ENTER TECHNO LOGY.INC | CRCW04027503FKED | G | PWA BOM |  |
| 6 | PSTC4,PSLC4,PSFC4,PSEC4,PSDC4,PQPC4,PFRC4,PEEC4,PEDC4,PSPC3003,PIPC3003,PFPC3003,PEPC3003,PSRC3010 |  | 62012T300-015-G | CAP,1uF,+/-10%,X7S,25V,G,SMD0402 | MURATA ELEC. NORTH AMERICA | GRM155C71E105KE11D | G | PWA BOM |  |
|  |  | NO | 620138700-026-G | CAP,1uF,+/-10%,X6S,25V,G,SMD0402 | SAMSUNG SEMICONDUCTOR | CL05X105KA5NQNC | G | PWA BOM |  |
|  |  | ADD | 620138700-015-G | CAP,1uF,+/-10%,X6S,25V,G,SMD0402 | MURATA | GRM155C81E105KE11D | G | PWA BOM |  |
|  |  | Delete | GRM155C81E105KE11D | CAP,1uF,+/-10%,X6S,25V,G,SMD0402 | MURATA | GRM155C81E105KE11D | G | PWA BOM |  |
| 7 | PETL1,PERL1,PSFL2,PEEL2,PEDL2 |  | 63032CD00-088-G | IND,2.2uH@100KHz,+/-20%,8A,20mOhm,SHLD,G,SMD | COOPER BUSSMANN, INC. | HCM0703-2R2-R | G | PWA BOM |  |
|  |  | ADD | 630365J00-034-G | IND,2.2uH@100KHz,+/-20%,9A,12.8mOhm,SHLD,G,SMD | CYNTEC CO. LTD | CMLE063T-2R2MS | G | PWA BOM |  |
|  |  | Delete | CMLE063T-2R2MS | IND,CMLE063T-2R2MS | CYNTEC CO. LTD | CMLE063T-2R2MS | G | PWA BOM |  |
| 8 | PHAQ1,PHAQ2,PHAQ3 |  | 51031VY00-031-G | MOS N,PSMN4R8-100BSE,100V,120A,4.8m@10V,G,SOT404-3,SMD | NXP SEMICONDUCTORS | PSMN4R8-100BSE | G | PWA BOM |  |
|  |  | NO | 51032HE00-185-G | MOS N,FDB047N10,100V,120A,3.9m@10V,G,TO263-3,SMD | FAIRCHILD SEMICONDUCTOR CORP | FDB047N10 | G | PWA BOM |  |
|  |  | ADD | 51032JY00-029-G | MOS N,SUM70040E-GE3,100V,120A,G,TO-263-3,SMD | VISHAY ENTER TECHNO LOGY.INC | SUM70040E-GE3 | G | PWA BOM |  |
|  |  | Delete | SUM70040E-GE3 | MOS N,SUM70040E-GE3,100V,120A,4.0m@10V,G,TO263-3,SMD | VISHAY ENTER TECHNO LOGY.INC | SUM70040E-GE3 | G | PWA BOM |  |
| 9 | PSRL2 |  | 63034GW00-088-G | IND,680nH@100KHz,+/-20%,34A,1.33mOhm,SHLD,G,SMD | COOPER BUSSMANN, INC. | HCM1305-R68-R | G | PWA BOM |  |
|  |  | ADD | 630365H00-034-G | IND,680nH@100KHz,+/-20%,29.5A,1.55mOhm,SHLD,G,SMD | CYNTEC CO. LTD | CMLB135T-R68MS | G | PWA BOM |  |
|  |  | Delete | CMLB135T-R68MS | IND,680nH@100KHz,+/-20%,34A,1.33mOhm,SHLD,G,SMD | CYNTEC CO. LTD | CMLB135T-R68MS | G | PWA BOM |  |
| 10 | PSTR17 |  | 61100QA00-017-G | RES,16KOhm,+/-0.1%,1/16W,G,SMD0402 | KOA SPEER ELECTRONICS, INC. | RN731ETTP1602B25 | G | PWA BOM |  |
|  |  | ADD | 61100QA01-024-G | RES,16KOhm,+/-0.1%,1/16W,G,SMD0402 | PANASONIC INDUSTRIAL CO.,LTD. | ERA2AEB163X | G | PWA BOM |  |
|  |  | NO | 61100QA00-029-G | RES,16KOhm,+/-0.1%,1/16W,G,SMD0402 | VISHAY ENTER TECHNO LOGY.INC | TNPW040216K0BEED | G | PWA BOM |  |
|  |  | Delete | ERA2AEB163X | RES,16KOhm,+/-0.1%,1/16W,G,SMD0402 | PANASONIC INDUSTRIAL CO.,LTD. | ERA2AEB163X | G | PWA BOM |  |
| 11 | PSTR19 |  | 61100J401-017-G | RES,1.78KOhm,+/-0.1%,1/16W,G,SMD0402 | KOA SPEER ELECTRONICS, INC. | RN73H1ETTP1781B25 | G | PWA BOM |  |
|  |  | NO | 61100J400-024-G | RES,1.78KOhm,+/-0.1%,1/16W,G,SMD0402 | PANASONIC INDUSTRIAL CO.,LTD. | ERA2AEB1781X | G | PWA BOM |  |
|  |  | ADD | 61100J400-029-G | RES,1.78KOhm,+/-0.1%,1/16W,G,SMD0402 | VISHAY ENTER TECHNO LOGY.INC | MCS0402MD1781BE000 | G | PWA BOM |  |
|  |  | Delete | MCS0402MD1781BE000 | RES,1.78KOhm,+/-0.1%,1/16W,G,SMD0402 | VISHAY ENTER TECHNO LOGY.INC | MCS0402MD1781BE000 | G | PWA BOM |  |
| 12 | QN2,QN3 |  | 510503B00-223-G | MOS N/N,NTZD3154NT1G,20V,0.54A,550m24.5V,G,SOT563-6,SMD | ON SEMICONDUCTOR CORP | NTZD3154NT1G | G | PWA BOM |  |
|  |  | ADD | 51050L500-029-G | MOS,N/N,Si1034CX-T1-GE3,20V,0.61A,G,SC-89-6,SMD | VISHAY ENTER TECHNO LOGY.INC | Si1034CX-T1-GE3 | G | PWA BOM |  |
|  |  | NO | 51050KW00-131-G | MOS N/N,SSM6N36FE,20V,500mA,0.63@5V,G,ES6-6,SMD | TOSHIBA ELECTRONICS ASIA LTD | SSM6N36FE | G | PWA BOM |  |
|  |  | Delete | Si1034CX-T1-GE3 | MOS N/N,Si1034CX,20V,0.5A,1ohm@4V,G,EMT-6,SMD | VISHAY ENTER TECHNO LOGY.INC | Si1034CX-T1-GE3 | G | PWA BOM |  |
| 13 | Q5,Q7 |  | 510406000-185-G | MOS P,FDD6685,30V,11A,30m@4.5V,G,TO252-3,SMD | FAIRCHILD SEMICONDUCTOR CORP | FDD6685 | G | PWA BOM |  |
|  |  | ADD | 510410800-221-G | MOS P,IPD042P03L3G,-30V,-70A,4.2m@-10V,G,TO-252-3,SMD | INFINEON TECHNOLOGIES CORP. | IPD042P03L3G | G | PWA BOM |  |
|  |  | NO | 51040WQ00-131-G | MOS P,TJ40S04M3L,-40V,-40A,9.1m@-10V,G,SMD-3 | TOSHIBA ELECTRONICS ASIA LTD | TJ40S04M3L | G | PWA BOM |  |
|  |  | Delete | IPD042P03L3 | MOS P,30V,11A,30m@4.5V,G,TO252-3,SMD | INFINEON TECHNOLOGIES CORP. | IPD042P03L3 | G | PWA BOM |  |
| 14 | J23,J24,J25,J26 |  | 3406A2B00-317-G | CONN,Header,WTB,1X4,V/T,Bla,2.54mm,15u,G,DIP-4 | MOLEX INCORPORATED | 171856-1104 | G | PWA BOM |  |
|  |  | ADD | 3406BJ100-278-G | CONN,Header,WTB,1X4,V/T,Bla,2.54mm,15u,G,DIP-4 | TYCO ELECTRONICS CORPORATION | 640456-4 | G | PWA BOM |  |
|  |  | NO | 3406AYG00-637-G | Header&Socket Connector,2111100400-0141,Wire-to-Board Header,4,DIP,NY66,2.54mm,15u",Black,G | LONG SHOUNG CO.,LTD. | 2111100400-0141 | G | PWA BOM |  |
|  |  | Delete | 640456-4 | CONN,Header,WTB,1X4,V/T,Bla,2.54mm,15u,G,DIP-4 | TYCO ELECTRONICS CORPORATION | 640456-4 | G | PWA BOM |  |
| OOOOOOOOOOOOOOOOOOOOOOOOOOOOOOOOOOOOOOOOOOOOOOOOOOOOOOOOOOOOOOOOOOOOOOOOOOOOOOOOOOOOOOOOOO | OOOOOOOOOOOOOOOOOOOOOOOOOOOOOOOOOOOOOOOOOOOOOOOOOOOOOOOOOOOOOOOOOOOOOOOOOOOOOOOOOOOOOOOOOO | OOOOOOOOOOOOOOOOOOOOOOOOOOOOOOOOOOOOOOOOOOOOOOOOOOOOOOOOOOOOOOOOOOOOOOOOOOOOOOOOOOOOOOOOOO | OOOOOOOOOOOOOOOOOOOOOOOOOOOOOOOOOOOOOOOOOOOOOOOOOOOOOOOOOOOOOOOOOOOOOOOOOOOOOOOOOOOOOOOOOO | OOOOOOOOOOOOOOOOOOOOOOOOOOOOOOOOOOOOOOOOOOOOOOOOOOOOOOOOOOOOOOOOOOOOOOOOOOOOOOOOOOOOOOOOOO | OOOOOOOOOOOOOOOOOOOOOOOOOOOOOOOOOOOOOOOOOOOOOOOOOOOOOOOOOOOOOOOOOOOOOOOOOOOOOOOOOOOOOOOOOO | OOOOOOOOOOOOOOOOOOOOOOOOOOOOOOOOOOOOOOOOOOOOOOOOOOOOOOOOOOOOOOOOOOOOOOOOOOOOOOOOOOOOOOOOOO | OOOOOOOOOOOOOOOOOOOOOOOOOOOOOOOOOOOOOOOOOOOOOOOOOOOOOOOOOOOOOOOOOOOOOOOOOOOOOOOOOOOOOOOOOO | OOOOOOOOOOOOOOOOOOOOOOOOOOOOOOOOOOOOOOOOOOOOOOOOOOOOOOOOOOOOOOOOOOOOOOOOOOOOOOOOOOOOOOOOOO | OOOOOOOOOOOOOOOOOOOOOOOOOOOOOOOOOOOOOOOOOOOOOOOOOOOOOOOOOOOOOOOOOOOOOOOOOOOOOOOOOOOOOOOOOO |
| Master Materials Change |  |  |  |  |  |  |  |  |  |
| Item | Foxconn P/N | Orig._Usage | New_Usage | Part Description | Manufacturer Full Name | Manufacturer P/N | RoHS | Location | Sheet |
| 1 | 62111U700-024-G | 0 | 6 | ECAP,68uF,+/-20%,100V,105C,320mOhm,G,SMD12.5*13.5 | PANASONIC INDUSTRIAL CO.,LTD. | EEEFK2A680AQ | G | (+)PSUCE1,PBACE1,PAACE1,PSUCE2,PBACE2,PAACE2 | PWA BOM |
| 2 | 520103B00-185-G | 0 | 8 | Diode,Rectifier&Switching,MMBD1205,100V,200mA,G,SOT-23-3,SMD | FAIRCHILD SEMICONDUCTOR CORP | MMBD1205 | G | (+)PBMD1,PBFD1,PBED1,PBAD1,PAMD1,PAFD1,PAED1,PAAD1 | PWA BOM |
| 3 | PE38993-51BC1-1H | 0 | 2 | POWER9 CPU Socket for LGA3899-HYBRID | FOXCONN TECHNOLOGY CO.,LTD. | PE38993-51BC1-1H | G | (+)U1,U10 | PWA BOM |
| 4 | 52030DA00-237-G | 16 | 0 | DIODE,Schottky,BAT46W-7-F,100V,150mA,G,SOD123-2,SMD | DIODES INEORPORATION | BAT46W-7-F | G | (-)PBMD1,PBFD1,PBED1,PBAD1,PAMD1,PAFD1,PAED1,PAAD1,PBMD4,PBFD4,PBED4,PAMD4,PAFD4,PAED4,PBAD5,PAAD5 | PWA BOM |
| 5 | EEEFK2A680AQ | 6 | 0 | ECAP,68uF,+/-20%,100V,105C,G,SMD12.5*13.5,ESR<=320mOhm | PANASONIC INDUSTRIAL CO.,LTD. | EEEFK2A680AQ | G | (-)PSUCE1,PBACE1,PAACE1,PSUCE2,PBACE2,PAACE2 | PWA BOM |
| 6 | 340108S00-600-G | 2 | 0 | POWER9 CPU Socket for LGA3899-HYBRID | FOXCONN TECHNOLOGY CO.,LTD. | PE38993-51BC0-1H | G | (-)U1,U10 | PWA BOM |
| OOOOOOOOOOOOOOOOOOOOOOOOOOOOOOOOOOOOOOOOOOOOOOOOOOOOOOOOOOOOOOOOOOOOOOOOOOOOOOOOOOOOOOOOOO | OOOOOOOOOOOOOOOOOOOOOOOOOOOOOOOOOOOOOOOOOOOOOOOOOOOOOOOOOOOOOOOOOOOOOOOOOOOOOOOOOOOOOOOOOO | OOOOOOOOOOOOOOOOOOOOOOOOOOOOOOOOOOOOOOOOOOOOOOOOOOOOOOOOOOOOOOOOOOOOOOOOOOOOOOOOOOOOOOOOOO | OOOOOOOOOOOOOOOOOOOOOOOOOOOOOOOOOOOOOOOOOOOOOOOOOOOOOOOOOOOOOOOOOOOOOOOOOOOOOOOOOOOOOOOOOO | OOOOOOOOOOOOOOOOOOOOOOOOOOOOOOOOOOOOOOOOOOOOOOOOOOOOOOOOOOOOOOOOOOOOOOOOOOOOOOOOOOOOOOOOOO | OOOOOOOOOOOOOOOOOOOOOOOOOOOOOOOOOOOOOOOOOOOOOOOOOOOOOOOOOOOOOOOOOOOOOOOOOOOOOOOOOOOOOOOOOO | OOOOOOOOOOOOOOOOOOOOOOOOOOOOOOOOOOOOOOOOOOOOOOOOOOOOOOOOOOOOOOOOOOOOOOOOOOOOOOOOOOOOOOOOOO | OOOOOOOOOOOOOOOOOOOOOOOOOOOOOOOOOOOOOOOOOOOOOOOOOOOOOOOOOOOOOOOOOOOOOOOOOOOOOOOOOOOOOOOOOO | OOOOOOOOOOOOOOOOOOOOOOOOOOOOOOOOOOOOOOOOOOOOOOOOOOOOOOOOOOOOOOOOOOOOOOOOOOOOOOOOOOOOOOOOOO | OOOOOOOOOOOOOOOOOOOOOOOOOOOOOOOOOOOOOOOOOOOOOOOOOOOOOOOOOOOOOOOOOOOOOOOOOOOOOOOOOOOOOOOOOO |
| TLA Parts Change |  |  |  |  |  |  |  |  |  |
| Item | Foxconn P/N | Qty | Part Description | Manufacturer Full Name | Manufacturer P/N | RoHS | Location | Remark | BOM |
| BOM Change List Date:Sat Aug 26 10:56:01 GMT+08:00 2017 |  |  |  |  |  |  |  |  |  |
| New BOM file : E:\barreleye g2\0825\Zaius Bom\Zaius0825.xls |  |  |  |  |  |  |  |  |  |
| Old BOM file : E:\barreleye g2\0825\Zaius Bom\Zaius0821.xls |  |  |  |  |  |  |  |  |  |
| ##### Add Parts |  |  |  |  |  |  |  |  |  |
| Item | Location | Qty | Foxconn P/N | Part Description | Manufacturer Full Name | Manufacturer P/N | RoHS | Sheet |  |
| ##### Remove Parts |  |  |  |  |  |  |  |  |  |
| Item | Location | Qty | Foxconn P/N | Part Description | Manufacturer Full Name | Manufacturer P/N | RoHS | Sheet |  |
| ##### Change Parts |  |  |  |  |  |  |  |  |  |
| Item | Location | Qty | Foxconn P/N | Part Description | Manufacturer Full Name | Manufacturer P/N | RoHS | Sheet | Remark |
| 1 | PCIE2,PCIE3,PCIE4 | 3 | 10061913-103HLF | CONN,PCIE-16X,V/T,Bla,1mm,30u,G,SMD-164 | FCI CONNECTORS HONGKONG LTD. | 10061913-103HLF | G | PWA BOM | In New BOM |
|  |  |  | 2041366-9 | CONN,PCIE-16X,V/T,Bla,1mm,30u,G,SMD-164 | TYCO ELECTRONICS CORPORATION | 2041366-9 | G | PWA BOM | In New BOM |
|  | PCIE2,PCIE3,PCIE4 | 3 | 10061913-103HLF | CONN,PCIE-16X,V/T,Bla,1mm,30u,G,SMD-164 | FCI CONNECTORS HONGKONG LTD. | 10061913-103HLF | G | PWA BOM | In Old BOM |
|  |  |  | 340320Q00-278-G | CONN,PCIE-16X,V/T,Bla,1mm,30u,G,SMD-164 | TYCO ELECTRONICS CORPORATION | 2041366-6 | G | PWA BOM | In Old BOM |
| 2 | PSUU1 | 1 | 880302300-065-G | Converter,input 40V~60V,600W,G,Q54SJ12050NNDH,OVAL | DELTA ELECTRONICS INDUSTRIAL CO.,LTD | Q54SJ12050NNDH | G | PWA BOM | In New BOM |
|  |  |  | 880302100-065-G | Converter,input 40V~60V,600W,G,Q54SH12050NNDH | DELTA ELECTRONICS INDUSTRIAL CO.,LTD | Q54SH12050NNDH | G | PWA BOM | In New BOM |
|  | PSUU1 | 1 | 880302300-065-G | Converter,input 40V~60V,600W,G,Q54SJ12050NNDH,OVAL | DELTA ELECTRONICS INDUSTRIAL CO.,LTD | Q54SJ12050NNDH | G | PWA BOM | In Old BOM |
|  |  |  | 880302100-065-G | Converter,input 40V~60V,600W,G,Q54SH12050NNDH | DELTA ELECTRONICS INDUSTRIAL CO.,LTD | Q54SH12050NNDH | G | PWA BOM | In Old BOM |
|  |  |  | 880302A00-462-G | Converter,input 40V~60V,650W,G,BMR458 2130/004 | Ericsson | BMR458 2130/004 | G | PWA BOM | In Old BOM |
| 3 | U1,U10 | 2 | 340109B00-600-G | CONN,CPU Socket,0.75mm,30u,G,SMD-3899 | FOXCONN TECHNOLOGY CO.,LTD. | PE38993-51BC1-1H | G | PWA BOM | In New BOM |
|  | U1,U10 | 2 | PE38993-51BC1-1H | POWER9 CPU Socket for LGA3899-HYBRID | FOXCONN TECHNOLOGY CO.,LTD. | PE38993-51BC1-1H | G | PWA BOM | In Old BOM |
| ##### Change Revision |  |  |  |  |  |  |  |  |  |
| Sheet | REV OF BOM | CUSTOMER | CUSTOMER P/N | PWA PN | PWA DESCRIPTION | PWA REV | DATE | Remark |  |
| OOOOOOOOOOOOOOOOOOOOOOOOOOOOOOOOOOOOOOOOOOOOOOOOOOOOOOOOOOOOOOOOOOOOOOOOOOOOOOOOOOOOOOOOOO | OOOOOOOOOOOOOOOOOOOOOOOOOOOOOOOOOOOOOOOOOOOOOOOOOOOOOOOOOOOOOOOOOOOOOOOOOOOOOOOOOOOOOOOOOO | OOOOOOOOOOOOOOOOOOOOOOOOOOOOOOOOOOOOOOOOOOOOOOOOOOOOOOOOOOOOOOOOOOOOOOOOOOOOOOOOOOOOOOOOOO | OOOOOOOOOOOOOOOOOOOOOOOOOOOOOOOOOOOOOOOOOOOOOOOOOOOOOOOOOOOOOOOOOOOOOOOOOOOOOOOOOOOOOOOOOO | OOOOOOOOOOOOOOOOOOOOOOOOOOOOOOOOOOOOOOOOOOOOOOOOOOOOOOOOOOOOOOOOOOOOOOOOOOOOOOOOOOOOOOOOOO | OOOOOOOOOOOOOOOOOOOOOOOOOOOOOOOOOOOOOOOOOOOOOOOOOOOOOOOOOOOOOOOOOOOOOOOOOOOOOOOOOOOOOOOOOO | OOOOOOOOOOOOOOOOOOOOOOOOOOOOOOOOOOOOOOOOOOOOOOOOOOOOOOOOOOOOOOOOOOOOOOOOOOOOOOOOOOOOOOOOOO | OOOOOOOOOOOOOOOOOOOOOOOOOOOOOOOOOOOOOOOOOOOOOOOOOOOOOOOOOOOOOOOOOOOOOOOOOOOOOOOOOOOOOOOOOO | OOOOOOOOOOOOOOOOOOOOOOOOOOOOOOOOOOOOOOOOOOOOOOOOOOOOOOOOOOOOOOOOOOOOOOOOOOOOOOOOOOOOOOOOOO | OOOOOOOOOOOOOOOOOOOOOOOOOOOOOOOOOOOOOOOOOOOOOOOOOOOOOOOOOOOOOOOOOOOOOOOOOOOOOOOOOOOOOOOOOO |
| Second Source Change |  |  |  |  |  |  |  |  |  |
| Item | Location | Change Type | Foxconn P/N | Part Description | Manufacturer Full Name | Manufacturer P/N | RoHS | Sheet |  |
| 1 | PCIE2,PCIE3,PCIE4 |  | 10061913-103HLF | CONN,PCIE-16X,V/T,Bla,1mm,30u,G,SMD-164 | FCI CONNECTORS HONGKONG LTD. | 10061913-103HLF | G | PWA BOM |  |
|  |  | ADD | 2041366-9 | CONN,PCIE-16X,V/T,Bla,1mm,30u,G,SMD-164 | TYCO ELECTRONICS CORPORATION | 2041366-9 | G | PWA BOM |  |
|  |  | Delete | 340320Q00-278-G | CONN,PCIE-16X,V/T,Bla,1mm,30u,G,SMD-164 | TYCO ELECTRONICS CORPORATION | 2041366-6 | G | PWA BOM |  |
| 2 | PSUU1 |  | 880302300-065-G | Converter,input 40V~60V,600W,G,Q54SJ12050NNDH,OVAL | DELTA ELECTRONICS INDUSTRIAL CO.,LTD | Q54SJ12050NNDH | G | PWA BOM |  |
|  |  | NO | 880302100-065-G | Converter,input 40V~60V,600W,G,Q54SH12050NNDH | DELTA ELECTRONICS INDUSTRIAL CO.,LTD | Q54SH12050NNDH | G | PWA BOM |  |
|  |  | Delete | 880302A00-462-G | Converter,input 40V~60V,650W,G,BMR458 2130/004 | Ericsson | BMR458 2130/004 | G | PWA BOM |  |
| OOOOOOOOOOOOOOOOOOOOOOOOOOOOOOOOOOOOOOOOOOOOOOOOOOOOOOOOOOOOOOOOOOOOOOOOOOOOOOOOOOOOOOOOOO | OOOOOOOOOOOOOOOOOOOOOOOOOOOOOOOOOOOOOOOOOOOOOOOOOOOOOOOOOOOOOOOOOOOOOOOOOOOOOOOOOOOOOOOOOO | OOOOOOOOOOOOOOOOOOOOOOOOOOOOOOOOOOOOOOOOOOOOOOOOOOOOOOOOOOOOOOOOOOOOOOOOOOOOOOOOOOOOOOOOOO | OOOOOOOOOOOOOOOOOOOOOOOOOOOOOOOOOOOOOOOOOOOOOOOOOOOOOOOOOOOOOOOOOOOOOOOOOOOOOOOOOOOOOOOOOO | OOOOOOOOOOOOOOOOOOOOOOOOOOOOOOOOOOOOOOOOOOOOOOOOOOOOOOOOOOOOOOOOOOOOOOOOOOOOOOOOOOOOOOOOOO | OOOOOOOOOOOOOOOOOOOOOOOOOOOOOOOOOOOOOOOOOOOOOOOOOOOOOOOOOOOOOOOOOOOOOOOOOOOOOOOOOOOOOOOOOO | OOOOOOOOOOOOOOOOOOOOOOOOOOOOOOOOOOOOOOOOOOOOOOOOOOOOOOOOOOOOOOOOOOOOOOOOOOOOOOOOOOOOOOOOOO | OOOOOOOOOOOOOOOOOOOOOOOOOOOOOOOOOOOOOOOOOOOOOOOOOOOOOOOOOOOOOOOOOOOOOOOOOOOOOOOOOOOOOOOOOO | OOOOOOOOOOOOOOOOOOOOOOOOOOOOOOOOOOOOOOOOOOOOOOOOOOOOOOOOOOOOOOOOOOOOOOOOOOOOOOOOOOOOOOOOOO | OOOOOOOOOOOOOOOOOOOOOOOOOOOOOOOOOOOOOOOOOOOOOOOOOOOOOOOOOOOOOOOOOOOOOOOOOOOOOOOOOOOOOOOOOO |
| Master Materials Change |  |  |  |  |  |  |  |  |  |
| Item | Foxconn P/N | Orig._Usage | New_Usage | Part Description | Manufacturer Full Name | Manufacturer P/N | RoHS | Location | Sheet |
| 1 | 340109B00-600-G | 0 | 2 | CONN,CPU Socket,0.75mm,30u,G,SMD-3899 | FOXCONN TECHNOLOGY CO.,LTD. | PE38993-51BC1-1H | G | (+)U1,U10 | PWA BOM |
| 2 | PE38993-51BC1-1H | 2 | 0 | POWER9 CPU Socket for LGA3899-HYBRID | FOXCONN TECHNOLOGY CO.,LTD. | PE38993-51BC1-1H | G | (-)U1,U10 | PWA BOM |
| OOOOOOOOOOOOOOOOOOOOOOOOOOOOOOOOOOOOOOOOOOOOOOOOOOOOOOOOOOOOOOOOOOOOOOOOOOOOOOOOOOOOOOOOOO | OOOOOOOOOOOOOOOOOOOOOOOOOOOOOOOOOOOOOOOOOOOOOOOOOOOOOOOOOOOOOOOOOOOOOOOOOOOOOOOOOOOOOOOOOO | OOOOOOOOOOOOOOOOOOOOOOOOOOOOOOOOOOOOOOOOOOOOOOOOOOOOOOOOOOOOOOOOOOOOOOOOOOOOOOOOOOOOOOOOOO | OOOOOOOOOOOOOOOOOOOOOOOOOOOOOOOOOOOOOOOOOOOOOOOOOOOOOOOOOOOOOOOOOOOOOOOOOOOOOOOOOOOOOOOOOO | OOOOOOOOOOOOOOOOOOOOOOOOOOOOOOOOOOOOOOOOOOOOOOOOOOOOOOOOOOOOOOOOOOOOOOOOOOOOOOOOOOOOOOOOOO | OOOOOOOOOOOOOOOOOOOOOOOOOOOOOOOOOOOOOOOOOOOOOOOOOOOOOOOOOOOOOOOOOOOOOOOOOOOOOOOOOOOOOOOOOO | OOOOOOOOOOOOOOOOOOOOOOOOOOOOOOOOOOOOOOOOOOOOOOOOOOOOOOOOOOOOOOOOOOOOOOOOOOOOOOOOOOOOOOOOOO | OOOOOOOOOOOOOOOOOOOOOOOOOOOOOOOOOOOOOOOOOOOOOOOOOOOOOOOOOOOOOOOOOOOOOOOOOOOOOOOOOOOOOOOOOO | OOOOOOOOOOOOOOOOOOOOOOOOOOOOOOOOOOOOOOOOOOOOOOOOOOOOOOOOOOOOOOOOOOOOOOOOOOOOOOOOOOOOOOOOOO | OOOOOOOOOOOOOOOOOOOOOOOOOOOOOOOOOOOOOOOOOOOOOOOOOOOOOOOOOOOOOOOOOOOOOOOOOOOOOOOOOOOOOOOOOO |
| TLA Parts Change |  |  |  |  |  |  |  |  |  |
| Item | Foxconn P/N | Qty | Part Description | Manufacturer Full Name | Manufacturer P/N | RoHS | Location | Remark | BOM |
| BOM Change List Date:Mon Aug 28 14:36:04 GMT+08:00 2017 |  |  |  |  |  |  |  |  |  |
| New BOM file : E:\barreleye g2\0828\foxbis\zaius0828.xls |  |  |  |  |  |  |  |  |  |
| Old BOM file : E:\barreleye g2\0828\foxbis\zaius0825.xls |  |  |  |  |  |  |  |  |  |
| ##### Add Parts |  |  |  |  |  |  |  |  |  |
| Item | Location | Qty | Foxconn P/N | Part Description | Manufacturer Full Name | Manufacturer P/N | RoHS | Sheet |  |
| ##### Remove Parts |  |  |  |  |  |  |  |  |  |
| Item | Location | Qty | Foxconn P/N | Part Description | Manufacturer Full Name | Manufacturer P/N | RoHS | Sheet |  |
| ##### Change Parts |  |  |  |  |  |  |  |  |  |
| Item | Location | Qty | Foxconn P/N | Part Description | Manufacturer Full Name | Manufacturer P/N | RoHS | Sheet | Remark |
| 1 | PBAR65,PAAR65 | 2 | 610606G00-017-G | RES,20mOhm,+/-1%,5W,G,SMD2512 | KOA SPEER ELECTRONICS, INC. | TLRH3APTTE20L0F | G | PWA BOM | In New BOM |
|  |  |  | 610605400-125-G | RES,20mOhm,+/-1%,1W,G,SMD2512 | INTERNATIONAL RESISTIVE COMPANY, INC. | LRMAP2512-R02FT4 | G | PWA BOM | In New BOM |
|  | PBAR65,PAAR65 | 2 | TLRH3APTTE20L0F | RES,20mOhm,+/-1%,2W,G,SMD2512 | KOA SPEER ELECTRONICS, INC. | TLRH3APTTE20L0F | G | PWA BOM | In Old BOM |
|  |  |  | LRMAP2512-R02FT4 | RES,20mOhm,+/-1%,2W,G,SMD2512 | INTERNATIONAL RESISTIVE COMPANY, INC. | LRMAP2512-R02FT4 | G | PWA BOM | In Old BOM |
| 2 | PBER65,PAFR65,PAER65,PBFR66 | 4 | 610606H00-017-G | RES,50mOhm,+/-1%,1.5W,G,SMD2512 | KOA SPEER ELECTRONICS, INC. | SLW1TTE50L0F | G | PWA BOM | In New BOM |
|  |  |  | 610606E00-125-G | RES,50mOhm,+/-1%,1W,G,SMD2512 | INTERNATIONAL RESISTIVE COMPANY, INC. | LRMAP2512-R05FT4 | G | PWA BOM | In New BOM |
|  | PBER65,PAFR65,PAER65,PBFR66 | 4 | SLW1TTE50L0F | RES,50mOhm,+/-1%,1.5W,G,SMD2512 | KOA | SLW1TTE50L0F | G | PWA BOM | In Old BOM |
|  |  |  | LRMAP2512-R05FT4 | RES,50mOhm,+/-1%,1.5W,G,SMD2512 | INTERNATIONAL RESISTIVE COMPANY, INC. | LRMAP2512-R05FT4 | G | PWA BOM | In Old BOM |
| 3 | PBMR34,PAMR34 | 2 | 61100YW00-017-G | RES,316 Ohm,+/-0.1%,1/16W,G,SMD0402 | KOA SPEER ELECTRONICS, INC. | RN731ETTP3160B25 | G | PWA BOM | In New BOM |
|  | PBMR34,PAMR34 | 2 | RN731ETTP3160B25 | RES,316 Ohm,+/-0.1%,1/16W,G,SMD0402 | KOA SPEER ELECTRONICS, INC. | RN731ETTP3160B25 | G | PWA BOM | In Old BOM |
| 4 | PBMR65,PAMR65 | 2 | 610606J00-017-G | RES,75mOhm,+/-1%,1.5W,G,SMD2512 | KOA SPEER ELECTRONICS, INC. | SLW1TTE75L0F | G | PWA BOM | In New BOM |
|  |  |  | 610606D00-125-G | RES,75mOhm,+/-1%,1W,G,SMD2512 | INTERNATIONAL RESISTIVE COMPANY, INC. | LRMAP2512-R075FT4 | G | PWA BOM | In New BOM |
|  | PBMR65,PAMR65 | 2 | SLW1TTE75L0F | RES,75mOhm,+/-1%,1.5W,G,SMD2512 | KOA | SLW1TTE75L0F | G | PWA BOM | In Old BOM |
|  |  |  | LRMAP2512-R075FT4 | RES,75mOhm,+/-1%,1.5W,G,SMD2512 | INTERNATIONAL RESISTIVE COMPANY, INC. | LRMAP2512-R075FT4 | G | PWA BOM | In Old BOM |
| ##### Change Revision |  |  |  |  |  |  |  |  |  |
| Sheet | REV OF BOM | CUSTOMER | CUSTOMER P/N | PWA PN | PWA DESCRIPTION | PWA REV | DATE | Remark |  |
| OOOOOOOOOOOOOOOOOOOOOOOOOOOOOOOOOOOOOOOOOOOOOOOOOOOOOOOOOOOOOOOOOOOOOOOOOOOOOOOOOOOOOOOOOO | OOOOOOOOOOOOOOOOOOOOOOOOOOOOOOOOOOOOOOOOOOOOOOOOOOOOOOOOOOOOOOOOOOOOOOOOOOOOOOOOOOOOOOOOOO | OOOOOOOOOOOOOOOOOOOOOOOOOOOOOOOOOOOOOOOOOOOOOOOOOOOOOOOOOOOOOOOOOOOOOOOOOOOOOOOOOOOOOOOOOO | OOOOOOOOOOOOOOOOOOOOOOOOOOOOOOOOOOOOOOOOOOOOOOOOOOOOOOOOOOOOOOOOOOOOOOOOOOOOOOOOOOOOOOOOOO | OOOOOOOOOOOOOOOOOOOOOOOOOOOOOOOOOOOOOOOOOOOOOOOOOOOOOOOOOOOOOOOOOOOOOOOOOOOOOOOOOOOOOOOOOO | OOOOOOOOOOOOOOOOOOOOOOOOOOOOOOOOOOOOOOOOOOOOOOOOOOOOOOOOOOOOOOOOOOOOOOOOOOOOOOOOOOOOOOOOOO | OOOOOOOOOOOOOOOOOOOOOOOOOOOOOOOOOOOOOOOOOOOOOOOOOOOOOOOOOOOOOOOOOOOOOOOOOOOOOOOOOOOOOOOOOO | OOOOOOOOOOOOOOOOOOOOOOOOOOOOOOOOOOOOOOOOOOOOOOOOOOOOOOOOOOOOOOOOOOOOOOOOOOOOOOOOOOOOOOOOOO | OOOOOOOOOOOOOOOOOOOOOOOOOOOOOOOOOOOOOOOOOOOOOOOOOOOOOOOOOOOOOOOOOOOOOOOOOOOOOOOOOOOOOOOOOO | OOOOOOOOOOOOOOOOOOOOOOOOOOOOOOOOOOOOOOOOOOOOOOOOOOOOOOOOOOOOOOOOOOOOOOOOOOOOOOOOOOOOOOOOOO |
| Second Source Change |  |  |  |  |  |  |  |  |  |
| Item | Location | Change Type | Foxconn P/N | Part Description | Manufacturer Full Name | Manufacturer P/N | RoHS | Sheet |  |
| OOOOOOOOOOOOOOOOOOOOOOOOOOOOOOOOOOOOOOOOOOOOOOOOOOOOOOOOOOOOOOOOOOOOOOOOOOOOOOOOOOOOOOOOOO | OOOOOOOOOOOOOOOOOOOOOOOOOOOOOOOOOOOOOOOOOOOOOOOOOOOOOOOOOOOOOOOOOOOOOOOOOOOOOOOOOOOOOOOOOO | OOOOOOOOOOOOOOOOOOOOOOOOOOOOOOOOOOOOOOOOOOOOOOOOOOOOOOOOOOOOOOOOOOOOOOOOOOOOOOOOOOOOOOOOOO | OOOOOOOOOOOOOOOOOOOOOOOOOOOOOOOOOOOOOOOOOOOOOOOOOOOOOOOOOOOOOOOOOOOOOOOOOOOOOOOOOOOOOOOOOO | OOOOOOOOOOOOOOOOOOOOOOOOOOOOOOOOOOOOOOOOOOOOOOOOOOOOOOOOOOOOOOOOOOOOOOOOOOOOOOOOOOOOOOOOOO | OOOOOOOOOOOOOOOOOOOOOOOOOOOOOOOOOOOOOOOOOOOOOOOOOOOOOOOOOOOOOOOOOOOOOOOOOOOOOOOOOOOOOOOOOO | OOOOOOOOOOOOOOOOOOOOOOOOOOOOOOOOOOOOOOOOOOOOOOOOOOOOOOOOOOOOOOOOOOOOOOOOOOOOOOOOOOOOOOOOOO | OOOOOOOOOOOOOOOOOOOOOOOOOOOOOOOOOOOOOOOOOOOOOOOOOOOOOOOOOOOOOOOOOOOOOOOOOOOOOOOOOOOOOOOOOO | OOOOOOOOOOOOOOOOOOOOOOOOOOOOOOOOOOOOOOOOOOOOOOOOOOOOOOOOOOOOOOOOOOOOOOOOOOOOOOOOOOOOOOOOOO | OOOOOOOOOOOOOOOOOOOOOOOOOOOOOOOOOOOOOOOOOOOOOOOOOOOOOOOOOOOOOOOOOOOOOOOOOOOOOOOOOOOOOOOOOO |
| Master Materials Change |  |  |  |  |  |  |  |  |  |
| Item | Foxconn P/N | Orig._Usage | New_Usage | Part Description | Manufacturer Full Name | Manufacturer P/N | RoHS | Location | Sheet |
| 1 | 610606G00-017-G | 0 | 2 | RES,20mOhm,+/-1%,5W,G,SMD2512 | KOA SPEER ELECTRONICS, INC. | TLRH3APTTE20L0F | G | (+)PBAR65,PAAR65 | PWA BOM |
|  | 610605400-125-G |  |  | RES,20mOhm,+/-1%,1W,G,SMD2512 | INTERNATIONAL RESISTIVE COMPANY, INC. | LRMAP2512-R02FT4 |  |  | PWA BOM |
| 2 | 610606H00-017-G | 0 | 4 | RES,50mOhm,+/-1%,1.5W,G,SMD2512 | KOA SPEER ELECTRONICS, INC. | SLW1TTE50L0F | G | (+)PBER65,PAFR65,PAER65,PBFR66 | PWA BOM |
|  | 610606E00-125-G |  |  | RES,50mOhm,+/-1%,1W,G,SMD2512 | INTERNATIONAL RESISTIVE COMPANY, INC. | LRMAP2512-R05FT4 |  |  | PWA BOM |
| 3 | 61100YW00-017-G | 0 | 2 | RES,316 Ohm,+/-0.1%,1/16W,G,SMD0402 | KOA SPEER ELECTRONICS, INC. | RN731ETTP3160B25 | G | (+)PBMR34,PAMR34 | PWA BOM |
| 4 | 610606J00-017-G | 0 | 2 | RES,75mOhm,+/-1%,1.5W,G,SMD2512 | KOA SPEER ELECTRONICS, INC. | SLW1TTE75L0F | G | (+)PBMR65,PAMR65 | PWA BOM |
|  | 610606D00-125-G |  |  | RES,75mOhm,+/-1%,1W,G,SMD2512 | INTERNATIONAL RESISTIVE COMPANY, INC. | LRMAP2512-R075FT4 |  |  | PWA BOM |
| 5 | TLRH3APTTE20L0F | 2 | 0 | RES,20mOhm,+/-1%,2W,G,SMD2512 | KOA SPEER ELECTRONICS, INC. | TLRH3APTTE20L0F | G | (-)PBAR65,PAAR65 | PWA BOM |
|  | LRMAP2512-R02FT4 |  |  | RES,20mOhm,+/-1%,2W,G,SMD2512 | INTERNATIONAL RESISTIVE COMPANY, INC. | LRMAP2512-R02FT4 |  |  | PWA BOM |
| 6 | SLW1TTE50L0F | 4 | 0 | RES,50mOhm,+/-1%,1.5W,G,SMD2512 | KOA | SLW1TTE50L0F | G | (-)PBER65,PAFR65,PAER65,PBFR66 | PWA BOM |
|  | LRMAP2512-R05FT4 |  |  | RES,50mOhm,+/-1%,1.5W,G,SMD2512 | INTERNATIONAL RESISTIVE COMPANY, INC. | LRMAP2512-R05FT4 |  |  | PWA BOM |
| 7 | RN731ETTP3160B25 | 2 | 0 | RES,316 Ohm,+/-0.1%,1/16W,G,SMD0402 | KOA SPEER ELECTRONICS, INC. | RN731ETTP3160B25 | G | (-)PBMR34,PAMR34 | PWA BOM |
| 8 | SLW1TTE75L0F | 2 | 0 | RES,75mOhm,+/-1%,1.5W,G,SMD2512 | KOA | SLW1TTE75L0F | G | (-)PBMR65,PAMR65 | PWA BOM |
|  | LRMAP2512-R075FT4 |  |  | RES,75mOhm,+/-1%,1.5W,G,SMD2512 | INTERNATIONAL RESISTIVE COMPANY, INC. | LRMAP2512-R075FT4 |  |  | PWA BOM |
| OOOOOOOOOOOOOOOOOOOOOOOOOOOOOOOOOOOOOOOOOOOOOOOOOOOOOOOOOOOOOOOOOOOOOOOOOOOOOOOOOOOOOOOOOO | OOOOOOOOOOOOOOOOOOOOOOOOOOOOOOOOOOOOOOOOOOOOOOOOOOOOOOOOOOOOOOOOOOOOOOOOOOOOOOOOOOOOOOOOOO | OOOOOOOOOOOOOOOOOOOOOOOOOOOOOOOOOOOOOOOOOOOOOOOOOOOOOOOOOOOOOOOOOOOOOOOOOOOOOOOOOOOOOOOOOO | OOOOOOOOOOOOOOOOOOOOOOOOOOOOOOOOOOOOOOOOOOOOOOOOOOOOOOOOOOOOOOOOOOOOOOOOOOOOOOOOOOOOOOOOOO | OOOOOOOOOOOOOOOOOOOOOOOOOOOOOOOOOOOOOOOOOOOOOOOOOOOOOOOOOOOOOOOOOOOOOOOOOOOOOOOOOOOOOOOOOO | OOOOOOOOOOOOOOOOOOOOOOOOOOOOOOOOOOOOOOOOOOOOOOOOOOOOOOOOOOOOOOOOOOOOOOOOOOOOOOOOOOOOOOOOOO | OOOOOOOOOOOOOOOOOOOOOOOOOOOOOOOOOOOOOOOOOOOOOOOOOOOOOOOOOOOOOOOOOOOOOOOOOOOOOOOOOOOOOOOOOO | OOOOOOOOOOOOOOOOOOOOOOOOOOOOOOOOOOOOOOOOOOOOOOOOOOOOOOOOOOOOOOOOOOOOOOOOOOOOOOOOOOOOOOOOOO | OOOOOOOOOOOOOOOOOOOOOOOOOOOOOOOOOOOOOOOOOOOOOOOOOOOOOOOOOOOOOOOOOOOOOOOOOOOOOOOOOOOOOOOOOO | OOOOOOOOOOOOOOOOOOOOOOOOOOOOOOOOOOOOOOOOOOOOOOOOOOOOOOOOOOOOOOOOOOOOOOOOOOOOOOOOOOOOOOOOOO |
| TLA Parts Change |  |  |  |  |  |  |  |  |  |
| Item | Foxconn P/N | Qty | Part Description | Manufacturer Full Name | Manufacturer P/N | RoHS | Location | Remark | BOM |
| BOM Change List Date:Thu Aug 31 10:06:03 GMT+08:00 2017 |  |  |  |  |  |  |  |  |  |
| New BOM file : E:\barreleye g2\0830\foxbis\zaius 0831.xls |  |  |  |  |  |  |  |  |  |
| Old BOM file : E:\barreleye g2\0830\foxbis\zaius 0828.xls |  |  |  |  |  |  |  |  |  |
| ##### Add Parts |  |  |  |  |  |  |  |  |  |
| Item | Location | Qty | Foxconn P/N | Part Description | Manufacturer Full Name | Manufacturer P/N | RoHS | Sheet |  |
| ##### Remove Parts |  |  |  |  |  |  |  |  |  |
| Item | Location | Qty | Foxconn P/N | Part Description | Manufacturer Full Name | Manufacturer P/N | RoHS | Sheet |  |
| ##### Change Parts |  |  |  |  |  |  |  |  |  |
| Item | Location | Qty | Foxconn P/N | Part Description | Manufacturer Full Name | Manufacturer P/N | RoHS | Sheet | Remark |
| 1 | R4,R5,R9,R10,R103,R129,R130,R131,R150,R151,R154,R171,R172,R175,R192,R193,R195,R213,R214,R215,R234,R235,R236,R255,R256,R259,R276,R277,R279,R318,R319,R366,R367,R371,R372,R455,R458,R484,R485,R486,R505,R506,R509,R526,R527,R530,R547,R548,R550,R568,R569,R570,R589,R590,R591,R611,R612,R615,R631,R632,R634,R1072,R1080,R1232,R1340,R1341,R1350,R1351,R1352,R1353,R1354,R1355,R1356,R1357,R1358,R1359,R1361,R1363,R1364,R1365,R1366,R1367,R1377,R1378,R1379,R1380,R1381,R1382,R1383,R1384,R1385,R1386,R1387,R1388,R1389,R1390,R1391,R1392,R1746,R1775 | 100 | 610100T00-017-G | RES,1KOhm,+/-5%,1/16W,G,SMD0402 | KOA SPEER ELECTRONICS, INC. | RK73B1ETTP102J | G | PWA BOM | In New BOM |
|  |  |  | 610100T00-024-G | RES,1KOhm,+/-5%,1/16W,G,SMD0402 | PANASONIC INDUSTRIAL CO.,LTD. | ERJ2GEJ102X | G | PWA BOM | In New BOM |
|  |  |  | 610100T00-011-G | RES,1KOhm,+/-5%,1/16W,G,SMD0402 | YAGEO CORPORATION COMPONENT | RC0402JR-071KL | G | PWA BOM | In New BOM |
|  |  |  | 610100T00-044-G | RES,1KOhm,+/-5%,1/16W,G,SMD0402 | TA-I TECHNOLOGY CO., LTD. | RM04JTN102 | G | PWA BOM | In New BOM |
|  | R4,R5,R9,R10,R103,R129,R130,R131,R150,R151,R154,R171,R172,R175,R192,R193,R195,R213,R214,R215,R234,R235,R236,R255,R256,R259,R276,R277,R279,R318,R319,R366,R367,R371,R372,R455,R458,R484,R485,R486,R505,R506,R509,R526,R527,R530,R547,R548,R550,R568,R569,R570,R589,R590,R591,R611,R612,R615,R631,R632,R634,R1072,R1080,R1232,R1340,R1341,R1350,R1351,R1352,R1353,R1354,R1355,R1356,R1357,R1358,R1359,R1361,R1363,R1364,R1365,R1366,R1367,R1377,R1378,R1379,R1380,R1381,R1382,R1383,R1384,R1385,R1386,R1387,R1388,R1389,R1390,R1391,R1392,R1746,R1775 | 100 | 610100T00-017-G | RES,1KOhm,+/-5%,1/16W,G,SMD0402 | KOA SPEER ELECTRONICS, INC. | RK73B1ETTP102J | G | PWA BOM | In Old BOM |
|  |  |  | 610100T00-024-G | RES,1KOhm,+/-5%,1/16W,G,SMD0402 | PANASONIC INDUSTRIAL CO.,LTD. | ERJ2GEJ102X | G | PWA BOM | In Old BOM |
| 2 | R16,R17,R18,R19,R20,R21,R24,R25,R33,R34,R35,R36,R37,R46,R47,R48,R49,R50,R51,R65,R66,R69,R76,R94,R95,R99,R100,R101,R104,R105,R106,R107,R110,R111,R112,R113,R122,R138,R139,R140,R146,R147,R148,R155,R160,R161,R164,R166,R169,R177,R180,R182,R186,R187,R189,R197,R198,R203,R206,R207,R208,R222,R223,R224,R230,R231,R232,R240,R244,R245,R248,R250,R253,R261,R264,R266,R270,R271,R273,R281,R282,R287,R291,R292,R293,R376,R379,R380,R381,R382,R383,R386,R387,R391,R392,R395,R396,R397,R398,R400,R405,R406,R407,R408,R409,R410,R421,R422,R423,R424,R425,R426,R427,R432,R435,R436,R445,R446,R449,R453,R456,R457,R459,R460,R461,R493,R494,R495,R501,R502,R503,R510,R515,R516,R519,R521,R524,R533,R535,R537,R541,R542,R544,R552,R553,R558,R561,R562,R563,R577,R578,R579,R585,R586,R587,R594,R599,R600,R603,R605,R608,R610,R617,R621,R625,R626,R628,R636,R637,R642,R645,R646,R647,R740,R748,R933,R935,R1346,R1348,R1349,R1368,R1371,R1374,R1396,R1397,R1401,R1402,R1408,R1409,R1410,R1411,R1419,R1420,R1421,R1429,R1430,R1431,R1591,R1822,R1827,R1828,R1829 | 202 | 610102700-017-G | RES,49.9 Ohm,+/-1%,1/16W,G,SMD0402 | KOA SPEER ELECTRONICS, INC. | RK73H1ETTP49R9F | G | PWA BOM | In New BOM |
|  |  |  | 610102700-029-G | RES,49.9 Ohm,+/-1%,1/16W,G,SMD0402 | VISHAY ENTER TECHNO LOGY.INC | CRCW040249R9FKED | G | PWA BOM | In New BOM |
|  |  |  | 610102700-024-G | RES,49.9 Ohm,+/-1%,1/16W,G,SMD0402 | PANASONIC INDUSTRIAL CO.,LTD. | ERJ2RKF49R9X | G | PWA BOM | In New BOM |
|  |  |  | 610102700-011-G | RES,49.9 Ohm,+/-1%,1/16W,G,SMD0402 | YAGEO CORPORATION COMPONENT | RC0402FR-0749R9L | G | PWA BOM | In New BOM |
|  |  |  | 610102700-044-G | RES,49.9 Ohm,+/-1%,1/16W,G,SMD0402 | TA-I TECHNOLOGY CO., LTD. | RM04FTN49R9 | G | PWA BOM | In New BOM |
|  | R16,R17,R18,R19,R20,R21,R24,R25,R33,R34,R35,R36,R37,R46,R47,R48,R49,R50,R51,R65,R66,R69,R76,R94,R95,R99,R100,R101,R104,R105,R106,R107,R110,R111,R112,R113,R122,R138,R139,R140,R146,R147,R148,R155,R160,R161,R164,R166,R169,R177,R180,R182,R186,R187,R189,R197,R198,R203,R206,R207,R208,R222,R223,R224,R230,R231,R232,R240,R244,R245,R248,R250,R253,R261,R264,R266,R270,R271,R273,R281,R282,R287,R291,R292,R293,R376,R379,R380,R381,R382,R383,R386,R387,R391,R392,R395,R396,R397,R398,R400,R405,R406,R407,R408,R409,R410,R421,R422,R423,R424,R425,R426,R427,R432,R435,R436,R445,R446,R449,R453,R456,R457,R459,R460,R461,R493,R494,R495,R501,R502,R503,R510,R515,R516,R519,R521,R524,R533,R535,R537,R541,R542,R544,R552,R553,R558,R561,R562,R563,R577,R578,R579,R585,R586,R587,R594,R599,R600,R603,R605,R608,R610,R617,R621,R625,R626,R628,R636,R637,R642,R645,R646,R647,R740,R748,R933,R935,R1346,R1348,R1349,R1368,R1371,R1374,R1396,R1397,R1401,R1402,R1408,R1409,R1410,R1411,R1419,R1420,R1421,R1429,R1430,R1431,R1591,R1822,R1827,R1828,R1829 | 202 | 610102700-017-G | RES,49.9 Ohm,+/-1%,1/16W,G,SMD0402 | KOA SPEER ELECTRONICS, INC. | RK73H1ETTP49R9F | G | PWA BOM | In Old BOM |
|  |  |  | 610102700-029-G | RES,49.9 Ohm,+/-1%,1/16W,G,SMD0402 | VISHAY ENTER TECHNO LOGY.INC | CRCW040249R9FKED | G | PWA BOM | In Old BOM |
|  |  |  | 610102700-024-G | RES,49.9 Ohm,+/-1%,1/16W,G,SMD0402 | PANASONIC INDUSTRIAL CO.,LTD. | ERJ2RKF49R9X | G | PWA BOM | In Old BOM |
| 3 | R22,R23,R26,R32,R38,R39,R41,R42,R43,R44,R45,R52,R68,R88,R89,R299,R300,R301,R302,R342,R384,R385,R388,R389,R390,R394,R399,R401,R403,R404,R411,R412,R413,R441,R442,R465,R466,R468,R469,R472,R475,R476,R954,R1029,R1031,R1032,R1033,R1034,R1035,R1041,R1042,R1043,R1044,R1047,R1048,R1050,R1051,R1054,R1055,R1059,R1060,R1063,R1064,R1067,R1068,R1127,R1128,R1139,R1141,R1225,R1227,R1229,R1234,R1239,R1336,R1337,R1466,R1468,R1524,R1525,R1553,R1823 | 82 | 61010KJ00-017-G | RES,3.3KOhm,+/-5%,1/16W,G,SMD0402 | KOA SPEER ELECTRONICS, INC. | RK73B1ETTP332J | G | PWA BOM | In New BOM |
|  |  |  | 61010KJ00-024-G | RES,3.3KOhm,+/-5%,1/16W,G,SMD0402 | PANASONIC INDUSTRIAL CO.,LTD. | ERJ2GEJ332X | G | PWA BOM | In New BOM |
|  |  |  | 61010KJ00-044-G | RES,3.3KOhm,+/-5%,1/16W,G,SMD0402 | TA-I TECHNOLOGY CO., LTD. | RM04JTN332 | G | PWA BOM | In New BOM |
|  |  |  | 61010KJ00-011-G | RES,3.3KOhm,+/-5%,1/16W,G,SMD0402 | YAGEO CORPORATION COMPONENT | RC0402JR-073K3L | G | PWA BOM | In New BOM |
|  | R22,R23,R26,R32,R38,R39,R41,R42,R43,R44,R45,R52,R68,R88,R89,R299,R300,R301,R302,R342,R384,R385,R388,R389,R390,R394,R399,R401,R403,R404,R411,R412,R413,R441,R442,R465,R466,R468,R469,R472,R475,R476,R954,R1029,R1031,R1032,R1033,R1034,R1035,R1041,R1042,R1043,R1044,R1047,R1048,R1050,R1051,R1054,R1055,R1059,R1060,R1063,R1064,R1067,R1068,R1127,R1128,R1139,R1141,R1225,R1227,R1229,R1234,R1239,R1336,R1337,R1466,R1468,R1524,R1525,R1553,R1823 | 82 | 61010KJ00-017-G | RES,3.3KOhm,+/-5%,1/16W,G,SMD0402 | KOA SPEER ELECTRONICS, INC. | RK73B1ETTP332J | G | PWA BOM | In Old BOM |
|  |  |  | 61010KJ00-024-G | RES,3.3KOhm,+/-5%,1/16W,G,SMD0402 | PANASONIC INDUSTRIAL CO.,LTD. | ERJ2GEJ332X | G | PWA BOM | In Old BOM |
| 4 | R27,R28,R54,R55,R56,R57,R58,R59,R417,R418,R419,R420 | 12 | 610115E00-017-G | RES,1.2KOhm,+/-5%,1/16W,G,SMD0402 | KOA SPEER ELECTRONICS, INC. | RK73B1ETTP122J | G | PWA BOM | In New BOM |
|  |  |  | 610115E00-024-G | RES,1.2KOhm,+/-5%,1/16W,G,SMD0402 | PANASONIC INDUSTRIAL CO.,LTD. | ERJ2GEJ122X | G | PWA BOM | In New BOM |
|  |  |  | 610115E00-011-G | RES,1.2KOhm,+/-5%,1/16W,G,SMD0402 | YAGEO CORPORATION COMPONENT | RC0402JR-071K2L | G | PWA BOM | In New BOM |
|  |  |  | 610115E00-044-G | RES,1.2KOhm,+/-5%,1/16W,G,SMD0402 | TA-I TECHNOLOGY CO., LTD. | RM04JTN122 | G | PWA BOM | In New BOM |
|  | R27,R28,R54,R55,R56,R57,R58,R59,R417,R418,R419,R420 | 12 | 610115E00-017-G | RES,1.2KOhm,+/-5%,1/16W,G,SMD0402 | KOA SPEER ELECTRONICS, INC. | RK73B1ETTP122J | G | PWA BOM | In Old BOM |
|  |  |  | 610115E00-024-G | RES,1.2KOhm,+/-5%,1/16W,G,SMD0402 | PANASONIC INDUSTRIAL CO.,LTD. | ERJ2GEJ122X | G | PWA BOM | In Old BOM |
| 5 | R78 | 1 | 610115T00-017-G | RES,40.2KOhm,+/-1%,1/16W,G,SMD0402 | KOA SPEER ELECTRONICS, INC. | RK73H1ETTP4022F | G | PWA BOM | In New BOM |
|  |  |  | 610115T00-029-G | RES,40.2KOhm,+/-1%,1/16W,G,SMD0402 | VISHAY ENTER TECHNO LOGY.INC | CRCW040240K2FKEDC | G | PWA BOM | In New BOM |
|  |  |  | 610115T00-011-G | RES,40.2KOhm,+/-1%,1/16W,G,SMD0402 | YAGEO CORPORATION COMPONENT | RC0402FR-0740K2L | G | PWA BOM | In New BOM |
|  |  |  | 610115T00-044-G | RES,40.2KOhm,+/-1%,1/16W,G,SMD0402 | TA-I TECHNOLOGY CO., LTD. | RM04FTN4022 | G | PWA BOM | In New BOM |
|  | R78 | 1 | 610115T00-017-G | RES,40.2KOhm,+/-1%,1/16W,G,SMD0402 | KOA SPEER ELECTRONICS, INC. | RK73H1ETTP4022F | G | PWA BOM | In Old BOM |
|  |  |  | 610115T00-029-G | RES,40.2KOhm,+/-1%,1/16W,G,SMD0402 | VISHAY ENTER TECHNO LOGY.INC | CRCW040240K2FKEDC | G | PWA BOM | In Old BOM |
| 6 | R97,R98,R447,R452,R454 | 5 | 610112W00-017-G | RES,2KOhm,+/-5%,1/16W,G,SMD0402 | KOA SPEER ELECTRONICS, INC. | RK73B1ETTP202J | G | PWA BOM | In New BOM |
|  |  |  | 610112W00-024-G | RES,2KOhm,+/-5%,1/16W,G,SMD0402 | PANASONIC INDUSTRIAL CO.,LTD. | ERJ2GEJ202X | G | PWA BOM | In New BOM |
|  |  |  | 610112W00-011-G | RES,2KOhm,+/-5%,1/16W,G,SMD0402 | YAGEO CORPORATION COMPONENT | RC0402JR-072KL | G | PWA BOM | In New BOM |
|  |  |  | 610112W00-044-G | RES,2KOhm,+/-5%,1/16W,G,SMD0402 | TA-I TECHNOLOGY CO., LTD. | RM04JTN202 | G | PWA BOM | In New BOM |
|  | R97,R98,R447,R452,R454 | 5 | 610112W00-017-G | RES,2KOhm,+/-5%,1/16W,G,SMD0402 | KOA SPEER ELECTRONICS, INC. | RK73B1ETTP202J | G | PWA BOM | In Old BOM |
|  |  |  | 610112W00-024-G | RES,2KOhm,+/-5%,1/16W,G,SMD0402 | PANASONIC INDUSTRIAL CO.,LTD. | ERJ2GEJ202X | G | PWA BOM | In Old BOM |
| 7 | R108,R109,R463,R464 | 4 | 61010DL01-017-G | RES,0 Ohm,+/-5%,1/8W,G,SMD0805 | KOA SPEER ELECTRONICS, INC. | RK73Z2ATTD | G | PWA BOM | In New BOM |
|  |  |  | 61010DL00-024-G | RES,0 Ohm,+/-5%,1/8W,G,SMD0805 | PANASONIC INDUSTRIAL CO.,LTD. | ERJ6GEY0R00V | G | PWA BOM | In New BOM |
|  |  |  | 61010DL00-011-G | RES,0 Ohm,+/-5%,1/8W,G,SMD0805 | YAGEO CORPORATION COMPONENT | RC0805JR-070RL | G | PWA BOM | In New BOM |
|  |  |  | 61010DL00-044-G | RES,0 Ohm,+/-5%,1/8W,G,SMD0805 | TA-I TECHNOLOGY CO., LTD. | RM10JTN0 | G | PWA BOM | In New BOM |
|  | R108,R109,R463,R464 | 4 | 61010DL01-017-G | RES,0 Ohm,+/-5%,1/8W,G,SMD0805 | KOA SPEER ELECTRONICS, INC. | RK73Z2ATTD | G | PWA BOM | In Old BOM |
|  |  |  | 61010DL00-024-G | RES,0 Ohm,+/-5%,1/8W,G,SMD0805 | PANASONIC INDUSTRIAL CO.,LTD. | ERJ6GEY0R00V | G | PWA BOM | In Old BOM |
| 8 | R132,R137,R141,R143,R152,R158,R162,R167,R173,R179,R183,R188,R194,R200,R204,R209,R216,R221,R225,R227,R237,R239,R246,R251,R257,R263,R267,R272,R278,R284,R288,R290,R487,R492,R496,R498,R507,R513,R517,R522,R528,R531,R538,R543,R549,R555,R559,R564,R571,R576,R580,R582,R592,R597,R601,R606,R613,R620,R622,R627,R633,R639,R643,R648,R934 | 65 | 610102E00-017-G | RES,100 Ohm,+/-5%,1/16W,G,SMD0402 | KOA SPEER ELECTRONICS, INC. | RK73B1ETTP101J | G | PWA BOM | In New BOM |
|  |  |  | 610102E00-029-G | RES,100 Ohm,+/-5%,1/16W,G,SMD0402 | VISHAY ENTER TECHNO LOGY.INC | CRCW0402100RJNED | G | PWA BOM | In New BOM |
|  |  |  | 610102E00-011-G | RES,100 Ohm,+/-5%,1/16W,G,SMD0402 | YAGEO CORPORATION COMPONENT | RC0402JR-07100RL | G | PWA BOM | In New BOM |
|  |  |  | 610102E00-044-G | RES,100 Ohm,+/-5%,1/16W,G,SMD0402 | TA-I TECHNOLOGY CO., LTD. | RM04JTN101 | G | PWA BOM | In New BOM |
|  | R132,R137,R141,R143,R152,R158,R162,R167,R173,R179,R183,R188,R194,R200,R204,R209,R216,R221,R225,R227,R237,R239,R246,R251,R257,R263,R267,R272,R278,R284,R288,R290,R487,R492,R496,R498,R507,R513,R517,R522,R528,R531,R538,R543,R549,R555,R559,R564,R571,R576,R580,R582,R592,R597,R601,R606,R613,R620,R622,R627,R633,R639,R643,R648,R934 | 65 | 610102E00-017-G | RES,100 Ohm,+/-5%,1/16W,G,SMD0402 | KOA SPEER ELECTRONICS, INC. | RK73B1ETTP101J | G | PWA BOM | In Old BOM |
|  |  |  | 610102E00-029-G | RES,100 Ohm,+/-5%,1/16W,G,SMD0402 | VISHAY ENTER TECHNO LOGY.INC | CRCW0402100RJNED | G | PWA BOM | In Old BOM |
| 9 | R297,R298,R304,R1069,R1070,R1342,R1343 | 7 | 610107B00-017-G | RES,4.7KOhm,+/-5%,1/16W,G,SMD0402 | KOA SPEER ELECTRONICS, INC. | RK73B1ETTP472J | G | PWA BOM | In New BOM |
|  |  |  | 610107B00-024-G | RES,4.7KOhm,+/-5%,1/16W,G,SMD0402 | PANASONIC INDUSTRIAL CO.,LTD. | ERJ2GEJ472X | G | PWA BOM | In New BOM |
|  |  |  | 610107B00-029-G | RES,4.7KOhm,+/-5%,1/16W,G,SMD0402 | VISHAY ENTER TECHNO LOGY.INC | CRCW04024K70JNED | G | PWA BOM | In New BOM |
|  |  |  | 610107B00-011-G | RES,4.7KOhm,+/-5%,1/16W,G,SMD0402 | YAGEO CORPORATION COMPONENT | RC0402JR-074K7L | G | PWA BOM | In New BOM |
|  |  |  | 610107B00-044-G | RES,4.7KOhm,+/-5%,1/16W,G,SMD0402 | TA-I TECHNOLOGY CO., LTD. | RM04JTN472 | G | PWA BOM | In New BOM |
|  | R297,R298,R304,R1069,R1070,R1342,R1343 | 7 | 610107B00-017-G | RES,4.7KOhm,+/-5%,1/16W,G,SMD0402 | KOA SPEER ELECTRONICS, INC. | RK73B1ETTP472J | G | PWA BOM | In Old BOM |
|  |  |  | 610107B00-024-G | RES,4.7KOhm,+/-5%,1/16W,G,SMD0402 | PANASONIC INDUSTRIAL CO.,LTD. | ERJ2GEJ472X | G | PWA BOM | In Old BOM |
|  |  |  | 610107B00-029-G | RES,4.7KOhm,+/-5%,1/16W,G,SMD0402 | VISHAY ENTER TECHNO LOGY.INC | CRCW04024K70JNED | G | PWA BOM | In Old BOM |
| 10 | R307 | 1 | 610112U00-017-G | RES,499 Ohm,+/-1%,1/16W,G,SMD0402 | KOA SPEER ELECTRONICS, INC. | RK73H1ETTP4990F | G | PWA BOM | In New BOM |
|  |  |  | 610112U00-024-G | RES,499 Ohm,+/-1%,1/16W,G,SMD0402 | PANASONIC INDUSTRIAL CO.,LTD. | ERJ2RKF4990X | G | PWA BOM | In New BOM |
|  |  |  | 610112U00-011-G | RES,499 Ohm,+/-1%,1/16W,G,SMD0402 | YAGEO CORPORATION COMPONENT | RC0402FR-07499RL | G | PWA BOM | In New BOM |
|  |  |  | 610112U00-044-G | RES,499 Ohm,+/-1%,1/16W,G,SMD0402 | TA-I TECHNOLOGY CO., LTD. | RM04FTN4990 | G | PWA BOM | In New BOM |
|  | R307 | 1 | 610112U00-017-G | RES,499 Ohm,+/-1%,1/16W,G,SMD0402 | KOA SPEER ELECTRONICS, INC. | RK73H1ETTP4990F | G | PWA BOM | In Old BOM |
|  |  |  | 610112U00-024-G | RES,499 Ohm,+/-1%,1/16W,G,SMD0402 | PANASONIC INDUSTRIAL CO.,LTD. | ERJ2RKF4990X | G | PWA BOM | In Old BOM |
| 11 | R310,R990 | 2 | 610107C00-017-G | RES,10KOhm,+/-5%,1/16W,G,SMD0402 | KOA SPEER ELECTRONICS, INC. | RK73B1ETTP103J | G | PWA BOM | In New BOM |
|  |  |  | 610107C00-024-G | RES,10KOhm,+/-5%,1/16W,G,SMD0402 | PANASONIC INDUSTRIAL CO.,LTD. | ERJ2GEJ103X | G | PWA BOM | In New BOM |
|  |  |  | 610107C00-029-G | RES,10KOhm,+/-5%,1/16W,G,SMD0402 | VISHAY ENTER TECHNO LOGY.INC | CRCW040210K0JNED | G | PWA BOM | In New BOM |
|  |  |  | 610107C00-011-G | RES,10KOhm,+/-5%,1/16W,G,SMD0402 | YAGEO CORPORATION COMPONENT | RC0402JR-0710KL | G | PWA BOM | In New BOM |
|  |  |  | 610107C00-044-G | RES,10KOhm,+/-5%,1/16W,G,SMD0402 | TA-I TECHNOLOGY CO., LTD. | RM04JTN103 | G | PWA BOM | In New BOM |
|  | R310,R990 | 2 | 610107C00-017-G | RES,10KOhm,+/-5%,1/16W,G,SMD0402 | KOA SPEER ELECTRONICS, INC. | RK73B1ETTP103J | G | PWA BOM | In Old BOM |
|  |  |  | 610107C00-024-G | RES,10KOhm,+/-5%,1/16W,G,SMD0402 | PANASONIC INDUSTRIAL CO.,LTD. | ERJ2GEJ103X | G | PWA BOM | In Old BOM |
|  |  |  | 610107C00-029-G | RES,10KOhm,+/-5%,1/16W,G,SMD0402 | VISHAY ENTER TECHNO LOGY.INC | CRCW040210K0JNED | G | PWA BOM | In Old BOM |
| 12 | R329 | 1 | 610118G00-017-G | RES,90.9KOhm,+/-1%,1/16W,G,SMD0402 | KOA SPEER ELECTRONICS, INC. | RK73H1ETTP9092F | G | PWA BOM | In New BOM |
|  |  |  | 610118G00-024-G | RES,90.9KOhm,+/-1%,1/16W,G,SMD0402 | PANASONIC INDUSTRIAL CO.,LTD. | ERJ2RKF9092X | G | PWA BOM | In New BOM |
|  |  |  | 610118G00-011-G | RES,90.9KOhm,+/-1%,1/16W,G,SMD0402 | YAGEO CORPORATION COMPONENT | RC0402FR-0790K9L | G | PWA BOM | In New BOM |
|  |  |  | 610118G00-044-G | RES,90.9KOhm,+/-1%,1/16W,G,SMD0402 | TA-I TECHNOLOGY CO., LTD. | RM04FTN9092 | G | PWA BOM | In New BOM |
|  | R329 | 1 | 610118G00-017-G | RES,90.9KOhm,+/-1%,1/16W,G,SMD0402 | KOA SPEER ELECTRONICS, INC. | RK73H1ETTP9092F | G | PWA BOM | In Old BOM |
|  |  |  | 610118G00-024-G | RES,90.9KOhm,+/-1%,1/16W,G,SMD0402 | PANASONIC INDUSTRIAL CO.,LTD. | ERJ2RKF9092X | G | PWA BOM | In Old BOM |
| 13 | R332,R333,R334,R335,R336,R337,R338,R339,R340,R341,R343,R344,R345 | 13 | 610116J00-017-G | RES,1.21KOhm,+/-1%,1/16W,G,SMD0402 | KOA SPEER ELECTRONICS, INC. | RK73H1ETTP1211F | G | PWA BOM | In New BOM |
|  |  |  | 610116J00-024-G | RES,1.21KOhm,+/-1%,1/16W,G,SMD0402 | PANASONIC INDUSTRIAL CO.,LTD. | ERJ2RKF1211X | G | PWA BOM | In New BOM |
|  |  |  | 610116J00-029-G | RES,1.21KOhm,+/-1%,1/16W,G,SMD0402 | VISHAY ENTER TECHNO LOGY.INC | CRCW04021K21FKED | G | PWA BOM | In New BOM |
|  |  |  | 610116J00-011-G | RES,1.21KOhm,+/-1%,1/16W,G,SMD040 | YAGEO CORPORATION COMPONENT | RC0402FR-071K21L | G | PWA BOM | In New BOM |
|  |  |  | 610116J00-044-G | RES,1.21KOhm,+/-1%,1/16W,G,SMD0402 | TA-I TECHNOLOGY CO., LTD. | RM04FTN1211 | G | PWA BOM | In New BOM |
|  | R332,R333,R334,R335,R336,R337,R338,R339,R340,R341,R343,R344,R345 | 13 | 610116J00-017-G | RES,1.21KOhm,+/-1%,1/16W,G,SMD0402 | KOA SPEER ELECTRONICS, INC. | RK73H1ETTP1211F | G | PWA BOM | In Old BOM |
|  |  |  | 610116J00-024-G | RES,1.21KOhm,+/-1%,1/16W,G,SMD0402 | PANASONIC INDUSTRIAL CO.,LTD. | ERJ2RKF1211X | G | PWA BOM | In Old BOM |
|  |  |  | 610116J00-029-G | RES,1.21KOhm,+/-1%,1/16W,G,SMD0402 | VISHAY ENTER TECHNO LOGY.INC | CRCW04021K21FKED | G | PWA BOM | In Old BOM |
| 14 | R346 | 1 | 610114W00-017-G | RES,3.01KOhm,+/-1%,1/16W,G,SMD0402 | KOA SPEER ELECTRONICS, INC. | RK73H1ETTP3011F | G | PWA BOM | In New BOM |
|  |  |  | 610114W00-029-G | RES,3.01KOhm,+/-1%,1/16W,G,SMD0402 | VISHAY ENTER TECHNO LOGY.INC | CRCW04023K01FKED | G | PWA BOM | In New BOM |
|  |  |  | 610114W00-011-G | RES,3.01KOhm,+/-1%,1/16W,G,SMD0402 | YAGEO CORPORATION COMPONENT | RC0402FR-073K01L | G | PWA BOM | In New BOM |
|  |  |  | 610114W00-044-G | RES,3.01KOhm,+/-1%,1/16W,G,SMD0402 | TA-I TECHNOLOGY CO., LTD. | RM04FTN3011 | G | PWA BOM | In New BOM |
|  | R346 | 1 | 610114W00-017-G | RES,3.01KOhm,+/-1%,1/16W,G,SMD0402 | KOA SPEER ELECTRONICS, INC. | RK73H1ETTP3011F | G | PWA BOM | In Old BOM |
|  |  |  | 610114W00-029-G | RES,3.01KOhm,+/-1%,1/16W,G,SMD0402 | VISHAY ENTER TECHNO LOGY.INC | CRCW04023K01FKED | G | PWA BOM | In Old BOM |
| 15 | R349 | 1 | 61010L600-017-G | RES,11KOhm,+/-1%,1/16W,G,SMD0402 | KOA SPEER ELECTRONICS, INC. | RK73H1ETTP1102F | G | PWA BOM | In New BOM |
|  |  |  | 61010L600-024-G | RES,11KOhm,+/-1%,1/16W,G,SMD0402 | PANASONIC INDUSTRIAL CO.,LTD. | ERJ2RKF1102X | G | PWA BOM | In New BOM |
|  |  |  | 61010L600-029-G | RES,11KOhm,+/-1%,1/16W,G,SMD0402 | VISHAY ENTER TECHNO LOGY.INC | CRCW040211K0FKEDC | G | PWA BOM | In New BOM |
|  |  |  | 61010L600-011-G | RES,11KOhm,+/-1%,1/16W,G,SMD0402 | YAGEO CORPORATION COMPONENT | RC0402FR-0711KL | G | PWA BOM | In New BOM |
|  |  |  | 61010L600-044-G | RES,11KOhm,+/-1%,1/16W,G,SMD0402 | TA-I TECHNOLOGY CO., LTD. | RM04FTN1102 | G | PWA BOM | In New BOM |
|  | R349 | 1 | 61010L600-017-G | RES,11KOhm,+/-1%,1/16W,G,SMD0402 | KOA SPEER ELECTRONICS, INC. | RK73H1ETTP1102F | G | PWA BOM | In Old BOM |
|  |  |  | 61010L600-024-G | RES,11KOhm,+/-1%,1/16W,G,SMD0402 | PANASONIC INDUSTRIAL CO.,LTD. | ERJ2RKF1102X | G | PWA BOM | In Old BOM |
|  |  |  | 61010L600-029-G | RES,11KOhm,+/-1%,1/16W,G,SMD0402 | VISHAY ENTER TECHNO LOGY.INC | CRCW040211K0FKEDC | G | PWA BOM | In Old BOM |
| 16 | R738,R1111 | 2 | 61011B000-017-G | RES,1.5KOhm,+/-1%,1/16W,G,SMD0402 | KOA SPEER ELECTRONICS, INC. | RK73H1ETTP1501F | G | PWA BOM | In New BOM |
|  |  |  | 61011B000-024-G | RES,1.5KOhm,+/-1%,1/16W,G,SMD0402 | PANASONIC INDUSTRIAL CO.,LTD. | ERJ2RKF1501X | G | PWA BOM | In New BOM |
|  |  |  | 61011B000-011-G | RES,1.5KOhm,+/-1%,1/16W,G,SMD0402 | YAGEO CORPORATION COMPONENT | RC0402FR-071K5L | G | PWA BOM | In New BOM |
|  |  |  | 61011B000-044-G | RES,1.5KOhm,+/-1%,1/16W,G,SMD0402 | TA-I TECHNOLOGY CO., LTD. | RM04FTN1501 | G | PWA BOM | In New BOM |
|  | R738,R1111 | 2 | 61011B000-017-G | RES,1.5KOhm,+/-1%,1/16W,G,SMD0402 | KOA SPEER ELECTRONICS, INC. | RK73H1ETTP1501F | G | PWA BOM | In Old BOM |
|  |  |  | 61011B000-024-G | RES,1.5KOhm,+/-1%,1/16W,G,SMD0402 | PANASONIC INDUSTRIAL CO.,LTD. | ERJ2RKF1501X | G | PWA BOM | In Old BOM |
| 17 | R739,R741,R742,R743,R749,R936,R937,R993,R994,R995,R996,R997 | 12 | 610101V00-017-G | RES,22 Ohm,+/-5%,1/16W,G,SMD0402 | KOA SPEER ELECTRONICS, INC. | RK73B1ETTP220J | G | PWA BOM | In New BOM |
|  |  |  | 610101V00-024-G | RES,22 Ohm,+/-5%,1/16W,G,SMD0402 | PANASONIC INDUSTRIAL CO.,LTD. | ERJ2GEJ220X | G | PWA BOM | In New BOM |
|  |  |  | 610101V00-011-G | RES,22 Ohm,+/-5%,1/16W,G,SMD0402 | YAGEO CORPORATION COMPONENT | RC0402JR-0722RL | G | PWA BOM | In New BOM |
|  |  |  | 610101V00-044-G | RES,22 Ohm,+/-5%,1/16W,G,SMD0402 | TA-I TECHNOLOGY CO., LTD. | RM04JTN220 | G | PWA BOM | In New BOM |
|  | R739,R741,R742,R743,R749,R936,R937,R993,R994,R995,R996,R997 | 12 | 610101V00-017-G | RES,22 Ohm,+/-5%,1/16W,G,SMD0402 | KOA SPEER ELECTRONICS, INC. | RK73B1ETTP220J | G | PWA BOM | In Old BOM |
|  |  |  | 610101V00-024-G | RES,22 Ohm,+/-5%,1/16W,G,SMD0402 | PANASONIC INDUSTRIAL CO.,LTD. | ERJ2GEJ220X | G | PWA BOM | In Old BOM |
| 18 | R753 | 1 | 610112L00-017-G | RES,1.24KOhm,+/-1%,1/16W,G,SMD0402 | KOA SPEER ELECTRONICS, INC. | RK73H1ETTP1241F | G | PWA BOM | In New BOM |
|  |  |  | 610112L00-029-G | RES,1.24KOhm,+/-1%,1/16W,G,SMD0402 | VISHAY ENTER TECHNO LOGY.INC | CRCW04021K24FKED | G | PWA BOM | In New BOM |
|  |  |  | 610112L00-024-G | RES,1.24KOhm,+/-1%,1/16W,G,SMD0402 | PANASONIC INDUSTRIAL CO.,LTD. | ERJ2RKF1241X | G | PWA BOM | In New BOM |
|  |  |  | 610112L00-011-G | RES,1.24KOhm,+/-1%,1/16W,G,SMD0402 | YAGEO CORPORATION COMPONENT | RC0402FR-071K24L | G | PWA BOM | In New BOM |
|  |  |  | 610112L00-044-G | RES,1.24KOhm,+/-1%,1/16W,G,SMD0402 | TA-I TECHNOLOGY CO., LTD. | RM04FTN1241 | G | PWA BOM | In New BOM |
|  | R753 | 1 | 610112L00-017-G | RES,1.24KOhm,+/-1%,1/16W,G,SMD0402 | KOA SPEER ELECTRONICS, INC. | RK73H1ETTP1241F | G | PWA BOM | In Old BOM |
|  |  |  | 610112L00-029-G | RES,1.24KOhm,+/-1%,1/16W,G,SMD0402 | VISHAY ENTER TECHNO LOGY.INC | CRCW04021K24FKED | G | PWA BOM | In Old BOM |
|  |  |  | 610112L00-024-G | RES,1.24KOhm,+/-1%,1/16W,G,SMD0402 | PANASONIC INDUSTRIAL CO.,LTD. | ERJ2RKF1241X | G | PWA BOM | In Old BOM |
| 19 | R792,R793,R794,R796,R797,R799 | 6 | 610115J00-017-G | RES,33 Ohm,+/-1%,1/16W,G,SMD0402 | KOA SPEER ELECTRONICS, INC. | RK73H1ETTP33R0F | G | PWA BOM | In New BOM |
|  |  |  | 610115J00-024-G | RES,33 Ohm,+/-1%,1/16W,G,SMD0402 | PANASONIC INDUSTRIAL CO.,LTD. | ERJ2RKF33R0X | G | PWA BOM | In New BOM |
|  |  |  | 610115J00-011-G | RES,33 Ohm,+/-1%,1/16W,G,SMD0402 | YAGEO CORPORATION COMPONENT | RC0402FR-0733RL | G | PWA BOM | In New BOM |
|  |  |  | 610115J00-044-G | RES,33 Ohm,+/-1%,1/16W,G,SMD0402 | TA-I TECHNOLOGY CO., LTD. | RM04FTN33R0 | G | PWA BOM | In New BOM |
|  | R792,R793,R794,R796,R797,R799 | 6 | 610115J00-017-G | RES,33 Ohm,+/-1%,1/16W,G,SMD0402 | KOA SPEER ELECTRONICS, INC. | RK73H1ETTP33R0F | G | PWA BOM | In Old BOM |
|  |  |  | 610115J00-024-G | RES,33 Ohm,+/-1%,1/16W,G,SMD0402 | PANASONIC INDUSTRIAL CO.,LTD. | ERJ2RKF33R0X | G | PWA BOM | In Old BOM |
| 20 | R815,R816,R818,R1015,R1161,R1163,R1171,R1173,R1183,R1189,R1196,R1202,R1206,R1209,R1226,R1307,R1314,R1315,R1316,R1317,R1318,R1319,R1320,R1502 | 24 | 61011H500-017-G | RES,22 Ohm,+/-1%,1/16W,G,SMD0402 | KOA SPEER ELECTRONICS, INC. | RK73H1ETTP22R0F | G | PWA BOM | In New BOM |
|  |  |  | 61011H500-024-G | RES,22 Ohm,+/-1%,1/16W,G,SMD0402 | PANASONIC INDUSTRIAL CO.,LTD. | ERJ2RKF22R0X | G | PWA BOM | In New BOM |
|  |  |  | 61011H500-011-G | RES,22 Ohm,+/-1%,1/16W,G,SMD0402 | YAGEO CORPORATION COMPONENT | RC0402FR-0722RL | G | PWA BOM | In New BOM |
|  |  |  | 61011H500-044-G | RES,22 Ohm,+/-1%,1/16W,G,SMD0402 | TA-I TECHNOLOGY CO., LTD. | RM04FTN22R0 | G | PWA BOM | In New BOM |
|  | R815,R816,R818,R1015,R1161,R1163,R1171,R1173,R1183,R1189,R1196,R1202,R1206,R1209,R1226,R1307,R1314,R1315,R1316,R1317,R1318,R1319,R1320,R1502 | 24 | 61011H500-017-G | RES,22 Ohm,+/-1%,1/16W,G,SMD0402 | KOA SPEER ELECTRONICS, INC. | RK73H1ETTP22R0F | G | PWA BOM | In Old BOM |
|  |  |  | 61011H500-024-G | RES,22 Ohm,+/-1%,1/16W,G,SMD0402 | PANASONIC INDUSTRIAL CO.,LTD. | ERJ2RKF22R0X | G | PWA BOM | In Old BOM |
| 21 | R831,R832,R833,R834,R1345,R1347,R1494 | 7 | 61011H100-017-G | RES,220 Ohm,+/-1%,1/16W,G,SMD0402 | KOA SPEER ELECTRONICS, INC. | RK73H1ETTP2200F | G | PWA BOM | In New BOM |
|  |  |  | 61011H100-024-G | RES,220 Ohm,+/-1%,1/16W,G,SMD0402 | PANASONIC INDUSTRIAL CO.,LTD. | ERJ2RKF2200X | G | PWA BOM | In New BOM |
|  |  |  | 61011H100-029-G | RES,220 Ohm,+/-1%,1/16W,G,SMD0402 | VISHAY ENTER TECHNO LOGY.INC | CRCW0402220RFKEDC | G | PWA BOM | In New BOM |
|  |  |  | 61011H100-011-G | RES,220 Ohm,+/-1%,1/16W,G,SMD0402 | YAGEO CORPORATION COMPONENT | RC0402FR-07220RL | G | PWA BOM | In New BOM |
|  | R831,R832,R833,R834,R1345,R1347,R1494 | 7 | 61011H100-017-G | RES,220 Ohm,+/-1%,1/16W,G,SMD0402 | KOA SPEER ELECTRONICS, INC. | RK73H1ETTP2200F | G | PWA BOM | In Old BOM |
|  |  |  | 61011H100-024-G | RES,220 Ohm,+/-1%,1/16W,G,SMD0402 | PANASONIC INDUSTRIAL CO.,LTD. | ERJ2RKF2200X | G | PWA BOM | In Old BOM |
|  |  |  | 61011H100-029-G | RES,220 Ohm,+/-1%,1/16W,G,SMD0402 | VISHAY ENTER TECHNO LOGY.INC | CRCW0402220RFKEDC | G | PWA BOM | In Old BOM |
| 22 | R886 | 1 | 61011KH00-017-G | RES,240 Ohm,+/-5%,1/16W,G,SMD0402 | KOA SPEER ELECTRONICS, INC. | RK73B1ETTP241J | G | PWA BOM | In New BOM |
|  |  |  | 61011KH00-024-G | RES,240 Ohm,+/-5%,1/16W,G,SMD0402 | PANASONIC INDUSTRIAL CO.,LTD. | ERJ2GEJ241X | G | PWA BOM | In New BOM |
|  |  |  | 61011KH00-011-G | RES,240 Ohm,+/-5%,1/16W,G,SMD0402 | YAGEO CORPORATION COMPONENT | RC0402JR-07240RL | G | PWA BOM | In New BOM |
|  |  |  | 61011KH00-044-G | RES,240 Ohm,+/-5%,1/16W,G,SMD0402 | TA-I TECHNOLOGY CO., LTD. | RM04JTN241 | G | PWA BOM | In New BOM |
|  | R886 | 1 | 61011KH00-017-G | RES,240 Ohm,+/-5%,1/16W,G,SMD0402 | KOA SPEER ELECTRONICS, INC. | RK73B1ETTP241J | G | PWA BOM | In Old BOM |
|  |  |  | 61011KH00-024-G | RES,240 Ohm,+/-5%,1/16W,G,SMD0402 | PANASONIC INDUSTRIAL CO.,LTD. | ERJ2GEJ241X | G | PWA BOM | In Old BOM |
| 23 | R925,R927,R929 | 3 | 610102600-017-G | RES,56 Ohm,+/-1%,1/16W,G,SMD0402 | KOA SPEER ELECTRONICS, INC. | RK73H1ETTP56R0F | G | PWA BOM | In New BOM |
|  |  |  | 610102600-024-G | RES,56 Ohm,+/-1%,1/16W,G,SMD0402 | PANASONIC INDUSTRIAL CO.,LTD. | ERJ2RKF56R0X | G | PWA BOM | In New BOM |
|  |  |  | 610102600-011-G | RES,56 Ohm,+/-1%,1/16W,G,SMD0402 | YAGEO CORPORATION COMPONENT | RC0402FR-0756RL | G | PWA BOM | In New BOM |
|  |  |  | 610102600-044-G | RES,56 Ohm,+/-1%,1/16W,G,SMD0402 | TA-I TECHNOLOGY CO., LTD. | RM04FTN56R0 | G | PWA BOM | In New BOM |
|  | R925,R927,R929 | 3 | 610102600-017-G | RES,56 Ohm,+/-1%,1/16W,G,SMD0402 | KOA SPEER ELECTRONICS, INC. | RK73H1ETTP56R0F | G | PWA BOM | In Old BOM |
|  |  |  | 610102600-024-G | RES,56 Ohm,+/-1%,1/16W,G,SMD0402 | PANASONIC INDUSTRIAL CO.,LTD. | ERJ2RKF56R0X | G | PWA BOM | In Old BOM |
| 24 | R960,R1323,R1325,R1327,R1328,R1412,R1413,R1414,R1416,R1417,R1418,R1422,R1423,R1424,R1425,R1426,R1427,R1428,R1505,R1506,R1516,R1517,R1518,R1523,R1783 | 25 | 610114U00-017-G | RES,3.3KOhm,+/-1%,1/16W,G,SMD0402 | KOA SPEER ELECTRONICS, INC. | RK73H1ETTP3301F | G | PWA BOM | In New BOM |
|  |  |  | 610114U00-024-G | RES,3.3KOhm,+/-1%,1/16W,G,SMD0402 | PANASONIC INDUSTRIAL CO.,LTD. | ERJ2RKF3301X | G | PWA BOM | In New BOM |
|  |  |  | 610114U00-011-G | RES,3.3KOhm,+/-1%,1/16W,G,SMD0402 | YAGEO CORPORATION COMPONENT | RC0402FR-073K3L | G | PWA BOM | In New BOM |
|  |  |  | 610114U00-044-G | RES,3.3KOhm,+/-1%,1/16W,G,SMD0402 | TA-I TECHNOLOGY CO., LTD. | RM04FTN3301 | G | PWA BOM | In New BOM |
|  | R960,R1323,R1325,R1327,R1328,R1412,R1413,R1414,R1416,R1417,R1418,R1422,R1423,R1424,R1425,R1426,R1427,R1428,R1505,R1506,R1516,R1517,R1518,R1523,R1783 | 25 | 610114U00-017-G | RES,3.3KOhm,+/-1%,1/16W,G,SMD0402 | KOA SPEER ELECTRONICS, INC. | RK73H1ETTP3301F | G | PWA BOM | In Old BOM |
|  |  |  | 610114U00-024-G | RES,3.3KOhm,+/-1%,1/16W,G,SMD0402 | PANASONIC INDUSTRIAL CO.,LTD. | ERJ2RKF3301X | G | PWA BOM | In Old BOM |
| 25 | R971 | 1 | 61010A000-017-G | RES,8.2KOhm,+/-5%,1/16W,G,SMD0402 | KOA SPEER ELECTRONICS, INC. | RK73B1ETTP822J | G | PWA BOM | In New BOM |
|  |  |  | 61010A000-024-G | RES,8.2KOhm,+/-5%,1/16W,G,SMD0402 | PANASONIC INDUSTRIAL CO.,LTD. | ERJ2GEJ822X | G | PWA BOM | In New BOM |
|  |  |  | 61010A000-011-G | RES,8.2KOhm,+/-5%,1/16W,G,SMD0402 | YAGEO CORPORATION COMPONENT | RC0402JR-078K2L | G | PWA BOM | In New BOM |
|  |  |  | 61010A000-044-G | RES,8.2KOhm,+/-5%,1/16W,G,SMD0402 | TA-I TECHNOLOGY CO., LTD. | RM04JTN822 | G | PWA BOM | In New BOM |
|  | R971 | 1 | 61010A000-017-G | RES,8.2KOhm,+/-5%,1/16W,G,SMD0402 | KOA SPEER ELECTRONICS, INC. | RK73B1ETTP822J | G | PWA BOM | In Old BOM |
|  |  |  | 61010A000-024-G | RES,8.2KOhm,+/-5%,1/16W,G,SMD0402 | PANASONIC INDUSTRIAL CO.,LTD. | ERJ2GEJ822X | G | PWA BOM | In Old BOM |
| 26 | R1000,R1002 | 2 | 610118100-017-G | RES,1.4KOhm,+/-1%,1/16W,G,SMD0402 | KOA SPEER ELECTRONICS, INC. | RK73H1ETTP1401F | G | PWA BOM | In New BOM |
|  |  |  | 610118100-024-G | RES,1.4KOhm,+/-1%,1/16W,G,SMD0402 | PANASONIC INDUSTRIAL CO.,LTD. | ERJ2RKF1401X | G | PWA BOM | In New BOM |
|  |  |  | 610118100-011-G | RES,1.4KOhm,+/-1%,1/16W,G,SMD0402 | YAGEO CORPORATION COMPONENT | RC0402FR-071K4L | G | PWA BOM | In New BOM |
|  |  |  | 610118100-044-G | RES,1.4KOhm,+/-1%,1/16W,G,SMD0402 | TA-I TECHNOLOGY CO., LTD. | RM04FTN1401 | G | PWA BOM | In New BOM |
|  | R1000,R1002 | 2 | 610118100-017-G | RES,1.4KOhm,+/-1%,1/16W,G,SMD0402 | KOA SPEER ELECTRONICS, INC. | RK73H1ETTP1401F | G | PWA BOM | In Old BOM |
|  |  |  | 610118100-024-G | RES,1.4KOhm,+/-1%,1/16W,G,SMD0402 | PANASONIC INDUSTRIAL CO.,LTD. | ERJ2RKF1401X | G | PWA BOM | In Old BOM |
| 27 | R1026 | 1 | 610114R00-017-G | RES,49.9KOhm,+/-1%,1/16W,G,SMD0402 | KOA SPEER ELECTRONICS, INC. | RK73H1ETTP4992F | G | PWA BOM | In New BOM |
|  |  |  | 610114R00-029-G | RES,49.9KOhm,+/-1%,1/16W,G,SMD0402 | VISHAY ENTER TECHNO LOGY.INC | CRCW040249K9FKED | G | PWA BOM | In New BOM |
|  |  |  | 610114R00-011-G | RES,49.9KOhm,+/-1%,1/16W,G,SMD0402 | YAGEO CORPORATION COMPONENT | RC0402FR-0749K9L | G | PWA BOM | In New BOM |
|  |  |  | 610114R00-044-G | RES,49.9KOhm,+/-1%,1/16W,G,SMD0402 | TA-I TECHNOLOGY CO., LTD. | RM04FTN4992 | G | PWA BOM | In New BOM |
|  | R1026 | 1 | 610114R00-017-G | RES,49.9KOhm,+/-1%,1/16W,G,SMD0402 | KOA SPEER ELECTRONICS, INC. | RK73H1ETTP4992F | G | PWA BOM | In Old BOM |
|  |  |  | 610114R00-029-G | RES,49.9KOhm,+/-1%,1/16W,G,SMD0402 | VISHAY ENTER TECHNO LOGY.INC | CRCW040249K9FKED | G | PWA BOM | In Old BOM |
| 28 | R1027 | 1 | 610115W00-017-G | RES,18KOhm,+/-1%,1/16W,G,SMD0402 | KOA SPEER ELECTRONICS, INC. | RK73H1ETTP1802F | G | PWA BOM | In New BOM |
|  |  |  | 610115W00-024-G | RES,18KOhm,+/-1%,1/16W,G,SMD0402 | PANASONIC INDUSTRIAL CO.,LTD. | ERJ2RKF1802X | G | PWA BOM | In New BOM |
|  |  |  | 610115W00-011-G | RES,18KOhm,+/-1%,1/16W,G,SMD0402 | YAGEO CORPORATION COMPONENT | RC0402FR-0718KL | G | PWA BOM | In New BOM |
|  |  |  | 610115W00-044-G | RES,18KOhm,+/-1%,1/16W,G,SMD0402 | TA-I TECHNOLOGY CO., LTD. | RM04FTN1802 | G | PWA BOM | In New BOM |
|  | R1027 | 1 | 610115W00-017-G | RES,18KOhm,+/-1%,1/16W,G,SMD0402 | KOA SPEER ELECTRONICS, INC. | RK73H1ETTP1802F | G | PWA BOM | In Old BOM |
|  |  |  | 610115W00-024-G | RES,18KOhm,+/-1%,1/16W,G,SMD0402 | PANASONIC INDUSTRIAL CO.,LTD. | ERJ2RKF1802X | G | PWA BOM | In Old BOM |
| 29 | R1147 | 1 | 610112800-017-G | RES,6.04KOhm,+/-1%,1/16W,G,SMD0402 | KOA SPEER ELECTRONICS, INC. | RK73H1ETTP6041F | G | PWA BOM | In New BOM |
|  |  |  | 610112800-029-G | RES,6.04KOhm,+/-1%,1/16W,G,SMD0402 | VISHAY ENTER TECHNO LOGY.INC | CRCW04026K04FKED | G | PWA BOM | In New BOM |
|  |  |  | 610112800-011-G | RES,6.04KOhm,+/-1%,1/16W,G,SMD0402 | YAGEO CORPORATION COMPONENT | RC0402FR-076K04L | G | PWA BOM | In New BOM |
|  |  |  | 610112800-044-G | RES,6.04KOhm,+/-1%,1/16W,G,SMD0402 | TA-I TECHNOLOGY CO., LTD. | RM04FTN6041 | G | PWA BOM | In New BOM |
|  | R1147 | 1 | 610112800-017-G | RES,6.04KOhm,+/-1%,1/16W,G,SMD0402 | KOA SPEER ELECTRONICS, INC. | RK73H1ETTP6041F | G | PWA BOM | In Old BOM |
|  |  |  | 610112800-029-G | RES,6.04KOhm,+/-1%,1/16W,G,SMD0402 | VISHAY ENTER TECHNO LOGY.INC | CRCW04026K04FKED | G | PWA BOM | In Old BOM |
| 30 | R1251,R1252,R1253,R1254,R1395,R1398 | 6 | 610103300-017-G | RES,100KOhm,+/-5%,1/16W,G,SMD0402 | KOA SPEER ELECTRONICS, INC. | RK73B1ETTP104J | G | PWA BOM | In New BOM |
|  |  |  | 610103300-029-G | RES,100KOhm,+/-5%,1/16W,G,SMD0402 | VISHAY ENTER TECHNO LOGY.INC | CRCW0402100KJNED | G | PWA BOM | In New BOM |
|  |  |  | 610103300-011-G | RES,100KOhm,+/-5%,1/16W,G,SMD0402 | YAGEO CORPORATION COMPONENT | RC0402JR-07100KL | G | PWA BOM | In New BOM |
|  |  |  | 610103300-044-G | RES,100KOhm,+/-5%,1/16W,G,SMD0402 | TA-I TECHNOLOGY CO., LTD. | RM04JTN104 | G | PWA BOM | In New BOM |
|  | R1251,R1252,R1253,R1254,R1395,R1398 | 6 | 610103300-017-G | RES,100KOhm,+/-5%,1/16W,G,SMD0402 | KOA SPEER ELECTRONICS, INC. | RK73B1ETTP104J | G | PWA BOM | In Old BOM |
|  |  |  | 610103300-029-G | RES,100KOhm,+/-5%,1/16W,G,SMD0402 | VISHAY ENTER TECHNO LOGY.INC | CRCW0402100KJNED | G | PWA BOM | In Old BOM |
| 31 | R1280 | 1 | 610112N00-017-G | RES,130 Ohm,+/-1%,1/16W,G,SMD0402 | KOA SPEER ELECTRONICS, INC. | RK73H1ETTP1300F | G | PWA BOM | In New BOM |
|  |  |  | 610112N00-029-G | RES,130 Ohm,+/-1%,1/16W,G,SMD0402 | VISHAY ENTER TECHNO LOGY.INC | CRCW0402130RFKED | G | PWA BOM | In New BOM |
|  |  |  | 610112N00-024-G | RES,130 Ohm,+/-1%,1/16W,G,SMD0402 | PANASONIC INDUSTRIAL CO.,LTD. | ERJ2RKF1300X | G | PWA BOM | In New BOM |
|  |  |  | 610112N00-011-G | RES,130 Ohm,+/-1%,1/16W,G,SMD0402 | YAGEO CORPORATION COMPONENT | RC0402FR-07130RL | G | PWA BOM | In New BOM |
|  |  |  | 610112N00-044-G | RES,130 Ohm,+/-1%,1/16W,G,SMD0402 | TA-I TECHNOLOGY CO., LTD. | RM04FTN1300 | G | PWA BOM | In New BOM |
|  | R1280 | 1 | 610112N00-017-G | RES,130 Ohm,+/-1%,1/16W,G,SMD0402 | KOA SPEER ELECTRONICS, INC. | RK73H1ETTP1300F | G | PWA BOM | In Old BOM |
|  |  |  | 610112N00-029-G | RES,130 Ohm,+/-1%,1/16W,G,SMD0402 | VISHAY ENTER TECHNO LOGY.INC | CRCW0402130RFKED | G | PWA BOM | In Old BOM |
|  |  |  | 610112N00-024-G | RES,130 Ohm,+/-1%,1/16W,G,SMD0402 | PANASONIC INDUSTRIAL CO.,LTD. | ERJ2RKF1300X | G | PWA BOM | In Old BOM |
| 32 | R1298 | 1 | 61010AC00-017-G | RES,2.2 Ohm,+/-1%,1/10W,G,SMD0603 | KOA SPEER ELECTRONICS, INC. | RK73H1JTTD2R20F | G | PWA BOM | In New BOM |
|  |  |  | 61010AC00-024-G | RES,2.2 Ohm,+/-1%,1/10W,G,SMD0603 | PANASONIC INDUSTRIAL CO.,LTD. | ERJ3RQF2R2V | G | PWA BOM | In New BOM |
|  |  |  | 61010AC00-011-G | RES,2.2 Ohm,+/-1%,1/10W,G,SMD0603 | YAGEO CORPORATION COMPONENT | RC0603FR-072R2L | G | PWA BOM | In New BOM |
|  |  |  | 61010AC00-044-G | RES,2.2 Ohm,+/-1%,1/10W,G,SMD0603 | TA-I TECHNOLOGY CO., LTD. | RM06FTN2R20 | G | PWA BOM | In New BOM |
|  | R1298 | 1 | 61010AC00-017-G | RES,2.2 Ohm,+/-1%,1/10W,G,SMD0603 | KOA SPEER ELECTRONICS, INC. | RK73H1JTTD2R20F | G | PWA BOM | In Old BOM |
|  |  |  | 61010AC00-024-G | RES,2.2 Ohm,+/-1%,1/10W,G,SMD0603 | PANASONIC INDUSTRIAL CO.,LTD. | ERJ3RQF2R2V | G | PWA BOM | In Old BOM |
| 33 | R1492 | 1 | 610118800-017-G | RES,499KOhm,+/-1%,1/8W,G,SMD0805 | KOA SPEER ELECTRONICS, INC. | RK73H2ATTD4993F | G | PWA BOM | In New BOM |
|  |  |  | 610118800-024-G | RES,499KOhm,+/-1%,1/8W,G,SMD0805 | PANASONIC INDUSTRIAL CO.,LTD. | ERJ6ENF4993V | G | PWA BOM | In New BOM |
|  |  |  | RC0805FR-07499KL | RES,499KOhm,+/-1%,1/8W,G,SMD0805 | YAGEO CORPORATION COMPONENT | RC0805FR-07499KL | G | PWA BOM | In New BOM |
|  | R1492 | 1 | 610118800-017-G | RES,499KOhm,+/-1%,1/8W,G,SMD0805 | KOA SPEER ELECTRONICS, INC. | RK73H2ATTD4993F | G | PWA BOM | In Old BOM |
|  |  |  | 610118800-024-G | RES,499KOhm,+/-1%,1/8W,G,SMD0805 | PANASONIC INDUSTRIAL CO.,LTD. | ERJ6ENF4993V | G | PWA BOM | In Old BOM |
| 34 | R1493,R1847 | 2 | 61011LF00-017-G | RES,499KOhm,+/-1%,1/16W,G,SMD0402 | KOA SPEER ELECTRONICS, INC. | RK73H1ETTP4993F | G | PWA BOM | In New BOM |
|  |  |  | 61011LF00-024-G | RES,499KOhm,+/-1%,1/16W,G,SMD0402 | PANASONIC INDUSTRIAL CO.,LTD. | ERJ2RKF4993X | G | PWA BOM | In New BOM |
|  |  |  | 61011LF00-011-G | RES,499KOhm,+/-1%,1/16W,G,SMD0402 | YAGEO CORPORATION COMPONENT | RC0402FR-07499KL | G | PWA BOM | In New BOM |
|  |  |  | 61011LF00-044-G | RES,499KOhm,+/-1%,1/16W,G,SMD0402 | TA-I TECHNOLOGY CO., LTD. | RM04FTN4993 | G | PWA BOM | In New BOM |
|  | R1493,R1847 | 2 | 61011LF00-017-G | RES,499KOhm,+/-1%,1/16W,G,SMD0402 | KOA SPEER ELECTRONICS, INC. | RK73H1ETTP4993F | G | PWA BOM | In Old BOM |
|  |  |  | 61011LF00-024-G | RES,499KOhm,+/-1%,1/16W,G,SMD0402 | PANASONIC INDUSTRIAL CO.,LTD. | ERJ2RKF4993X | G | PWA BOM | In Old BOM |
| 35 | R1754 | 1 | 61011HC00-017-G | RES,2.7KOhm,+/-1%,1/16W,G,SMD0402 | KOA SPEER ELECTRONICS, INC. | RK73H1ETTP2701F | G | PWA BOM | In New BOM |
|  |  |  | 61011HC00-029-G | RES,2.7KOhm,+/-1%,1/16W,G,SMD0402 | VISHAY ENTER TECHNO LOGY.INC | CRCW04022K70FKED | G | PWA BOM | In New BOM |
|  |  |  | 61011HC00-024-G | RES,2.7KOhm,+/-1%,1/16W,G,SMD0402 | PANASONIC INDUSTRIAL CO.,LTD. | ERJ2RKF2701X | G | PWA BOM | In New BOM |
|  |  |  | 61011HC00-011-G | RES,2.7KOhm,+/-1%,1/16W,G,SMD0402 | YAGEO CORPORATION COMPONENT | RC0402FR-072K7L | G | PWA BOM | In New BOM |
|  |  |  | 61011HC00-044-G | RES,2.7KOhm,+/-1%,1/16W,G,SMD0402 | TA-I TECHNOLOGY CO., LTD. | RM04FTN2701 | G | PWA BOM | In New BOM |
|  | R1754 | 1 | 61011HC00-017-G | RES,2.7KOhm,+/-1%,1/16W,G,SMD0402 | KOA SPEER ELECTRONICS, INC. | RK73H1ETTP2701F | G | PWA BOM | In Old BOM |
|  |  |  | 61011HC00-029-G | RES,2.7KOhm,+/-1%,1/16W,G,SMD0402 | VISHAY ENTER TECHNO LOGY.INC | CRCW04022K70FKED | G | PWA BOM | In Old BOM |
|  |  |  | 61011HC00-024-G | RES,2.7KOhm,+/-1%,1/16W,G,SMD0402 | PANASONIC INDUSTRIAL CO.,LTD. | ERJ2RKF2701X | G | PWA BOM | In Old BOM |
| 36 | R1769,R1770 | 2 | 610130300-017-G | RES,60.4 Ohm,+/-1%,1/20W,G,SMD0201 | KOA SPEER ELECTRONICS, INC. | RK73H1HTTC60R4F | G | PWA BOM | In New BOM |
|  |  |  | 610130300-024-G | RES,60.4 Ohm,+/-1%,1/20W,G,SMD0201 | PANASONIC INDUSTRIAL CO.,LTD. | ERJ1GNF60R4C | G | PWA BOM | In New BOM |
|  |  |  | 610130300-029-G | RES,60.4 Ohm,+/-1%,1/20W,G,SMD0201 | VISHAY ENTER TECHNO LOGY.INC | CRCW020160R4FKED | G | PWA BOM | In New BOM |
|  |  |  | 610130300-011-G | RES,60.4 Ohm,+/-1%,1/20W,G,SMD0201 | YAGEO CORPORATION COMPONENT | RC0201FR-0760R4L | G | PWA BOM | In New BOM |
|  | R1769,R1770 | 2 | 610130300-017-G | RES,60.4 Ohm,+/-1%,1/20W,G,SMD0201 | KOA SPEER ELECTRONICS, INC. | RK73H1HTTC60R4F | G | PWA BOM | In Old BOM |
|  |  |  | 610130300-024-G | RES,60.4 Ohm,+/-1%,1/20W,G,SMD0201 | PANASONIC INDUSTRIAL CO.,LTD. | ERJ1GNF60R4C | G | PWA BOM | In Old BOM |
|  |  |  | 610130300-029-G | RES,60.4 Ohm,+/-1%,1/20W,G,SMD0201 | VISHAY ENTER TECHNO LOGY.INC | CRCW020160R4FKED | G | PWA BOM | In Old BOM |
| 37 | PHAR35 | 1 | 610113D00-017-G | RES,10.5KOhm,+/-1%,1/16W,G,SMD0402 | KOA SPEER ELECTRONICS, INC. | RK73H1ETTP1052F | N | PWA BOM | In New BOM |
|  | PHAR35 | 1 | 61011PE00-017-G | RES,8.87KOhm,+/-1%,1/16W,G,SMD0402 | KOA SPEER ELECTRONICS, INC. | RK73H1ETTP8871F | G | PWA BOM | In Old BOM |
|  |  |  | 61011PE00-024-G | RES,8.87KOhm,+/-1%,1/16W,G,SMD0402 | PANASONIC INDUSTRIAL CO.,LTD. | ERJ2RKF8871X | G | PWA BOM | In Old BOM |
|  |  |  | 61011PE00-029-G | RES,8.87KOhm,+/-1%,1/16W,G,SMD0402 | VISHAY ENTER TECHNO LOGY.INC | CRCW04028K87FKEDC | G | PWA BOM | In Old BOM |
| ##### Change Revision |  |  |  |  |  |  |  |  |  |
| Sheet | REV OF BOM | CUSTOMER | CUSTOMER P/N | PWA PN | PWA DESCRIPTION | PWA REV | DATE | Remark |  |
| OOOOOOOOOOOOOOOOOOOOOOOOOOOOOOOOOOOOOOOOOOOOOOOOOOOOOOOOOOOOOOOOOOOOOOOOOOOOOOOOOOOOOOOOOO | OOOOOOOOOOOOOOOOOOOOOOOOOOOOOOOOOOOOOOOOOOOOOOOOOOOOOOOOOOOOOOOOOOOOOOOOOOOOOOOOOOOOOOOOOO | OOOOOOOOOOOOOOOOOOOOOOOOOOOOOOOOOOOOOOOOOOOOOOOOOOOOOOOOOOOOOOOOOOOOOOOOOOOOOOOOOOOOOOOOOO | OOOOOOOOOOOOOOOOOOOOOOOOOOOOOOOOOOOOOOOOOOOOOOOOOOOOOOOOOOOOOOOOOOOOOOOOOOOOOOOOOOOOOOOOOO | OOOOOOOOOOOOOOOOOOOOOOOOOOOOOOOOOOOOOOOOOOOOOOOOOOOOOOOOOOOOOOOOOOOOOOOOOOOOOOOOOOOOOOOOOO | OOOOOOOOOOOOOOOOOOOOOOOOOOOOOOOOOOOOOOOOOOOOOOOOOOOOOOOOOOOOOOOOOOOOOOOOOOOOOOOOOOOOOOOOOO | OOOOOOOOOOOOOOOOOOOOOOOOOOOOOOOOOOOOOOOOOOOOOOOOOOOOOOOOOOOOOOOOOOOOOOOOOOOOOOOOOOOOOOOOOO | OOOOOOOOOOOOOOOOOOOOOOOOOOOOOOOOOOOOOOOOOOOOOOOOOOOOOOOOOOOOOOOOOOOOOOOOOOOOOOOOOOOOOOOOOO | OOOOOOOOOOOOOOOOOOOOOOOOOOOOOOOOOOOOOOOOOOOOOOOOOOOOOOOOOOOOOOOOOOOOOOOOOOOOOOOOOOOOOOOOOO | OOOOOOOOOOOOOOOOOOOOOOOOOOOOOOOOOOOOOOOOOOOOOOOOOOOOOOOOOOOOOOOOOOOOOOOOOOOOOOOOOOOOOOOOOO |
| Second Source Change |  |  |  |  |  |  |  |  |  |
| Item | Location | Change Type | Foxconn P/N | Part Description | Manufacturer Full Name | Manufacturer P/N | RoHS | Sheet |  |
| 1 | R4,R5,R9,R10,R103,R129,R130,R131,R150,R151,R154,R171,R172,R175,R192,R193,R195,R213,R214,R215,R234,R235,R236,R255,R256,R259,R276,R277,R279,R318,R319,R366,R367,R371,R372,R455,R458,R484,R485,R486,R505,R506,R509,R526,R527,R530,R547,R548,R550,R568,R569,R570,R589,R590,R591,R611,R612,R615,R631,R632,R634,R1072,R1080,R1232,R1340,R1341,R1350,R1351,R1352,R1353,R1354,R1355,R1356,R1357,R1358,R1359,R1361,R1363,R1364,R1365,R1366,R1367,R1377,R1378,R1379,R1380,R1381,R1382,R1383,R1384,R1385,R1386,R1387,R1388,R1389,R1390,R1391,R1392,R1746,R1775 |  | 610100T00-017-G | RES,1KOhm,+/-5%,1/16W,G,SMD0402 | KOA SPEER ELECTRONICS, INC. | RK73B1ETTP102J | G | PWA BOM |  |
|  |  | NO | 610100T00-024-G | RES,1KOhm,+/-5%,1/16W,G,SMD0402 | PANASONIC INDUSTRIAL CO.,LTD. | ERJ2GEJ102X | G | PWA BOM |  |
|  |  | ADD | 610100T00-011-G | RES,1KOhm,+/-5%,1/16W,G,SMD0402 | YAGEO CORPORATION COMPONENT | RC0402JR-071KL | G | PWA BOM |  |
|  |  | ADD | 610100T00-044-G | RES,1KOhm,+/-5%,1/16W,G,SMD0402 | TA-I TECHNOLOGY CO., LTD. | RM04JTN102 | G | PWA BOM |  |
| 2 | R16,R17,R18,R19,R20,R21,R24,R25,R33,R34,R35,R36,R37,R46,R47,R48,R49,R50,R51,R65,R66,R69,R76,R94,R95,R99,R100,R101,R104,R105,R106,R107,R110,R111,R112,R113,R122,R138,R139,R140,R146,R147,R148,R155,R160,R161,R164,R166,R169,R177,R180,R182,R186,R187,R189,R197,R198,R203,R206,R207,R208,R222,R223,R224,R230,R231,R232,R240,R244,R245,R248,R250,R253,R261,R264,R266,R270,R271,R273,R281,R282,R287,R291,R292,R293,R376,R379,R380,R381,R382,R383,R386,R387,R391,R392,R395,R396,R397,R398,R400,R405,R406,R407,R408,R409,R410,R421,R422,R423,R424,R425,R426,R427,R432,R435,R436,R445,R446,R449,R453,R456,R457,R459,R460,R461,R493,R494,R495,R501,R502,R503,R510,R515,R516,R519,R521,R524,R533,R535,R537,R541,R542,R544,R552,R553,R558,R561,R562,R563,R577,R578,R579,R585,R586,R587,R594,R599,R600,R603,R605,R608,R610,R617,R621,R625,R626,R628,R636,R637,R642,R645,R646,R647,R740,R748,R933,R935,R1346,R1348,R1349,R1368,R1371,R1374,R1396,R1397,R1401,R1402,R1408,R1409,R1410,R1411,R1419,R1420,R1421,R1429,R1430,R1431,R1591,R1822,R1827,R1828,R1829 |  | 610102700-017-G | RES,49.9 Ohm,+/-1%,1/16W,G,SMD0402 | KOA SPEER ELECTRONICS, INC. | RK73H1ETTP49R9F | G | PWA BOM |  |
|  |  | NO | 610102700-029-G | RES,49.9 Ohm,+/-1%,1/16W,G,SMD0402 | VISHAY ENTER TECHNO LOGY.INC | CRCW040249R9FKED | G | PWA BOM |  |
|  |  | NO | 610102700-024-G | RES,49.9 Ohm,+/-1%,1/16W,G,SMD0402 | PANASONIC INDUSTRIAL CO.,LTD. | ERJ2RKF49R9X | G | PWA BOM |  |
|  |  | ADD | 610102700-011-G | RES,49.9 Ohm,+/-1%,1/16W,G,SMD0402 | YAGEO CORPORATION COMPONENT | RC0402FR-0749R9L | G | PWA BOM |  |
|  |  | ADD | 610102700-044-G | RES,49.9 Ohm,+/-1%,1/16W,G,SMD0402 | TA-I TECHNOLOGY CO., LTD. | RM04FTN49R9 | G | PWA BOM |  |
| 3 | R22,R23,R26,R32,R38,R39,R41,R42,R43,R44,R45,R52,R68,R88,R89,R299,R300,R301,R302,R342,R384,R385,R388,R389,R390,R394,R399,R401,R403,R404,R411,R412,R413,R441,R442,R465,R466,R468,R469,R472,R475,R476,R954,R1029,R1031,R1032,R1033,R1034,R1035,R1041,R1042,R1043,R1044,R1047,R1048,R1050,R1051,R1054,R1055,R1059,R1060,R1063,R1064,R1067,R1068,R1127,R1128,R1139,R1141,R1225,R1227,R1229,R1234,R1239,R1336,R1337,R1466,R1468,R1524,R1525,R1553,R1823 |  | 61010KJ00-017-G | RES,3.3KOhm,+/-5%,1/16W,G,SMD0402 | KOA SPEER ELECTRONICS, INC. | RK73B1ETTP332J | G | PWA BOM |  |
|  |  | NO | 61010KJ00-024-G | RES,3.3KOhm,+/-5%,1/16W,G,SMD0402 | PANASONIC INDUSTRIAL CO.,LTD. | ERJ2GEJ332X | G | PWA BOM |  |
|  |  | ADD | 61010KJ00-044-G | RES,3.3KOhm,+/-5%,1/16W,G,SMD0402 | TA-I TECHNOLOGY CO., LTD. | RM04JTN332 | G | PWA BOM |  |
|  |  | ADD | 61010KJ00-011-G | RES,3.3KOhm,+/-5%,1/16W,G,SMD0402 | YAGEO CORPORATION COMPONENT | RC0402JR-073K3L | G | PWA BOM |  |
| 4 | R27,R28,R54,R55,R56,R57,R58,R59,R417,R418,R419,R420 |  | 610115E00-017-G | RES,1.2KOhm,+/-5%,1/16W,G,SMD0402 | KOA SPEER ELECTRONICS, INC. | RK73B1ETTP122J | G | PWA BOM |  |
|  |  | NO | 610115E00-024-G | RES,1.2KOhm,+/-5%,1/16W,G,SMD0402 | PANASONIC INDUSTRIAL CO.,LTD. | ERJ2GEJ122X | G | PWA BOM |  |
|  |  | ADD | 610115E00-011-G | RES,1.2KOhm,+/-5%,1/16W,G,SMD0402 | YAGEO CORPORATION COMPONENT | RC0402JR-071K2L | G | PWA BOM |  |
|  |  | ADD | 610115E00-044-G | RES,1.2KOhm,+/-5%,1/16W,G,SMD0402 | TA-I TECHNOLOGY CO., LTD. | RM04JTN122 | G | PWA BOM |  |
| 5 | R78 |  | 610115T00-017-G | RES,40.2KOhm,+/-1%,1/16W,G,SMD0402 | KOA SPEER ELECTRONICS, INC. | RK73H1ETTP4022F | G | PWA BOM |  |
|  |  | NO | 610115T00-029-G | RES,40.2KOhm,+/-1%,1/16W,G,SMD0402 | VISHAY ENTER TECHNO LOGY.INC | CRCW040240K2FKEDC | G | PWA BOM |  |
|  |  | ADD | 610115T00-011-G | RES,40.2KOhm,+/-1%,1/16W,G,SMD0402 | YAGEO CORPORATION COMPONENT | RC0402FR-0740K2L | G | PWA BOM |  |
|  |  | ADD | 610115T00-044-G | RES,40.2KOhm,+/-1%,1/16W,G,SMD0402 | TA-I TECHNOLOGY CO., LTD. | RM04FTN4022 | G | PWA BOM |  |
| 6 | R97,R98,R447,R452,R454 |  | 610112W00-017-G | RES,2KOhm,+/-5%,1/16W,G,SMD0402 | KOA SPEER ELECTRONICS, INC. | RK73B1ETTP202J | G | PWA BOM |  |
|  |  | NO | 610112W00-024-G | RES,2KOhm,+/-5%,1/16W,G,SMD0402 | PANASONIC INDUSTRIAL CO.,LTD. | ERJ2GEJ202X | G | PWA BOM |  |
|  |  | ADD | 610112W00-011-G | RES,2KOhm,+/-5%,1/16W,G,SMD0402 | YAGEO CORPORATION COMPONENT | RC0402JR-072KL | G | PWA BOM |  |
|  |  | ADD | 610112W00-044-G | RES,2KOhm,+/-5%,1/16W,G,SMD0402 | TA-I TECHNOLOGY CO., LTD. | RM04JTN202 | G | PWA BOM |  |
| 7 | R108,R109,R463,R464 |  | 61010DL01-017-G | RES,0 Ohm,+/-5%,1/8W,G,SMD0805 | KOA SPEER ELECTRONICS, INC. | RK73Z2ATTD | G | PWA BOM |  |
|  |  | NO | 61010DL00-024-G | RES,0 Ohm,+/-5%,1/8W,G,SMD0805 | PANASONIC INDUSTRIAL CO.,LTD. | ERJ6GEY0R00V | G | PWA BOM |  |
|  |  | ADD | 61010DL00-011-G | RES,0 Ohm,+/-5%,1/8W,G,SMD0805 | YAGEO CORPORATION COMPONENT | RC0805JR-070RL | G | PWA BOM |  |
|  |  | ADD | 61010DL00-044-G | RES,0 Ohm,+/-5%,1/8W,G,SMD0805 | TA-I TECHNOLOGY CO., LTD. | RM10JTN0 | G | PWA BOM |  |
| 8 | R132,R137,R141,R143,R152,R158,R162,R167,R173,R179,R183,R188,R194,R200,R204,R209,R216,R221,R225,R227,R237,R239,R246,R251,R257,R263,R267,R272,R278,R284,R288,R290,R487,R492,R496,R498,R507,R513,R517,R522,R528,R531,R538,R543,R549,R555,R559,R564,R571,R576,R580,R582,R592,R597,R601,R606,R613,R620,R622,R627,R633,R639,R643,R648,R934 |  | 610102E00-017-G | RES,100 Ohm,+/-5%,1/16W,G,SMD0402 | KOA SPEER ELECTRONICS, INC. | RK73B1ETTP101J | G | PWA BOM |  |
|  |  | NO | 610102E00-029-G | RES,100 Ohm,+/-5%,1/16W,G,SMD0402 | VISHAY ENTER TECHNO LOGY.INC | CRCW0402100RJNED | G | PWA BOM |  |
|  |  | ADD | 610102E00-011-G | RES,100 Ohm,+/-5%,1/16W,G,SMD0402 | YAGEO CORPORATION COMPONENT | RC0402JR-07100RL | G | PWA BOM |  |
|  |  | ADD | 610102E00-044-G | RES,100 Ohm,+/-5%,1/16W,G,SMD0402 | TA-I TECHNOLOGY CO., LTD. | RM04JTN101 | G | PWA BOM |  |
| 9 | R297,R298,R304,R1069,R1070,R1342,R1343 |  | 610107B00-017-G | RES,4.7KOhm,+/-5%,1/16W,G,SMD0402 | KOA SPEER ELECTRONICS, INC. | RK73B1ETTP472J | G | PWA BOM |  |
|  |  | NO | 610107B00-024-G | RES,4.7KOhm,+/-5%,1/16W,G,SMD0402 | PANASONIC INDUSTRIAL CO.,LTD. | ERJ2GEJ472X | G | PWA BOM |  |
|  |  | NO | 610107B00-029-G | RES,4.7KOhm,+/-5%,1/16W,G,SMD0402 | VISHAY ENTER TECHNO LOGY.INC | CRCW04024K70JNED | G | PWA BOM |  |
|  |  | ADD | 610107B00-011-G | RES,4.7KOhm,+/-5%,1/16W,G,SMD0402 | YAGEO CORPORATION COMPONENT | RC0402JR-074K7L | G | PWA BOM |  |
|  |  | ADD | 610107B00-044-G | RES,4.7KOhm,+/-5%,1/16W,G,SMD0402 | TA-I TECHNOLOGY CO., LTD. | RM04JTN472 | G | PWA BOM |  |
| 10 | R307 |  | 610112U00-017-G | RES,499 Ohm,+/-1%,1/16W,G,SMD0402 | KOA SPEER ELECTRONICS, INC. | RK73H1ETTP4990F | G | PWA BOM |  |
|  |  | NO | 610112U00-024-G | RES,499 Ohm,+/-1%,1/16W,G,SMD0402 | PANASONIC INDUSTRIAL CO.,LTD. | ERJ2RKF4990X | G | PWA BOM |  |
|  |  | ADD | 610112U00-011-G | RES,499 Ohm,+/-1%,1/16W,G,SMD0402 | YAGEO CORPORATION COMPONENT | RC0402FR-07499RL | G | PWA BOM |  |
|  |  | ADD | 610112U00-044-G | RES,499 Ohm,+/-1%,1/16W,G,SMD0402 | TA-I TECHNOLOGY CO., LTD. | RM04FTN4990 | G | PWA BOM |  |
| 11 | R310,R990 |  | 610107C00-017-G | RES,10KOhm,+/-5%,1/16W,G,SMD0402 | KOA SPEER ELECTRONICS, INC. | RK73B1ETTP103J | G | PWA BOM |  |
|  |  | NO | 610107C00-024-G | RES,10KOhm,+/-5%,1/16W,G,SMD0402 | PANASONIC INDUSTRIAL CO.,LTD. | ERJ2GEJ103X | G | PWA BOM |  |
|  |  | NO | 610107C00-029-G | RES,10KOhm,+/-5%,1/16W,G,SMD0402 | VISHAY ENTER TECHNO LOGY.INC | CRCW040210K0JNED | G | PWA BOM |  |
|  |  | ADD | 610107C00-011-G | RES,10KOhm,+/-5%,1/16W,G,SMD0402 | YAGEO CORPORATION COMPONENT | RC0402JR-0710KL | G | PWA BOM |  |
|  |  | ADD | 610107C00-044-G | RES,10KOhm,+/-5%,1/16W,G,SMD0402 | TA-I TECHNOLOGY CO., LTD. | RM04JTN103 | G | PWA BOM |  |
| 12 | R329 |  | 610118G00-017-G | RES,90.9KOhm,+/-1%,1/16W,G,SMD0402 | KOA SPEER ELECTRONICS, INC. | RK73H1ETTP9092F | G | PWA BOM |  |
|  |  | NO | 610118G00-024-G | RES,90.9KOhm,+/-1%,1/16W,G,SMD0402 | PANASONIC INDUSTRIAL CO.,LTD. | ERJ2RKF9092X | G | PWA BOM |  |
|  |  | ADD | 610118G00-011-G | RES,90.9KOhm,+/-1%,1/16W,G,SMD0402 | YAGEO CORPORATION COMPONENT | RC0402FR-0790K9L | G | PWA BOM |  |
|  |  | ADD | 610118G00-044-G | RES,90.9KOhm,+/-1%,1/16W,G,SMD0402 | TA-I TECHNOLOGY CO., LTD. | RM04FTN9092 | G | PWA BOM |  |
| 13 | R332,R333,R334,R335,R336,R337,R338,R339,R340,R341,R343,R344,R345 |  | 610116J00-017-G | RES,1.21KOhm,+/-1%,1/16W,G,SMD0402 | KOA SPEER ELECTRONICS, INC. | RK73H1ETTP1211F | G | PWA BOM |  |
|  |  | NO | 610116J00-024-G | RES,1.21KOhm,+/-1%,1/16W,G,SMD0402 | PANASONIC INDUSTRIAL CO.,LTD. | ERJ2RKF1211X | G | PWA BOM |  |
|  |  | NO | 610116J00-029-G | RES,1.21KOhm,+/-1%,1/16W,G,SMD0402 | VISHAY ENTER TECHNO LOGY.INC | CRCW04021K21FKED | G | PWA BOM |  |
|  |  | ADD | 610116J00-011-G | RES,1.21KOhm,+/-1%,1/16W,G,SMD040 | YAGEO CORPORATION COMPONENT | RC0402FR-071K21L | G | PWA BOM |  |
|  |  | ADD | 610116J00-044-G | RES,1.21KOhm,+/-1%,1/16W,G,SMD0402 | TA-I TECHNOLOGY CO., LTD. | RM04FTN1211 | G | PWA BOM |  |
| 14 | R346 |  | 610114W00-017-G | RES,3.01KOhm,+/-1%,1/16W,G,SMD0402 | KOA SPEER ELECTRONICS, INC. | RK73H1ETTP3011F | G | PWA BOM |  |
|  |  | NO | 610114W00-029-G | RES,3.01KOhm,+/-1%,1/16W,G,SMD0402 | VISHAY ENTER TECHNO LOGY.INC | CRCW04023K01FKED | G | PWA BOM |  |
|  |  | ADD | 610114W00-011-G | RES,3.01KOhm,+/-1%,1/16W,G,SMD0402 | YAGEO CORPORATION COMPONENT | RC0402FR-073K01L | G | PWA BOM |  |
|  |  | ADD | 610114W00-044-G | RES,3.01KOhm,+/-1%,1/16W,G,SMD0402 | TA-I TECHNOLOGY CO., LTD. | RM04FTN3011 | G | PWA BOM |  |
| 15 | R349 |  | 61010L600-017-G | RES,11KOhm,+/-1%,1/16W,G,SMD0402 | KOA SPEER ELECTRONICS, INC. | RK73H1ETTP1102F | G | PWA BOM |  |
|  |  | NO | 61010L600-024-G | RES,11KOhm,+/-1%,1/16W,G,SMD0402 | PANASONIC INDUSTRIAL CO.,LTD. | ERJ2RKF1102X | G | PWA BOM |  |
|  |  | NO | 61010L600-029-G | RES,11KOhm,+/-1%,1/16W,G,SMD0402 | VISHAY ENTER TECHNO LOGY.INC | CRCW040211K0FKEDC | G | PWA BOM |  |
|  |  | ADD | 61010L600-011-G | RES,11KOhm,+/-1%,1/16W,G,SMD0402 | YAGEO CORPORATION COMPONENT | RC0402FR-0711KL | G | PWA BOM |  |
|  |  | ADD | 61010L600-044-G | RES,11KOhm,+/-1%,1/16W,G,SMD0402 | TA-I TECHNOLOGY CO., LTD. | RM04FTN1102 | G | PWA BOM |  |
| 16 | R738,R1111 |  | 61011B000-017-G | RES,1.5KOhm,+/-1%,1/16W,G,SMD0402 | KOA SPEER ELECTRONICS, INC. | RK73H1ETTP1501F | G | PWA BOM |  |
|  |  | NO | 61011B000-024-G | RES,1.5KOhm,+/-1%,1/16W,G,SMD0402 | PANASONIC INDUSTRIAL CO.,LTD. | ERJ2RKF1501X | G | PWA BOM |  |
|  |  | ADD | 61011B000-011-G | RES,1.5KOhm,+/-1%,1/16W,G,SMD0402 | YAGEO CORPORATION COMPONENT | RC0402FR-071K5L | G | PWA BOM |  |
|  |  | ADD | 61011B000-044-G | RES,1.5KOhm,+/-1%,1/16W,G,SMD0402 | TA-I TECHNOLOGY CO., LTD. | RM04FTN1501 | G | PWA BOM |  |
| 17 | R739,R741,R742,R743,R749,R936,R937,R993,R994,R995,R996,R997 |  | 610101V00-017-G | RES,22 Ohm,+/-5%,1/16W,G,SMD0402 | KOA SPEER ELECTRONICS, INC. | RK73B1ETTP220J | G | PWA BOM |  |
|  |  | NO | 610101V00-024-G | RES,22 Ohm,+/-5%,1/16W,G,SMD0402 | PANASONIC INDUSTRIAL CO.,LTD. | ERJ2GEJ220X | G | PWA BOM |  |
|  |  | ADD | 610101V00-011-G | RES,22 Ohm,+/-5%,1/16W,G,SMD0402 | YAGEO CORPORATION COMPONENT | RC0402JR-0722RL | G | PWA BOM |  |
|  |  | ADD | 610101V00-044-G | RES,22 Ohm,+/-5%,1/16W,G,SMD0402 | TA-I TECHNOLOGY CO., LTD. | RM04JTN220 | G | PWA BOM |  |
| 18 | R753 |  | 610112L00-017-G | RES,1.24KOhm,+/-1%,1/16W,G,SMD0402 | KOA SPEER ELECTRONICS, INC. | RK73H1ETTP1241F | G | PWA BOM |  |
|  |  | NO | 610112L00-029-G | RES,1.24KOhm,+/-1%,1/16W,G,SMD0402 | VISHAY ENTER TECHNO LOGY.INC | CRCW04021K24FKED | G | PWA BOM |  |
|  |  | NO | 610112L00-024-G | RES,1.24KOhm,+/-1%,1/16W,G,SMD0402 | PANASONIC INDUSTRIAL CO.,LTD. | ERJ2RKF1241X | G | PWA BOM |  |
|  |  | ADD | 610112L00-011-G | RES,1.24KOhm,+/-1%,1/16W,G,SMD0402 | YAGEO CORPORATION COMPONENT | RC0402FR-071K24L | G | PWA BOM |  |
|  |  | ADD | 610112L00-044-G | RES,1.24KOhm,+/-1%,1/16W,G,SMD0402 | TA-I TECHNOLOGY CO., LTD. | RM04FTN1241 | G | PWA BOM |  |
| 19 | R792,R793,R794,R796,R797,R799 |  | 610115J00-017-G | RES,33 Ohm,+/-1%,1/16W,G,SMD0402 | KOA SPEER ELECTRONICS, INC. | RK73H1ETTP33R0F | G | PWA BOM |  |
|  |  | NO | 610115J00-024-G | RES,33 Ohm,+/-1%,1/16W,G,SMD0402 | PANASONIC INDUSTRIAL CO.,LTD. | ERJ2RKF33R0X | G | PWA BOM |  |
|  |  | ADD | 610115J00-011-G | RES,33 Ohm,+/-1%,1/16W,G,SMD0402 | YAGEO CORPORATION COMPONENT | RC0402FR-0733RL | G | PWA BOM |  |
|  |  | ADD | 610115J00-044-G | RES,33 Ohm,+/-1%,1/16W,G,SMD0402 | TA-I TECHNOLOGY CO., LTD. | RM04FTN33R0 | G | PWA BOM |  |
| 20 | R815,R816,R818,R1015,R1161,R1163,R1171,R1173,R1183,R1189,R1196,R1202,R1206,R1209,R1226,R1307,R1314,R1315,R1316,R1317,R1318,R1319,R1320,R1502 |  | 61011H500-017-G | RES,22 Ohm,+/-1%,1/16W,G,SMD0402 | KOA SPEER ELECTRONICS, INC. | RK73H1ETTP22R0F | G | PWA BOM |  |
|  |  | NO | 61011H500-024-G | RES,22 Ohm,+/-1%,1/16W,G,SMD0402 | PANASONIC INDUSTRIAL CO.,LTD. | ERJ2RKF22R0X | G | PWA BOM |  |
|  |  | ADD | 61011H500-011-G | RES,22 Ohm,+/-1%,1/16W,G,SMD0402 | YAGEO CORPORATION COMPONENT | RC0402FR-0722RL | G | PWA BOM |  |
|  |  | ADD | 61011H500-044-G | RES,22 Ohm,+/-1%,1/16W,G,SMD0402 | TA-I TECHNOLOGY CO., LTD. | RM04FTN22R0 | G | PWA BOM |  |
| 21 | R831,R832,R833,R834,R1345,R1347,R1494 |  | 61011H100-017-G | RES,220 Ohm,+/-1%,1/16W,G,SMD0402 | KOA SPEER ELECTRONICS, INC. | RK73H1ETTP2200F | G | PWA BOM |  |
|  |  | NO | 61011H100-024-G | RES,220 Ohm,+/-1%,1/16W,G,SMD0402 | PANASONIC INDUSTRIAL CO.,LTD. | ERJ2RKF2200X | G | PWA BOM |  |
|  |  | NO | 61011H100-029-G | RES,220 Ohm,+/-1%,1/16W,G,SMD0402 | VISHAY ENTER TECHNO LOGY.INC | CRCW0402220RFKEDC | G | PWA BOM |  |
|  |  | ADD | 61011H100-011-G | RES,220 Ohm,+/-1%,1/16W,G,SMD0402 | YAGEO CORPORATION COMPONENT | RC0402FR-07220RL | G | PWA BOM |  |
| 22 | R886 |  | 61011KH00-017-G | RES,240 Ohm,+/-5%,1/16W,G,SMD0402 | KOA SPEER ELECTRONICS, INC. | RK73B1ETTP241J | G | PWA BOM |  |
|  |  | NO | 61011KH00-024-G | RES,240 Ohm,+/-5%,1/16W,G,SMD0402 | PANASONIC INDUSTRIAL CO.,LTD. | ERJ2GEJ241X | G | PWA BOM |  |
|  |  | ADD | 61011KH00-011-G | RES,240 Ohm,+/-5%,1/16W,G,SMD0402 | YAGEO CORPORATION COMPONENT | RC0402JR-07240RL | G | PWA BOM |  |
|  |  | ADD | 61011KH00-044-G | RES,240 Ohm,+/-5%,1/16W,G,SMD0402 | TA-I TECHNOLOGY CO., LTD. | RM04JTN241 | G | PWA BOM |  |
| 23 | R925,R927,R929 |  | 610102600-017-G | RES,56 Ohm,+/-1%,1/16W,G,SMD0402 | KOA SPEER ELECTRONICS, INC. | RK73H1ETTP56R0F | G | PWA BOM |  |
|  |  | NO | 610102600-024-G | RES,56 Ohm,+/-1%,1/16W,G,SMD0402 | PANASONIC INDUSTRIAL CO.,LTD. | ERJ2RKF56R0X | G | PWA BOM |  |
|  |  | ADD | 610102600-011-G | RES,56 Ohm,+/-1%,1/16W,G,SMD0402 | YAGEO CORPORATION COMPONENT | RC0402FR-0756RL | G | PWA BOM |  |
|  |  | ADD | 610102600-044-G | RES,56 Ohm,+/-1%,1/16W,G,SMD0402 | TA-I TECHNOLOGY CO., LTD. | RM04FTN56R0 | G | PWA BOM |  |
| 24 | R960,R1323,R1325,R1327,R1328,R1412,R1413,R1414,R1416,R1417,R1418,R1422,R1423,R1424,R1425,R1426,R1427,R1428,R1505,R1506,R1516,R1517,R1518,R1523,R1783 |  | 610114U00-017-G | RES,3.3KOhm,+/-1%,1/16W,G,SMD0402 | KOA SPEER ELECTRONICS, INC. | RK73H1ETTP3301F | G | PWA BOM |  |
|  |  | NO | 610114U00-024-G | RES,3.3KOhm,+/-1%,1/16W,G,SMD0402 | PANASONIC INDUSTRIAL CO.,LTD. | ERJ2RKF3301X | G | PWA BOM |  |
|  |  | ADD | 610114U00-011-G | RES,3.3KOhm,+/-1%,1/16W,G,SMD0402 | YAGEO CORPORATION COMPONENT | RC0402FR-073K3L | G | PWA BOM |  |
|  |  | ADD | 610114U00-044-G | RES,3.3KOhm,+/-1%,1/16W,G,SMD0402 | TA-I TECHNOLOGY CO., LTD. | RM04FTN3301 | G | PWA BOM |  |
| 25 | R971 |  | 61010A000-017-G | RES,8.2KOhm,+/-5%,1/16W,G,SMD0402 | KOA SPEER ELECTRONICS, INC. | RK73B1ETTP822J | G | PWA BOM |  |
|  |  | NO | 61010A000-024-G | RES,8.2KOhm,+/-5%,1/16W,G,SMD0402 | PANASONIC INDUSTRIAL CO.,LTD. | ERJ2GEJ822X | G | PWA BOM |  |
|  |  | ADD | 61010A000-011-G | RES,8.2KOhm,+/-5%,1/16W,G,SMD0402 | YAGEO CORPORATION COMPONENT | RC0402JR-078K2L | G | PWA BOM |  |
|  |  | ADD | 61010A000-044-G | RES,8.2KOhm,+/-5%,1/16W,G,SMD0402 | TA-I TECHNOLOGY CO., LTD. | RM04JTN822 | G | PWA BOM |  |
| 26 | R1000,R1002 |  | 610118100-017-G | RES,1.4KOhm,+/-1%,1/16W,G,SMD0402 | KOA SPEER ELECTRONICS, INC. | RK73H1ETTP1401F | G | PWA BOM |  |
|  |  | NO | 610118100-024-G | RES,1.4KOhm,+/-1%,1/16W,G,SMD0402 | PANASONIC INDUSTRIAL CO.,LTD. | ERJ2RKF1401X | G | PWA BOM |  |
|  |  | ADD | 610118100-011-G | RES,1.4KOhm,+/-1%,1/16W,G,SMD0402 | YAGEO CORPORATION COMPONENT | RC0402FR-071K4L | G | PWA BOM |  |
|  |  | ADD | 610118100-044-G | RES,1.4KOhm,+/-1%,1/16W,G,SMD0402 | TA-I TECHNOLOGY CO., LTD. | RM04FTN1401 | G | PWA BOM |  |
| 27 | R1026 |  | 610114R00-017-G | RES,49.9KOhm,+/-1%,1/16W,G,SMD0402 | KOA SPEER ELECTRONICS, INC. | RK73H1ETTP4992F | G | PWA BOM |  |
|  |  | NO | 610114R00-029-G | RES,49.9KOhm,+/-1%,1/16W,G,SMD0402 | VISHAY ENTER TECHNO LOGY.INC | CRCW040249K9FKED | G | PWA BOM |  |
|  |  | ADD | 610114R00-011-G | RES,49.9KOhm,+/-1%,1/16W,G,SMD0402 | YAGEO CORPORATION COMPONENT | RC0402FR-0749K9L | G | PWA BOM |  |
|  |  | ADD | 610114R00-044-G | RES,49.9KOhm,+/-1%,1/16W,G,SMD0402 | TA-I TECHNOLOGY CO., LTD. | RM04FTN4992 | G | PWA BOM |  |
| 28 | R1027 |  | 610115W00-017-G | RES,18KOhm,+/-1%,1/16W,G,SMD0402 | KOA SPEER ELECTRONICS, INC. | RK73H1ETTP1802F | G | PWA BOM |  |
|  |  | NO | 610115W00-024-G | RES,18KOhm,+/-1%,1/16W,G,SMD0402 | PANASONIC INDUSTRIAL CO.,LTD. | ERJ2RKF1802X | G | PWA BOM |  |
|  |  | ADD | 610115W00-011-G | RES,18KOhm,+/-1%,1/16W,G,SMD0402 | YAGEO CORPORATION COMPONENT | RC0402FR-0718KL | G | PWA BOM |  |
|  |  | ADD | 610115W00-044-G | RES,18KOhm,+/-1%,1/16W,G,SMD0402 | TA-I TECHNOLOGY CO., LTD. | RM04FTN1802 | G | PWA BOM |  |
| 29 | R1147 |  | 610112800-017-G | RES,6.04KOhm,+/-1%,1/16W,G,SMD0402 | KOA SPEER ELECTRONICS, INC. | RK73H1ETTP6041F | G | PWA BOM |  |
|  |  | NO | 610112800-029-G | RES,6.04KOhm,+/-1%,1/16W,G,SMD0402 | VISHAY ENTER TECHNO LOGY.INC | CRCW04026K04FKED | G | PWA BOM |  |
|  |  | ADD | 610112800-011-G | RES,6.04KOhm,+/-1%,1/16W,G,SMD0402 | YAGEO CORPORATION COMPONENT | RC0402FR-076K04L | G | PWA BOM |  |
|  |  | ADD | 610112800-044-G | RES,6.04KOhm,+/-1%,1/16W,G,SMD0402 | TA-I TECHNOLOGY CO., LTD. | RM04FTN6041 | G | PWA BOM |  |
| 30 | R1251,R1252,R1253,R1254,R1395,R1398 |  | 610103300-017-G | RES,100KOhm,+/-5%,1/16W,G,SMD0402 | KOA SPEER ELECTRONICS, INC. | RK73B1ETTP104J | G | PWA BOM |  |
|  |  | NO | 610103300-029-G | RES,100KOhm,+/-5%,1/16W,G,SMD0402 | VISHAY ENTER TECHNO LOGY.INC | CRCW0402100KJNED | G | PWA BOM |  |
|  |  | ADD | 610103300-011-G | RES,100KOhm,+/-5%,1/16W,G,SMD0402 | YAGEO CORPORATION COMPONENT | RC0402JR-07100KL | G | PWA BOM |  |
|  |  | ADD | 610103300-044-G | RES,100KOhm,+/-5%,1/16W,G,SMD0402 | TA-I TECHNOLOGY CO., LTD. | RM04JTN104 | G | PWA BOM |  |
| 31 | R1280 |  | 610112N00-017-G | RES,130 Ohm,+/-1%,1/16W,G,SMD0402 | KOA SPEER ELECTRONICS, INC. | RK73H1ETTP1300F | G | PWA BOM |  |
|  |  | NO | 610112N00-029-G | RES,130 Ohm,+/-1%,1/16W,G,SMD0402 | VISHAY ENTER TECHNO LOGY.INC | CRCW0402130RFKED | G | PWA BOM |  |
|  |  | NO | 610112N00-024-G | RES,130 Ohm,+/-1%,1/16W,G,SMD0402 | PANASONIC INDUSTRIAL CO.,LTD. | ERJ2RKF1300X | G | PWA BOM |  |
|  |  | ADD | 610112N00-011-G | RES,130 Ohm,+/-1%,1/16W,G,SMD0402 | YAGEO CORPORATION COMPONENT | RC0402FR-07130RL | G | PWA BOM |  |
|  |  | ADD | 610112N00-044-G | RES,130 Ohm,+/-1%,1/16W,G,SMD0402 | TA-I TECHNOLOGY CO., LTD. | RM04FTN1300 | G | PWA BOM |  |
| 32 | R1298 |  | 61010AC00-017-G | RES,2.2 Ohm,+/-1%,1/10W,G,SMD0603 | KOA SPEER ELECTRONICS, INC. | RK73H1JTTD2R20F | G | PWA BOM |  |
|  |  | NO | 61010AC00-024-G | RES,2.2 Ohm,+/-1%,1/10W,G,SMD0603 | PANASONIC INDUSTRIAL CO.,LTD. | ERJ3RQF2R2V | G | PWA BOM |  |
|  |  | ADD | 61010AC00-011-G | RES,2.2 Ohm,+/-1%,1/10W,G,SMD0603 | YAGEO CORPORATION COMPONENT | RC0603FR-072R2L | G | PWA BOM |  |
|  |  | ADD | 61010AC00-044-G | RES,2.2 Ohm,+/-1%,1/10W,G,SMD0603 | TA-I TECHNOLOGY CO., LTD. | RM06FTN2R20 | G | PWA BOM |  |
| 33 | R1492 |  | 610118800-017-G | RES,499KOhm,+/-1%,1/8W,G,SMD0805 | KOA SPEER ELECTRONICS, INC. | RK73H2ATTD4993F | G | PWA BOM |  |
|  |  | NO | 610118800-024-G | RES,499KOhm,+/-1%,1/8W,G,SMD0805 | PANASONIC INDUSTRIAL CO.,LTD. | ERJ6ENF4993V | G | PWA BOM |  |
|  |  | ADD | RC0805FR-07499KL | RES,499KOhm,+/-1%,1/8W,G,SMD0805 | YAGEO CORPORATION COMPONENT | RC0805FR-07499KL | G | PWA BOM |  |
| 34 | R1493,R1847 |  | 61011LF00-017-G | RES,499KOhm,+/-1%,1/16W,G,SMD0402 | KOA SPEER ELECTRONICS, INC. | RK73H1ETTP4993F | G | PWA BOM |  |
|  |  | NO | 61011LF00-024-G | RES,499KOhm,+/-1%,1/16W,G,SMD0402 | PANASONIC INDUSTRIAL CO.,LTD. | ERJ2RKF4993X | G | PWA BOM |  |
|  |  | ADD | 61011LF00-011-G | RES,499KOhm,+/-1%,1/16W,G,SMD0402 | YAGEO CORPORATION COMPONENT | RC0402FR-07499KL | G | PWA BOM |  |
|  |  | ADD | 61011LF00-044-G | RES,499KOhm,+/-1%,1/16W,G,SMD0402 | TA-I TECHNOLOGY CO., LTD. | RM04FTN4993 | G | PWA BOM |  |
| 35 | R1754 |  | 61011HC00-017-G | RES,2.7KOhm,+/-1%,1/16W,G,SMD0402 | KOA SPEER ELECTRONICS, INC. | RK73H1ETTP2701F | G | PWA BOM |  |
|  |  | NO | 61011HC00-029-G | RES,2.7KOhm,+/-1%,1/16W,G,SMD0402 | VISHAY ENTER TECHNO LOGY.INC | CRCW04022K70FKED | G | PWA BOM |  |
|  |  | NO | 61011HC00-024-G | RES,2.7KOhm,+/-1%,1/16W,G,SMD0402 | PANASONIC INDUSTRIAL CO.,LTD. | ERJ2RKF2701X | G | PWA BOM |  |
|  |  | ADD | 61011HC00-011-G | RES,2.7KOhm,+/-1%,1/16W,G,SMD0402 | YAGEO CORPORATION COMPONENT | RC0402FR-072K7L | G | PWA BOM |  |
|  |  | ADD | 61011HC00-044-G | RES,2.7KOhm,+/-1%,1/16W,G,SMD0402 | TA-I TECHNOLOGY CO., LTD. | RM04FTN2701 | G | PWA BOM |  |
| 36 | R1769,R1770 |  | 610130300-017-G | RES,60.4 Ohm,+/-1%,1/20W,G,SMD0201 | KOA SPEER ELECTRONICS, INC. | RK73H1HTTC60R4F | G | PWA BOM |  |
|  |  | NO | 610130300-024-G | RES,60.4 Ohm,+/-1%,1/20W,G,SMD0201 | PANASONIC INDUSTRIAL CO.,LTD. | ERJ1GNF60R4C | G | PWA BOM |  |
|  |  | NO | 610130300-029-G | RES,60.4 Ohm,+/-1%,1/20W,G,SMD0201 | VISHAY ENTER TECHNO LOGY.INC | CRCW020160R4FKED | G | PWA BOM |  |
|  |  | ADD | 610130300-011-G | RES,60.4 Ohm,+/-1%,1/20W,G,SMD0201 | YAGEO CORPORATION COMPONENT | RC0201FR-0760R4L | G | PWA BOM |  |
| OOOOOOOOOOOOOOOOOOOOOOOOOOOOOOOOOOOOOOOOOOOOOOOOOOOOOOOOOOOOOOOOOOOOOOOOOOOOOOOOOOOOOOOOOO | OOOOOOOOOOOOOOOOOOOOOOOOOOOOOOOOOOOOOOOOOOOOOOOOOOOOOOOOOOOOOOOOOOOOOOOOOOOOOOOOOOOOOOOOOO | OOOOOOOOOOOOOOOOOOOOOOOOOOOOOOOOOOOOOOOOOOOOOOOOOOOOOOOOOOOOOOOOOOOOOOOOOOOOOOOOOOOOOOOOOO | OOOOOOOOOOOOOOOOOOOOOOOOOOOOOOOOOOOOOOOOOOOOOOOOOOOOOOOOOOOOOOOOOOOOOOOOOOOOOOOOOOOOOOOOOO | OOOOOOOOOOOOOOOOOOOOOOOOOOOOOOOOOOOOOOOOOOOOOOOOOOOOOOOOOOOOOOOOOOOOOOOOOOOOOOOOOOOOOOOOOO | OOOOOOOOOOOOOOOOOOOOOOOOOOOOOOOOOOOOOOOOOOOOOOOOOOOOOOOOOOOOOOOOOOOOOOOOOOOOOOOOOOOOOOOOOO | OOOOOOOOOOOOOOOOOOOOOOOOOOOOOOOOOOOOOOOOOOOOOOOOOOOOOOOOOOOOOOOOOOOOOOOOOOOOOOOOOOOOOOOOOO | OOOOOOOOOOOOOOOOOOOOOOOOOOOOOOOOOOOOOOOOOOOOOOOOOOOOOOOOOOOOOOOOOOOOOOOOOOOOOOOOOOOOOOOOOO | OOOOOOOOOOOOOOOOOOOOOOOOOOOOOOOOOOOOOOOOOOOOOOOOOOOOOOOOOOOOOOOOOOOOOOOOOOOOOOOOOOOOOOOOOO | OOOOOOOOOOOOOOOOOOOOOOOOOOOOOOOOOOOOOOOOOOOOOOOOOOOOOOOOOOOOOOOOOOOOOOOOOOOOOOOOOOOOOOOOOO |
| Master Materials Change |  |  |  |  |  |  |  |  |  |
| Item | Foxconn P/N | Orig._Usage | New_Usage | Part Description | Manufacturer Full Name | Manufacturer P/N | RoHS | Location | Sheet |
| 1 | 61011PE00-017-G | 2 | 1 | RES,8.87KOhm,+/-1%,1/16W,G,SMD0402 | KOA SPEER ELECTRONICS, INC. | RK73H1ETTP8871F | G | (-)PHAR35 | PWA BOM |
|  | 61011PE00-024-G |  |  | RES,8.87KOhm,+/-1%,1/16W,G,SMD0402 | PANASONIC INDUSTRIAL CO.,LTD. | ERJ2RKF8871X |  |  | PWA BOM |
|  | 61011PE00-029-G |  |  | RES,8.87KOhm,+/-1%,1/16W,G,SMD0402 | VISHAY ENTER TECHNO LOGY.INC | CRCW04028K87FKEDC |  |  | PWA BOM |
| 2 | 610113D00-017-G | 0 | 1 | RES,10.5KOhm,+/-1%,1/16W,G,SMD0402 | KOA SPEER ELECTRONICS, INC. | RK73H1ETTP1052F | G | (+)PHAR35 | PWA BOM |
| OOOOOOOOOOOOOOOOOOOOOOOOOOOOOOOOOOOOOOOOOOOOOOOOOOOOOOOOOOOOOOOOOOOOOOOOOOOOOOOOOOOOOOOOOO | OOOOOOOOOOOOOOOOOOOOOOOOOOOOOOOOOOOOOOOOOOOOOOOOOOOOOOOOOOOOOOOOOOOOOOOOOOOOOOOOOOOOOOOOOO | OOOOOOOOOOOOOOOOOOOOOOOOOOOOOOOOOOOOOOOOOOOOOOOOOOOOOOOOOOOOOOOOOOOOOOOOOOOOOOOOOOOOOOOOOO | OOOOOOOOOOOOOOOOOOOOOOOOOOOOOOOOOOOOOOOOOOOOOOOOOOOOOOOOOOOOOOOOOOOOOOOOOOOOOOOOOOOOOOOOOO | OOOOOOOOOOOOOOOOOOOOOOOOOOOOOOOOOOOOOOOOOOOOOOOOOOOOOOOOOOOOOOOOOOOOOOOOOOOOOOOOOOOOOOOOOO | OOOOOOOOOOOOOOOOOOOOOOOOOOOOOOOOOOOOOOOOOOOOOOOOOOOOOOOOOOOOOOOOOOOOOOOOOOOOOOOOOOOOOOOOOO | OOOOOOOOOOOOOOOOOOOOOOOOOOOOOOOOOOOOOOOOOOOOOOOOOOOOOOOOOOOOOOOOOOOOOOOOOOOOOOOOOOOOOOOOOO | OOOOOOOOOOOOOOOOOOOOOOOOOOOOOOOOOOOOOOOOOOOOOOOOOOOOOOOOOOOOOOOOOOOOOOOOOOOOOOOOOOOOOOOOOO | OOOOOOOOOOOOOOOOOOOOOOOOOOOOOOOOOOOOOOOOOOOOOOOOOOOOOOOOOOOOOOOOOOOOOOOOOOOOOOOOOOOOOOOOOO | OOOOOOOOOOOOOOOOOOOOOOOOOOOOOOOOOOOOOOOOOOOOOOOOOOOOOOOOOOOOOOOOOOOOOOOOOOOOOOOOOOOOOOOOOO |
| TLA Parts Change |  |  |  |  |  |  |  |  |  |
| Item | Foxconn P/N | Qty | Part Description | Manufacturer Full Name | Manufacturer P/N | RoHS | Location | Remark | BOM |
| BOM Change List Date:Mon Sep 04 10:26:16 CST 2017 |  |  |  |  |  |  |  |  |  |
| New BOM file : E:\barreleye g2\0904\foxbis\zaius 0901.xls |  |  |  |  |  |  |  |  |  |
| Old BOM file : E:\barreleye g2\0904\foxbis\zaius 0831.xls |  |  |  |  |  |  |  |  |  |
| ##### Add Parts |  |  |  |  |  |  |  |  |  |
| Item | Location | Qty | Foxconn P/N | Part Description | Manufacturer Full Name | Manufacturer P/N | RoHS | Sheet |  |
| ##### Remove Parts |  |  |  |  |  |  |  |  |  |
| Item | Location | Qty | Foxconn P/N | Part Description | Manufacturer Full Name | Manufacturer P/N | RoHS | Sheet |  |
| ##### Change Parts |  |  |  |  |  |  |  |  |  |
| Item | Location | Qty | Foxconn P/N | Part Description | Manufacturer Full Name | Manufacturer P/N | RoHS | Sheet | Remark |
| 1 | FL2,FL3,FL5,FL6,FL7,FL8,FL9 | 7 | 720400201-015-G | Filter,Common Mode,90Ohm@100MHz,+/-25%,330mA,G,SMD0805 | MURATA ELEC. NORTH AMERICA | DLW21HN900SQ2L | G | PWA BOM | In New BOM |
|  |  |  | 720400M00-059-G | Common Choke,90 Ohm@100MHz,+/-25%,400mA,G,SMD0805 | TAI-TECH ADVANCED ELECTRONICS CO., LTD. | WCM2012F2SF-900T04 | G | PWA BOM | In New BOM |
|  |  |  | 720400800-016-G | Common Choke,90 Ohm@100MHz,+/-25%,400mA,190mOhm,2L,G,SMD0805 | TDK ELECTRONICS EUROPE GMBH | ACM2012-900-2P-T | G | PWA BOM | In New BOM |
|  | FL2,FL3,FL5,FL6,FL7,FL8,FL9 | 7 | 720400201-015-G | Filter,Common Mode,90Ohm@100MHz,+/-25%,330mA,G,SMD0805 | MURATA ELEC. NORTH AMERICA | DLW21HN900SQ2L | G | PWA BOM | In Old BOM |
|  |  |  | 720400M00-059-G | Common Choke,90 Ohm@100MHz,+/-25%,400mA,G,SMD0805 | TAI-TECH ADVANCED ELECTRONICS CO., LTD. | WCM2012F2SF-900T04 | G | PWA BOM | In Old BOM |
|  |  |  | 720400800-016-G | Common Choke,90 Ohm@100MHz,+/-25%,400mA,190mOhm,2L,G,SMD0805 | TDK ELECTRONICS EUROPE GMBH | ACM2012-900-2P-T | G | PWA BOM | In Old BOM |
|  |  |  | 720400200-129-G | Common Choke,90 Ohm@100MHz,+/-25%,400mA,190mOhm,2L,G,SMD0805 | MAG.LAYERS, SCIENTIFIC-TECHNICS (KUNSHAN) CO., LTD. | MCI-2012-900 | G | PWA BOM | In Old BOM |
| 2 | PBNCE1,PANCE1,PBNCE2,PANCE2,PBECE3,PALCE3,PAFCE3,PAECE3,PBMCE4,PBFCE4,PBECE4,PBACE4,PAMCE4,PALCE4,PAFCE4,PAECE4,PAACE4,PBMCE5,PBFCE5,PBECE5,PBACE5,PAMCE5,PAFCE5,PAECE5,PAACE5,PBMCE6,PBFCE6,PBECE6,PBACE6,PAMCE6,PAFCE6,PAECE6,PAACE6,PBMCE7,PBLCE7,PBFCE7,PBACE7,PAMCE7,PAACE7,PBLCE8,PBACE8,PAACE8,PBACE9,PAACE9,PBACE10,PAACE10,PBACE11,PAACE11,PBACE12,PAACE12 | 50 | 62120ER01-024-G | ECAP,SPEA,470uF,+/-20%,2.5V,105C,G,SMD2816,ESR<=3mOhm | PANASONIC INDUSTRIAL CO.,LTD. | EEFGX0E471R | G | PWA BOM | In New BOM |
|  | PBNCE1,PANCE1,PBNCE2,PANCE2,PBECE3,PALCE3,PAFCE3,PAECE3,PBMCE4,PBFCE4,PBECE4,PBACE4,PAMCE4,PALCE4,PAFCE4,PAECE4,PAACE4,PBMCE5,PBFCE5,PBECE5,PBACE5,PAMCE5,PAFCE5,PAECE5,PAACE5,PBMCE6,PBFCE6,PBECE6,PBACE6,PAMCE6,PAFCE6,PAECE6,PAACE6,PBMCE7,PBLCE7,PBFCE7,PBACE7,PAMCE7,PAACE7,PBLCE8,PBACE8,PAACE8,PBACE9,PAACE9,PBACE10,PAACE10,PBACE11,PAACE11,PBACE12,PAACE12 | 50 | 62120ER01-024-G | ECAP,SPEA,470uF,+/-20%,2.5V,105C,G,SMD2816,ESR<=3mOhm | PANASONIC INDUSTRIAL CO.,LTD. | EEFGX0E471R | G | PWA BOM | In Old BOM |
|  |  |  | 62120ER00-025-G | ECAP,SPEA,Low ESR(LESR),470uF,+/-20%,2.5V,105,3mOhm,SMD2816,G | KEMET ELECTRONICS CORPORATION | A720V477M2R5APE003 | G | PWA BOM | In Old BOM |
| 3 | Q8,PHAQ8,PBMQ11,PBAQ11,PAMQ11,PAAQ11,PBFQ12,PBEQ12,PAFQ12,PAEQ12,Q85,Q86,Q87,Q88,Q89,Q90,Q91,Q92 | 18 | 510100W00-237-G | TRANS N,MMBT3904-7-F,40V,0.2A,G,SOT23-3,SMD | DIODES INEORPORATION | MMBT3904-7-F | G | PWA BOM | In New BOM |
|  |  |  | 510100500-031-G | TRANS N,PMBT3904,40V,0.2A,G,SOT23-3,SMD | NXP SEMICONDUCTORS | PMBT3904 | G | PWA BOM | In New BOM |
|  |  |  | 510101700-185-G | TRANS N,MMBT3904,40V,0.2A,G,SOT23-3,SMD | FAIRCHILD SEMICONDUCTOR CORP | MMBT3904 | G | PWA BOM | In New BOM |
|  | Q8,PHAQ8,PBMQ11,PBAQ11,PAMQ11,PAAQ11,PBFQ12,PBEQ12,PAFQ12,PAEQ12,Q85,Q86,Q87,Q88,Q89,Q90,Q91,Q92 | 18 | 510100W00-237-G | TRANS N,MMBT3904-7-F,40V,0.2A,G,SOT23-3,SMD | DIODES INEORPORATION | MMBT3904-7-F | G | PWA BOM | In Old BOM |
|  |  |  | 510100500-031-G | TRANS N,PMBT3904,40V,0.2A,G,SOT23-3,SMD | NXP SEMICONDUCTORS | PMBT3904 | G | PWA BOM | In Old BOM |
|  |  |  | 510101700-185-G | TRANS N,MMBT3904,40V,0.2A,G,SOT23-3,SMD | FAIRCHILD SEMICONDUCTOR CORP | MMBT3904 | G | PWA BOM | In Old BOM |
|  |  |  | 510100800-223-G | TRANS N,MMBT3904LT1G,40V,0.2A,G,SOT23-3,SMD | ON SEMICONDUCTOR CORP | MMBT3904LT1G | G | PWA BOM | In Old BOM |
| 4 | PCIE1,PCIE5 | 2 | 10061913-102HLF | CONN,PCIE-8X,V/T,Bla,1mm,30u,G,SMD-98 | FCI CONNECTORS HONGKONG LTD. | 10061913-102HLF | G | PWA BOM | In New BOM |
|  | PCIE1,PCIE5 | 2 | 10061913-102HLF | CONN,PCIE-8X,V/T,Bla,1mm,30u,G,SMD-98 | FCI CONNECTORS HONGKONG LTD. | 10061913-102HLF | G | PWA BOM | In Old BOM |
|  |  |  | 340320R00-278-G | CONN,PCIE-8X,V/T,Bla,1mm,30u,G,SMD-98 | TYCO ELECTRONICS CORPORATION | 2041366-4 | G | PWA BOM | In Old BOM |
| 5 | PHAR2 | 1 | 61100DA00-017-G | RES,33KOhm,+/-0.1%,1/16W,G,SMD0402 | KOA SPEER ELECTRONICS, INC. | RN731ETTP3302B25 | G | PWA BOM | In New BOM |
|  |  |  | 61100DA00-011-G | RES,33KOhm,+/-0.1%,1/16W,G,SMD0402 | YAGEO CORPORATION COMPONENT | RT0402BRD0733KL | G | PWA BOM | In New BOM |
|  | PHAR2 | 1 | 61100DA00-017-G | RES,33KOhm,+/-0.1%,1/16W,G,SMD0402 | KOA SPEER ELECTRONICS, INC. | RN731ETTP3302B25 | G | PWA BOM | In Old BOM |
|  |  |  | 61100DA00-011-G | RES,33KOhm,+/-0.1%,1/16W,G,SMD0402 | YAGEO CORPORATION COMPONENT | RT0402BRD0733KL | G | PWA BOM | In Old BOM |
|  |  |  | 611010100-029-G | RES,33KOhm,+/-0.1%,1/10W,G,SMD0402 | VISHAY ENTER TECHNO LOGY.INC | TNPW040233K0BEED | G | PWA BOM | In Old BOM |
| 6 | PSTR19 | 1 | 61100J401-017-G | RES,1.78KOhm,+/-0.1%,1/16W,G,SMD0402 | KOA SPEER ELECTRONICS, INC. | RN73H1ETTP1781B25 | G | PWA BOM | In New BOM |
|  |  |  | 61100J400-024-G | RES,1.78KOhm,+/-0.1%,1/16W,G,SMD0402 | PANASONIC INDUSTRIAL CO.,LTD. | ERA2AEB1781X | G | PWA BOM | In New BOM |
|  | PSTR19 | 1 | 61100J401-017-G | RES,1.78KOhm,+/-0.1%,1/16W,G,SMD0402 | KOA SPEER ELECTRONICS, INC. | RN73H1ETTP1781B25 | G | PWA BOM | In Old BOM |
|  |  |  | 61100J400-024-G | RES,1.78KOhm,+/-0.1%,1/16W,G,SMD0402 | PANASONIC INDUSTRIAL CO.,LTD. | ERA2AEB1781X | G | PWA BOM | In Old BOM |
|  |  |  | 61100J400-029-G | RES,1.78KOhm,+/-0.1%,1/16W,G,SMD0402 | VISHAY ENTER TECHNO LOGY.INC | MCS0402MD1781BE000 | G | PWA BOM | In Old BOM |
| 7 | QN2,QN3 | 2 | 510503B00-223-G | MOS N/N,NTZD3154NT1G,20V,0.54A,550m24.5V,G,SOT563-6,SMD | ON SEMICONDUCTOR CORP | NTZD3154NT1G | G | PWA BOM | In New BOM |
|  |  |  | 51050L500-029-G | MOS,N/N,Si1034CX-T1-GE3,20V,0.61A,G,SC-89-6,SMD | VISHAY ENTER TECHNO LOGY.INC | Si1034CX-T1-GE3 | G | PWA BOM | In New BOM |
|  | QN2,QN3 | 2 | 510503B00-223-G | MOS N/N,NTZD3154NT1G,20V,0.54A,550m24.5V,G,SOT563-6,SMD | ON SEMICONDUCTOR CORP | NTZD3154NT1G | G | PWA BOM | In Old BOM |
|  |  |  | 51050L500-029-G | MOS,N/N,Si1034CX-T1-GE3,20V,0.61A,G,SC-89-6,SMD | VISHAY ENTER TECHNO LOGY.INC | Si1034CX-T1-GE3 | G | PWA BOM | In Old BOM |
|  |  |  | 51050KW00-131-G | MOS N/N,SSM6N36FE,20V,500mA,0.63@5V,G,ES6-6,SMD | TOSHIBA ELECTRONICS ASIA LTD | SSM6N36FE | G | PWA BOM | In Old BOM |
| 8 | R751 | 1 | 61100H601-017-G | RES,2KOhm,+/-0.5%,1/16W,G,SMD0402 | KOA SPEER ELECTRONICS, INC. | RN731ETTP2001D25 | G | PWA BOM | In New BOM |
|  | R751 | 1 | 61100H601-017-G | RES,2KOhm,+/-0.5%,1/16W,G,SMD0402 | KOA SPEER ELECTRONICS, INC. | RN731ETTP2001D25 | G | PWA BOM | In Old BOM |
|  |  |  | 61100YQ00-029-G | RES,2KOhm,+/-0.5%,1/10W,SMD0402,G | VISHAY ENTER TECHNO LOGY.INC | TNPW04022K00DEED | G | PWA BOM | In Old BOM |
| 9 | R961,R962,R963,R964,R965,R967,R968,R969,R970,R975,R976,R977,R978,R985,R986,R988,R989,R992,R1003 | 19 | 61100C600-017-G | RES,1KOhm,+/-0.5%,1/16W,G,SMD0402 | KOA SPEER ELECTRONICS, INC. | RN731ETTP1001D25 | G | PWA BOM | In New BOM |
|  |  |  | 61100C603-024-G | RES,1KOhm,+/-0.5%,1/16W,G,SMD0402 | PANASONIC INDUSTRIAL CO.,LTD. | ERA2AED102X | G | PWA BOM | In New BOM |
|  | R961,R962,R963,R964,R965,R967,R968,R969,R970,R975,R976,R977,R978,R985,R986,R988,R989,R992,R1003 | 19 | 61100C600-017-G | RES,1KOhm,+/-0.5%,1/16W,G,SMD0402 | KOA SPEER ELECTRONICS, INC. | RN731ETTP1001D25 | G | PWA BOM | In Old BOM |
|  |  |  | 61100C603-024-G | RES,1KOhm,+/-0.5%,1/16W,G,SMD0402 | PANASONIC INDUSTRIAL CO.,LTD. | ERA2AED102X | G | PWA BOM | In Old BOM |
|  |  |  | 61100C600-029-G | RES,1KOhm,+/-0.5%,1/16W,G,SMD0402 | VISHAY ENTER TECHNO LOGY.INC | MCS04020D1001DE000 | G | PWA BOM | In Old BOM |
| 10 | U110 | 1 | 330103N00-426-G | IC,Optocoupler,PS2811-1-F3-A,G,SSOP-4,SMD | RENESAS TECHNOLOGY AMERICA INC | PS2811-1-F3-A | G | PWA BOM | In New BOM |
|  |  |  | 330102900-289-G | OPTO-IC,ISOL,LTV-217-G,SSOP,4P,G | LITE-ON TECHNOLOGY CORPORATION | LTV-217-G | G | PWA BOM | In New BOM |
|  | U110 | 1 | 330103N00-426-G | IC,Optocoupler,PS2811-1-F3-A,G,SSOP-4,SMD | RENESAS TECHNOLOGY AMERICA INC | PS2811-1-F3-A | G | PWA BOM | In Old BOM |
|  |  |  | 330102900-289-G | OPTO-IC,ISOL,LTV-217-G,SSOP,4P,G | LITE-ON TECHNOLOGY CORPORATION | LTV-217-G | G | PWA BOM | In Old BOM |
|  |  |  | 330103T00-029-G | IC,Optocoupler,VOS618A-3X001T,G,SSOP-4,SMD | VISHAY ENTER TECHNO LOGY.INC | VOS618A-3X001T | G | PWA BOM | In Old BOM |
| 11 | Y2 | 1 | 71020Q600-16G-G | OSC,50MHz,50ppm,3.3V,G,SMD | SiTime Corporation | SIT1602AC-23-33E-50.000000T | G | PWA BOM | In New BOM |
|  |  |  | 71012DA00-100-G | OSC,50MHz,+/-25ppm,15pF,G,SMD | TXC CORPORATION | 7X50000015 | G | PWA BOM | In New BOM |
|  |  |  | 710216Q00-098-G | OSC,50MHz,+/-50ppm,3.3V,15pF,G,SMD | HARMONY (HELE) | SSW050000I3CHE-ST7R2 | G | PWA BOM | In New BOM |
|  | Y2 | 1 | 71020Q600-16G-G | OSC,50MHz,50ppm,3.3V,G,SMD | SiTime Corporation | SIT1602AC-23-33E-50.000000T | G | PWA BOM | In Old BOM |
|  |  |  | 71012DA00-100-G | OSC,50MHz,+/-25ppm,15pF,G,SMD | TXC CORPORATION | 7X50000015 | G | PWA BOM | In Old BOM |
|  |  |  | 710216Q00-098-G | OSC,50MHz,+/-50ppm,3.3V,15pF,G,SMD | HARMONY (HELE) | SSW050000I3CHE-ST7R2 | G | PWA BOM | In Old BOM |
|  |  |  | 710216P00-873-G | OSC,50MHz,+/-50ppm,3.3V,15pF,G,SMD | KYOCERA ELCO CORPORATION | KC3225K50.0000C1GE00 | G | PWA BOM | In Old BOM |
| 12 | J19,J20,J21,J22 | 4 | 340604M00-600-G | CONN,Header,Friction,1X3,V/T,Ivo,2.54mm,G,DIP-3 | FOXCONN TECHNOLOGY CO.,LTD. | HF2803E-P1 | G | PWA BOM | In New BOM |
|  |  |  | 3406AYL00-GRT-G | CONN,Header,WTB,1X3,V/T,Whi,2.54mm,G/F,G,DIP-3 | PINREX TECHNOLOGY CORP. | 744-81-03GW10 | G | PWA BOM | In New BOM |
|  |  |  | 3406AYF00-637-G | CONN,Header,WTB,1X3,V/T,Whi,2.54mm,G,DIP-3 | LONG SHOUNG CO.,LTD. | 2111110300-0212 | G | PWA BOM | In New BOM |
|  | J19,J20,J21,J22 | 4 | 340604M00-600-G | CONN,Header,Friction,1X3,V/T,Ivo,2.54mm,G,DIP-3 | FOXCONN TECHNOLOGY CO.,LTD. | HF2803E-P1 | G | PWA BOM | In Old BOM |
|  |  |  | 3406AYL00-GRT-G | CONN,Header,WTB,1X3,V/T,Whi,2.54mm,G/F,G,DIP-3 | PINREX TECHNOLOGY CORP. | 744-81-03GW10 | G | PWA BOM | In Old BOM |
|  |  |  | 3406AYF00-637-G | CONN,Header,WTB,1X3,V/T,Whi,2.54mm,G,DIP-3 | LONG SHOUNG CO.,LTD. | 2111110300-0212 | G | PWA BOM | In Old BOM |
|  |  |  | 34060G600-317-G | Header&Socket Connector,22-23-2031,Wire-to-Board Header,3,DIP,NYLON,2.54mm,200u",White,G | MOLEX INCORPORATED | 22-23-2031 | G | PWA BOM | In Old BOM |
| 13 | J27 | 1 | 3406AMV00-317-G | CONN,Header,MINFIT,2X4,V/T,Bla,10mm,30u,G,DIP-8 | MOLEX INCORPORATED | 42819-4233 | G | PWA BOM | In New BOM |
|  | J27 | 1 | 3406AMV00-317-G | CONN,Header,MINFIT,2X4,V/T,Bla,10mm,30u,G,DIP-8 | MOLEX INCORPORATED | 42819-4233 | G | PWA BOM | In Old BOM |
|  |  |  | 3406AYH00-971-G | Header&Socket Connector,C23709-10433-Y,Power Connector,4,DIP,LCP,10mm,30u",Black,G | ALLTOP TECHNOLOGY CO.,LTD | C23709-10433-Y | G | PWA BOM | In Old BOM |
| 14 | PBMJ1,PBEJ1,PBAJ1,PAMJ1,PAEJ1,PAAJ1 | 6 | 340634U00-600-G | CONN,Pin Header,2X3,V/T,Bla,2.54mm,30u,G,SMD-6 | FOXCONN TECHNOLOGY CO.,LTD. | HS1103H-RN | G | PWA BOM | In New BOM |
|  |  |  | 34065EA00-317-G | CONN,Header,Pin Header,2X3,V/T,Bla,2.54mm,30u,G,SMD-6 | MOLEX INCORPORATED | 015-91-3060 | G | PWA BOM | In New BOM |
|  |  |  | 3406AY700-637-G | Header&Socket Connector,11006A5807,Pin Header,6,SMD,NY6T,2.54mm,30u",Black,G | LONG SHOUNG CO.,LTD. | 11006A5807 | G | PWA BOM | In New BOM |
|  | PBMJ1,PBEJ1,PBAJ1,PAMJ1,PAEJ1,PAAJ1 | 6 | 340634U00-600-G | CONN,Pin Header,2X3,V/T,Bla,2.54mm,30u,G,SMD-6 | FOXCONN TECHNOLOGY CO.,LTD. | HS1103H-RN | G | PWA BOM | In Old BOM |
|  |  |  | 34065EA00-317-G | CONN,Header,Pin Header,2X3,V/T,Bla,2.54mm,30u,G,SMD-6 | MOLEX INCORPORATED | 015-91-3060 | G | PWA BOM | In Old BOM |
|  |  |  | 3406AY700-637-G | Header&Socket Connector,11006A5807,Pin Header,6,SMD,NY6T,2.54mm,30u",Black,G | LONG SHOUNG CO.,LTD. | 11006A5807 | G | PWA BOM | In Old BOM |
|  |  |  | 34068GJ00-GRT-G | CONN,Header,Pin Header,2X3,V/T,Bla,2.54mm,30u,SMD-6 | PINREX TECHNOLOGY CORP. | 212-92-03SBEL | G | PWA BOM | In Old BOM |
| ##### Change Revision |  |  |  |  |  |  |  |  |  |
| Sheet | REV OF BOM | CUSTOMER | CUSTOMER P/N | PWA PN | PWA DESCRIPTION | PWA REV | DATE | Remark |  |
| OOOOOOOOOOOOOOOOOOOOOOOOOOOOOOOOOOOOOOOOOOOOOOOOOOOOOOOOOOOOOOOOOOOOOOOOOOOOOOOOOOOOOOOOOO | OOOOOOOOOOOOOOOOOOOOOOOOOOOOOOOOOOOOOOOOOOOOOOOOOOOOOOOOOOOOOOOOOOOOOOOOOOOOOOOOOOOOOOOOOO | OOOOOOOOOOOOOOOOOOOOOOOOOOOOOOOOOOOOOOOOOOOOOOOOOOOOOOOOOOOOOOOOOOOOOOOOOOOOOOOOOOOOOOOOOO | OOOOOOOOOOOOOOOOOOOOOOOOOOOOOOOOOOOOOOOOOOOOOOOOOOOOOOOOOOOOOOOOOOOOOOOOOOOOOOOOOOOOOOOOOO | OOOOOOOOOOOOOOOOOOOOOOOOOOOOOOOOOOOOOOOOOOOOOOOOOOOOOOOOOOOOOOOOOOOOOOOOOOOOOOOOOOOOOOOOOO | OOOOOOOOOOOOOOOOOOOOOOOOOOOOOOOOOOOOOOOOOOOOOOOOOOOOOOOOOOOOOOOOOOOOOOOOOOOOOOOOOOOOOOOOOO | OOOOOOOOOOOOOOOOOOOOOOOOOOOOOOOOOOOOOOOOOOOOOOOOOOOOOOOOOOOOOOOOOOOOOOOOOOOOOOOOOOOOOOOOOO | OOOOOOOOOOOOOOOOOOOOOOOOOOOOOOOOOOOOOOOOOOOOOOOOOOOOOOOOOOOOOOOOOOOOOOOOOOOOOOOOOOOOOOOOOO | OOOOOOOOOOOOOOOOOOOOOOOOOOOOOOOOOOOOOOOOOOOOOOOOOOOOOOOOOOOOOOOOOOOOOOOOOOOOOOOOOOOOOOOOOO | OOOOOOOOOOOOOOOOOOOOOOOOOOOOOOOOOOOOOOOOOOOOOOOOOOOOOOOOOOOOOOOOOOOOOOOOOOOOOOOOOOOOOOOOOO |
| Second Source Change |  |  |  |  |  |  |  |  |  |
| Item | Location | Change Type | Foxconn P/N | Part Description | Manufacturer Full Name | Manufacturer P/N | RoHS | Sheet |  |
| 1 | FL2,FL3,FL5,FL6,FL7,FL8,FL9 |  | 720400201-015-G | Filter,Common Mode,90Ohm@100MHz,+/-25%,330mA,G,SMD0805 | MURATA ELEC. NORTH AMERICA | DLW21HN900SQ2L | G | PWA BOM |  |
|  |  | NO | 720400M00-059-G | Common Choke,90 Ohm@100MHz,+/-25%,400mA,G,SMD0805 | TAI-TECH ADVANCED ELECTRONICS CO., LTD. | WCM2012F2SF-900T04 | G | PWA BOM |  |
|  |  | NO | 720400800-016-G | Common Choke,90 Ohm@100MHz,+/-25%,400mA,190mOhm,2L,G,SMD0805 | TDK ELECTRONICS EUROPE GMBH | ACM2012-900-2P-T | G | PWA BOM |  |
|  |  | Delete | 720400200-129-G | Common Choke,90 Ohm@100MHz,+/-25%,400mA,190mOhm,2L,G,SMD0805 | MAG.LAYERS, SCIENTIFIC-TECHNICS (KUNSHAN) CO., LTD. | MCI-2012-900 | G | PWA BOM |  |
| 2 | PBNCE1,PANCE1,PBNCE2,PANCE2,PBECE3,PALCE3,PAFCE3,PAECE3,PBMCE4,PBFCE4,PBECE4,PBACE4,PAMCE4,PALCE4,PAFCE4,PAECE4,PAACE4,PBMCE5,PBFCE5,PBECE5,PBACE5,PAMCE5,PAFCE5,PAECE5,PAACE5,PBMCE6,PBFCE6,PBECE6,PBACE6,PAMCE6,PAFCE6,PAECE6,PAACE6,PBMCE7,PBLCE7,PBFCE7,PBACE7,PAMCE7,PAACE7,PBLCE8,PBACE8,PAACE8,PBACE9,PAACE9,PBACE10,PAACE10,PBACE11,PAACE11,PBACE12,PAACE12 |  | 62120ER01-024-G | ECAP,SPEA,470uF,+/-20%,2.5V,105C,G,SMD2816,ESR<=3mOhm | PANASONIC INDUSTRIAL CO.,LTD. | EEFGX0E471R | G | PWA BOM |  |
|  |  | Delete | 62120ER00-025-G | ECAP,SPEA,Low ESR(LESR),470uF,+/-20%,2.5V,105,3mOhm,SMD2816,G | KEMET ELECTRONICS CORPORATION | A720V477M2R5APE003 | G | PWA BOM |  |
| 3 | Q8,PHAQ8,PBMQ11,PBAQ11,PAMQ11,PAAQ11,PBFQ12,PBEQ12,PAFQ12,PAEQ12,Q85,Q86,Q87,Q88,Q89,Q90,Q91,Q92 |  | 510100W00-237-G | TRANS N,MMBT3904-7-F,40V,0.2A,G,SOT23-3,SMD | DIODES INEORPORATION | MMBT3904-7-F | G | PWA BOM |  |
|  |  | NO | 510100500-031-G | TRANS N,PMBT3904,40V,0.2A,G,SOT23-3,SMD | NXP SEMICONDUCTORS | PMBT3904 | G | PWA BOM |  |
|  |  | NO | 510101700-185-G | TRANS N,MMBT3904,40V,0.2A,G,SOT23-3,SMD | FAIRCHILD SEMICONDUCTOR CORP | MMBT3904 | G | PWA BOM |  |
|  |  | Delete | 510100800-223-G | TRANS N,MMBT3904LT1G,40V,0.2A,G,SOT23-3,SMD | ON SEMICONDUCTOR CORP | MMBT3904LT1G | G | PWA BOM |  |
| 4 | PCIE1,PCIE5 |  | 10061913-102HLF | CONN,PCIE-8X,V/T,Bla,1mm,30u,G,SMD-98 | FCI CONNECTORS HONGKONG LTD. | 10061913-102HLF | G | PWA BOM |  |
|  |  | Delete | 340320R00-278-G | CONN,PCIE-8X,V/T,Bla,1mm,30u,G,SMD-98 | TYCO ELECTRONICS CORPORATION | 2041366-4 | G | PWA BOM |  |
| 5 | PHAR2 |  | 61100DA00-017-G | RES,33KOhm,+/-0.1%,1/16W,G,SMD0402 | KOA SPEER ELECTRONICS, INC. | RN731ETTP3302B25 | G | PWA BOM |  |
|  |  | NO | 61100DA00-011-G | RES,33KOhm,+/-0.1%,1/16W,G,SMD0402 | YAGEO CORPORATION COMPONENT | RT0402BRD0733KL | G | PWA BOM |  |
|  |  | Delete | 611010100-029-G | RES,33KOhm,+/-0.1%,1/10W,G,SMD0402 | VISHAY ENTER TECHNO LOGY.INC | TNPW040233K0BEED | G | PWA BOM |  |
| 6 | PSTR19 |  | 61100J401-017-G | RES,1.78KOhm,+/-0.1%,1/16W,G,SMD0402 | KOA SPEER ELECTRONICS, INC. | RN73H1ETTP1781B25 | G | PWA BOM |  |
|  |  | NO | 61100J400-024-G | RES,1.78KOhm,+/-0.1%,1/16W,G,SMD0402 | PANASONIC INDUSTRIAL CO.,LTD. | ERA2AEB1781X | G | PWA BOM |  |
|  |  | Delete | 61100J400-029-G | RES,1.78KOhm,+/-0.1%,1/16W,G,SMD0402 | VISHAY ENTER TECHNO LOGY.INC | MCS0402MD1781BE000 | G | PWA BOM |  |
| 7 | QN2,QN3 |  | 510503B00-223-G | MOS N/N,NTZD3154NT1G,20V,0.54A,550m24.5V,G,SOT563-6,SMD | ON SEMICONDUCTOR CORP | NTZD3154NT1G | G | PWA BOM |  |
|  |  | NO | 51050L500-029-G | MOS,N/N,Si1034CX-T1-GE3,20V,0.61A,G,SC-89-6,SMD | VISHAY ENTER TECHNO LOGY.INC | Si1034CX-T1-GE3 | G | PWA BOM |  |
|  |  | Delete | 51050KW00-131-G | MOS N/N,SSM6N36FE,20V,500mA,0.63@5V,G,ES6-6,SMD | TOSHIBA ELECTRONICS ASIA LTD | SSM6N36FE | G | PWA BOM |  |
| 8 | R751 |  | 61100H601-017-G | RES,2KOhm,+/-0.5%,1/16W,G,SMD0402 | KOA SPEER ELECTRONICS, INC. | RN731ETTP2001D25 | G | PWA BOM |  |
|  |  | Delete | 61100YQ00-029-G | RES,2KOhm,+/-0.5%,1/10W,SMD0402,G | VISHAY ENTER TECHNO LOGY.INC | TNPW04022K00DEED | G | PWA BOM |  |
| 9 | R961,R962,R963,R964,R965,R967,R968,R969,R970,R975,R976,R977,R978,R985,R986,R988,R989,R992,R1003 |  | 61100C600-017-G | RES,1KOhm,+/-0.5%,1/16W,G,SMD0402 | KOA SPEER ELECTRONICS, INC. | RN731ETTP1001D25 | G | PWA BOM |  |
|  |  | NO | 61100C603-024-G | RES,1KOhm,+/-0.5%,1/16W,G,SMD0402 | PANASONIC INDUSTRIAL CO.,LTD. | ERA2AED102X | G | PWA BOM |  |
|  |  | Delete | 61100C600-029-G | RES,1KOhm,+/-0.5%,1/16W,G,SMD0402 | VISHAY ENTER TECHNO LOGY.INC | MCS04020D1001DE000 | G | PWA BOM |  |
| 10 | U110 |  | 330103N00-426-G | IC,Optocoupler,PS2811-1-F3-A,G,SSOP-4,SMD | RENESAS TECHNOLOGY AMERICA INC | PS2811-1-F3-A | G | PWA BOM |  |
|  |  | NO | 330102900-289-G | OPTO-IC,ISOL,LTV-217-G,SSOP,4P,G | LITE-ON TECHNOLOGY CORPORATION | LTV-217-G | G | PWA BOM |  |
|  |  | Delete | 330103T00-029-G | IC,Optocoupler,VOS618A-3X001T,G,SSOP-4,SMD | VISHAY ENTER TECHNO LOGY.INC | VOS618A-3X001T | G | PWA BOM |  |
| 11 | Y2 |  | 71020Q600-16G-G | OSC,50MHz,50ppm,3.3V,G,SMD | SiTime Corporation | SIT1602AC-23-33E-50.000000T | G | PWA BOM |  |
|  |  | NO | 71012DA00-100-G | OSC,50MHz,+/-25ppm,15pF,G,SMD | TXC CORPORATION | 7X50000015 | G | PWA BOM |  |
|  |  | NO | 710216Q00-098-G | OSC,50MHz,+/-50ppm,3.3V,15pF,G,SMD | HARMONY (HELE) | SSW050000I3CHE-ST7R2 | G | PWA BOM |  |
|  |  | Delete | 710216P00-873-G | OSC,50MHz,+/-50ppm,3.3V,15pF,G,SMD | KYOCERA ELCO CORPORATION | KC3225K50.0000C1GE00 | G | PWA BOM |  |
| 12 | J19,J20,J21,J22 |  | 340604M00-600-G | CONN,Header,Friction,1X3,V/T,Ivo,2.54mm,G,DIP-3 | FOXCONN TECHNOLOGY CO.,LTD. | HF2803E-P1 | G | PWA BOM |  |
|  |  | NO | 3406AYL00-GRT-G | CONN,Header,WTB,1X3,V/T,Whi,2.54mm,G/F,G,DIP-3 | PINREX TECHNOLOGY CORP. | 744-81-03GW10 | G | PWA BOM |  |
|  |  | NO | 3406AYF00-637-G | CONN,Header,WTB,1X3,V/T,Whi,2.54mm,G,DIP-3 | LONG SHOUNG CO.,LTD. | 2111110300-0212 | G | PWA BOM |  |
|  |  | Delete | 34060G600-317-G | Header&Socket Connector,22-23-2031,Wire-to-Board Header,3,DIP,NYLON,2.54mm,200u",White,G | MOLEX INCORPORATED | 22-23-2031 | G | PWA BOM |  |
| 13 | J27 |  | 3406AMV00-317-G | CONN,Header,MINFIT,2X4,V/T,Bla,10mm,30u,G,DIP-8 | MOLEX INCORPORATED | 42819-4233 | G | PWA BOM |  |
|  |  | Delete | 3406AYH00-971-G | Header&Socket Connector,C23709-10433-Y,Power Connector,4,DIP,LCP,10mm,30u",Black,G | ALLTOP TECHNOLOGY CO.,LTD | C23709-10433-Y | G | PWA BOM |  |
| 14 | PBMJ1,PBEJ1,PBAJ1,PAMJ1,PAEJ1,PAAJ1 |  | 340634U00-600-G | CONN,Pin Header,2X3,V/T,Bla,2.54mm,30u,G,SMD-6 | FOXCONN TECHNOLOGY CO.,LTD. | HS1103H-RN | G | PWA BOM |  |
|  |  | NO | 34065EA00-317-G | CONN,Header,Pin Header,2X3,V/T,Bla,2.54mm,30u,G,SMD-6 | MOLEX INCORPORATED | 015-91-3060 | G | PWA BOM |  |
|  |  | NO | 3406AY700-637-G | Header&Socket Connector,11006A5807,Pin Header,6,SMD,NY6T,2.54mm,30u",Black,G | LONG SHOUNG CO.,LTD. | 11006A5807 | G | PWA BOM |  |
|  |  | Delete | 34068GJ00-GRT-G | CONN,Header,Pin Header,2X3,V/T,Bla,2.54mm,30u,SMD-6 | PINREX TECHNOLOGY CORP. | 212-92-03SBEL | G | PWA BOM |  |
| OOOOOOOOOOOOOOOOOOOOOOOOOOOOOOOOOOOOOOOOOOOOOOOOOOOOOOOOOOOOOOOOOOOOOOOOOOOOOOOOOOOOOOOOOO | OOOOOOOOOOOOOOOOOOOOOOOOOOOOOOOOOOOOOOOOOOOOOOOOOOOOOOOOOOOOOOOOOOOOOOOOOOOOOOOOOOOOOOOOOO | OOOOOOOOOOOOOOOOOOOOOOOOOOOOOOOOOOOOOOOOOOOOOOOOOOOOOOOOOOOOOOOOOOOOOOOOOOOOOOOOOOOOOOOOOO | OOOOOOOOOOOOOOOOOOOOOOOOOOOOOOOOOOOOOOOOOOOOOOOOOOOOOOOOOOOOOOOOOOOOOOOOOOOOOOOOOOOOOOOOOO | OOOOOOOOOOOOOOOOOOOOOOOOOOOOOOOOOOOOOOOOOOOOOOOOOOOOOOOOOOOOOOOOOOOOOOOOOOOOOOOOOOOOOOOOOO | OOOOOOOOOOOOOOOOOOOOOOOOOOOOOOOOOOOOOOOOOOOOOOOOOOOOOOOOOOOOOOOOOOOOOOOOOOOOOOOOOOOOOOOOOO | OOOOOOOOOOOOOOOOOOOOOOOOOOOOOOOOOOOOOOOOOOOOOOOOOOOOOOOOOOOOOOOOOOOOOOOOOOOOOOOOOOOOOOOOOO | OOOOOOOOOOOOOOOOOOOOOOOOOOOOOOOOOOOOOOOOOOOOOOOOOOOOOOOOOOOOOOOOOOOOOOOOOOOOOOOOOOOOOOOOOO | OOOOOOOOOOOOOOOOOOOOOOOOOOOOOOOOOOOOOOOOOOOOOOOOOOOOOOOOOOOOOOOOOOOOOOOOOOOOOOOOOOOOOOOOOO | OOOOOOOOOOOOOOOOOOOOOOOOOOOOOOOOOOOOOOOOOOOOOOOOOOOOOOOOOOOOOOOOOOOOOOOOOOOOOOOOOOOOOOOOOO |
| Master Materials Change |  |  |  |  |  |  |  |  |  |
| Item | Foxconn P/N | Orig._Usage | New_Usage | Part Description | Manufacturer Full Name | Manufacturer P/N | RoHS | Location | Sheet |
| OOOOOOOOOOOOOOOOOOOOOOOOOOOOOOOOOOOOOOOOOOOOOOOOOOOOOOOOOOOOOOOOOOOOOOOOOOOOOOOOOOOOOOOOOO | OOOOOOOOOOOOOOOOOOOOOOOOOOOOOOOOOOOOOOOOOOOOOOOOOOOOOOOOOOOOOOOOOOOOOOOOOOOOOOOOOOOOOOOOOO | OOOOOOOOOOOOOOOOOOOOOOOOOOOOOOOOOOOOOOOOOOOOOOOOOOOOOOOOOOOOOOOOOOOOOOOOOOOOOOOOOOOOOOOOOO | OOOOOOOOOOOOOOOOOOOOOOOOOOOOOOOOOOOOOOOOOOOOOOOOOOOOOOOOOOOOOOOOOOOOOOOOOOOOOOOOOOOOOOOOOO | OOOOOOOOOOOOOOOOOOOOOOOOOOOOOOOOOOOOOOOOOOOOOOOOOOOOOOOOOOOOOOOOOOOOOOOOOOOOOOOOOOOOOOOOOO | OOOOOOOOOOOOOOOOOOOOOOOOOOOOOOOOOOOOOOOOOOOOOOOOOOOOOOOOOOOOOOOOOOOOOOOOOOOOOOOOOOOOOOOOOO | OOOOOOOOOOOOOOOOOOOOOOOOOOOOOOOOOOOOOOOOOOOOOOOOOOOOOOOOOOOOOOOOOOOOOOOOOOOOOOOOOOOOOOOOOO | OOOOOOOOOOOOOOOOOOOOOOOOOOOOOOOOOOOOOOOOOOOOOOOOOOOOOOOOOOOOOOOOOOOOOOOOOOOOOOOOOOOOOOOOOO | OOOOOOOOOOOOOOOOOOOOOOOOOOOOOOOOOOOOOOOOOOOOOOOOOOOOOOOOOOOOOOOOOOOOOOOOOOOOOOOOOOOOOOOOOO | OOOOOOOOOOOOOOOOOOOOOOOOOOOOOOOOOOOOOOOOOOOOOOOOOOOOOOOOOOOOOOOOOOOOOOOOOOOOOOOOOOOOOOOOOO |
| TLA Parts Change |  |  |  |  |  |  |  |  |  |
| Item | Foxconn P/N | Qty | Part Description | Manufacturer Full Name | Manufacturer P/N | RoHS | Location | Remark | BOM |
| BOM Change List Date:Thu Sep 07 16:10:21 CST 2017 |  |  |  |  |  |  |  |  |  |
| New BOM file : E:\barreleye g2\0905\ZAIUS FOXBIS\ZAIUS 0907.xls |  |  |  |  |  |  |  |  |  |
| Old BOM file : E:\barreleye g2\0905\ZAIUS FOXBIS\ZAIUS 0901.xls |  |  |  |  |  |  |  |  |  |
| ##### Add Parts |  |  |  |  |  |  |  |  |  |
| Item | Location | Qty | Foxconn P/N | Part Description | Manufacturer Full Name | Manufacturer P/N | RoHS | Sheet |  |
| ##### Remove Parts |  |  |  |  |  |  |  |  |  |
| Item | Location | Qty | Foxconn P/N | Part Description | Manufacturer Full Name | Manufacturer P/N | RoHS | Sheet |  |
| ##### Change Parts |  |  |  |  |  |  |  |  |  |
| Item | Location | Qty | Foxconn P/N | Part Description | Manufacturer Full Name | Manufacturer P/N | RoHS | Sheet | Remark |
| 1 | PCB | 1 | 0101FBQ00-000-G | PCB,Zaius-MB PVT-X04,OSP,Gre,22L,22.20*13.00,G | GOLD CIRCUIT ELECTRONICS LTD. | 0101FBQ00-000-G | G | PWA BOM | In New BOM |
|  | PCB | 1 | 0101FBQ00-000-G | PCB,Zaius-MB PVT-X04,OSP,Gre,22L,22.20*13.00,G | GOLD CIRCUIT ELECTRONICS LTD. | 0101FBQ00-000-G | G | PWA BOM | In Old BOM |
|  |  |  | 0101FBQ00-000-G | PCB,Zaius-MB PVT-X04,OSP,Gre,22L,22.20*13.00,G | ISUPETASYS CO., LTD | 0101FBQ00-000-G | G | PWA BOM | In Old BOM |
| 2 | PBMU1,PBFU1,PBEU1,PBAU1,PAMU1,PAFU1,PAEU1,PAAU1 | 8 | ISL68137IRAZ-GG04 | IC,PWM Controller,ISL68137IRAZ-T,G,QFN-48,SMD | INTERSIL CORPORATION | ISL68137IRAZ-GG04 | G | PWA BOM | In New BOM |
|  | PBMU1,PBFU1,PBEU1,PBAU1,PAMU1,PAFU1,PAEU1,PAAU1 | 8 | 320242200-230-G | IC,PWM Controller,ISL68137IRAZ-T,G,QFN-48,SMD | INTERSIL CORPORATION | ISL68137IRAZ-T | G | PWA BOM | In Old BOM |
| 3 | U5 | 1 | UCD90160RGCR-C11 | IC,Power Controller,UCD90160RGCR,G,VQFN-64,SMD | TEXAS INSTRUMENTS | UCD90160RGCR-C11 | G | PWA BOM | In New BOM |
|  | U5 | 1 | 320241C00-183-G | IC,Power Controller,UCD90160RGCR,G,VQFN-64,SMD | TEXAS INSTRUMENTS | UCD90160RGCR | G | PWA BOM | In Old BOM |
| 4 | J_BMC_DEBUG1,J1,J4,J5,J36,J41,J43,J48,J147,J149 | 10 | 87898-0318 | CONN,Header,Pin Header,1X3,V/T,2.54mm,30u,G,SMD-3 | MOLEX INCORPORATED | 87898-0318 | G | PWA BOM | In New BOM |
|  |  |  | 34068LN00-317-G | CONN,Header,Pin Header,1X3,V/T,2.54mm,30u,G,SMD-3 | MOLEX INCORPORATED | 87898-0315 | G | PWA BOM | In New BOM |
|  |  |  | 34068HT00-245-G | CONN,Header,Pin Header,1X3,V/T,Bla,2.54mm,30u,SMD-3 | AMPHENOL SHANGHAI CORP. | G800MU305010EU | G | PWA BOM | In New BOM |
|  |  |  | 34068GU00-309-G | CONN,Header,Pin Header,1X3,V/T,Bla,2.54mm,30u,SMD-3 | SAMTEC INC. | TSM-103-01-S-SV-P-TR | G | PWA BOM | In New BOM |
|  | J_BMC_DEBUG1,J1,J4,J5,J36,J41,J43,J48,J147,J149 | 10 | 34068LN00-317-G | CONN,Header,Pin Header,1X3,V/T,2.54mm,30u,G,SMD-3 | MOLEX INCORPORATED | 87898-0315 | G | PWA BOM | In Old BOM |
|  |  |  | 34068HT00-245-G | CONN,Header,Pin Header,1X3,V/T,Bla,2.54mm,30u,SMD-3 | AMPHENOL SHANGHAI CORP. | G800MU305010EU | G | PWA BOM | In Old BOM |
|  |  |  | 34068GU00-309-G | CONN,Header,Pin Header,1X3,V/T,Bla,2.54mm,30u,SMD-3 | SAMTEC INC. | TSM-103-01-S-SV-P-TR | G | PWA BOM | In Old BOM |
| 5 | J148 | 1 | 87898-0458 | CONN,Pin Header,1X4,V/T,Bla,2.54mm,30u,G,SMD-4 | MOLEX INCORPORATED | 87898-0458 | G | PWA BOM | In New BOM |
|  |  |  | 340672300-317-G | CONN,Pin Header,1X4,V/T,Bla,2.54mm,30u,G,SMD-4 | MOLEX INCORPORATED | 87898-0455 | G | PWA BOM | In New BOM |
|  |  |  | 340692T00-245-G | CONN,Header,Pin Header,1X4,V/T,Bla,2.54mm,30u,G,SMD-4 | AMPHENOL SHANGHAI CORP. | G800MR304010HR | G | PWA BOM | In New BOM |
|  |  |  | 34068VT00-GRT-G | CONN,Header,Pin Header,1X4,V/T,Bla,2.54mm,30u,G,SMD-4 | PINREX TECHNOLOGY CORP. | 212-91-04SBEJ | G | PWA BOM | In New BOM |
|  | J148 | 1 | 340672300-317-G | CONN,Pin Header,1X4,V/T,Bla,2.54mm,30u,G,SMD-4 | MOLEX INCORPORATED | 87898-0455 | G | PWA BOM | In Old BOM |
|  |  |  | 340692T00-245-G | CONN,Header,Pin Header,1X4,V/T,Bla,2.54mm,30u,G,SMD-4 | AMPHENOL SHANGHAI CORP. | G800MR304010HR | G | PWA BOM | In Old BOM |
|  |  |  | 34068VT00-GRT-G | CONN,Header,Pin Header,1X4,V/T,Bla,2.54mm,30u,G,SMD-4 | PINREX TECHNOLOGY CORP. | 212-91-04SBEJ | G | PWA BOM | In Old BOM |
| ##### Change Revision |  |  |  |  |  |  |  |  |  |
| Sheet | REV OF BOM | CUSTOMER | CUSTOMER P/N | PWA PN | PWA DESCRIPTION | PWA REV | DATE | Remark |  |
| OOOOOOOOOOOOOOOOOOOOOOOOOOOOOOOOOOOOOOOOOOOOOOOOOOOOOOOOOOOOOOOOOOOOOOOOOOOOOOOOOOOOOOOOOO | OOOOOOOOOOOOOOOOOOOOOOOOOOOOOOOOOOOOOOOOOOOOOOOOOOOOOOOOOOOOOOOOOOOOOOOOOOOOOOOOOOOOOOOOOO | OOOOOOOOOOOOOOOOOOOOOOOOOOOOOOOOOOOOOOOOOOOOOOOOOOOOOOOOOOOOOOOOOOOOOOOOOOOOOOOOOOOOOOOOOO | OOOOOOOOOOOOOOOOOOOOOOOOOOOOOOOOOOOOOOOOOOOOOOOOOOOOOOOOOOOOOOOOOOOOOOOOOOOOOOOOOOOOOOOOOO | OOOOOOOOOOOOOOOOOOOOOOOOOOOOOOOOOOOOOOOOOOOOOOOOOOOOOOOOOOOOOOOOOOOOOOOOOOOOOOOOOOOOOOOOOO | OOOOOOOOOOOOOOOOOOOOOOOOOOOOOOOOOOOOOOOOOOOOOOOOOOOOOOOOOOOOOOOOOOOOOOOOOOOOOOOOOOOOOOOOOO | OOOOOOOOOOOOOOOOOOOOOOOOOOOOOOOOOOOOOOOOOOOOOOOOOOOOOOOOOOOOOOOOOOOOOOOOOOOOOOOOOOOOOOOOOO | OOOOOOOOOOOOOOOOOOOOOOOOOOOOOOOOOOOOOOOOOOOOOOOOOOOOOOOOOOOOOOOOOOOOOOOOOOOOOOOOOOOOOOOOOO | OOOOOOOOOOOOOOOOOOOOOOOOOOOOOOOOOOOOOOOOOOOOOOOOOOOOOOOOOOOOOOOOOOOOOOOOOOOOOOOOOOOOOOOOOO | OOOOOOOOOOOOOOOOOOOOOOOOOOOOOOOOOOOOOOOOOOOOOOOOOOOOOOOOOOOOOOOOOOOOOOOOOOOOOOOOOOOOOOOOOO |
| Second Source Change |  |  |  |  |  |  |  |  |  |
| Item | Location | Change Type | Foxconn P/N | Part Description | Manufacturer Full Name | Manufacturer P/N | RoHS | Sheet |  |
| 1 | PCB |  | 0101FBQ00-000-G | PCB,Zaius-MB PVT-X04,OSP,Gre,22L,22.20*13.00,G | GOLD CIRCUIT ELECTRONICS LTD. | 0101FBQ00-000-G | G | PWA BOM |  |
|  |  | Delete | 0101FBQ00-000-G | PCB,Zaius-MB PVT-X04,OSP,Gre,22L,22.20*13.00,G | ISUPETASYS CO., LTD | 0101FBQ00-000-G | G | PWA BOM |  |
| OOOOOOOOOOOOOOOOOOOOOOOOOOOOOOOOOOOOOOOOOOOOOOOOOOOOOOOOOOOOOOOOOOOOOOOOOOOOOOOOOOOOOOOOOO | OOOOOOOOOOOOOOOOOOOOOOOOOOOOOOOOOOOOOOOOOOOOOOOOOOOOOOOOOOOOOOOOOOOOOOOOOOOOOOOOOOOOOOOOOO | OOOOOOOOOOOOOOOOOOOOOOOOOOOOOOOOOOOOOOOOOOOOOOOOOOOOOOOOOOOOOOOOOOOOOOOOOOOOOOOOOOOOOOOOOO | OOOOOOOOOOOOOOOOOOOOOOOOOOOOOOOOOOOOOOOOOOOOOOOOOOOOOOOOOOOOOOOOOOOOOOOOOOOOOOOOOOOOOOOOOO | OOOOOOOOOOOOOOOOOOOOOOOOOOOOOOOOOOOOOOOOOOOOOOOOOOOOOOOOOOOOOOOOOOOOOOOOOOOOOOOOOOOOOOOOOO | OOOOOOOOOOOOOOOOOOOOOOOOOOOOOOOOOOOOOOOOOOOOOOOOOOOOOOOOOOOOOOOOOOOOOOOOOOOOOOOOOOOOOOOOOO | OOOOOOOOOOOOOOOOOOOOOOOOOOOOOOOOOOOOOOOOOOOOOOOOOOOOOOOOOOOOOOOOOOOOOOOOOOOOOOOOOOOOOOOOOO | OOOOOOOOOOOOOOOOOOOOOOOOOOOOOOOOOOOOOOOOOOOOOOOOOOOOOOOOOOOOOOOOOOOOOOOOOOOOOOOOOOOOOOOOOO | OOOOOOOOOOOOOOOOOOOOOOOOOOOOOOOOOOOOOOOOOOOOOOOOOOOOOOOOOOOOOOOOOOOOOOOOOOOOOOOOOOOOOOOOOO | OOOOOOOOOOOOOOOOOOOOOOOOOOOOOOOOOOOOOOOOOOOOOOOOOOOOOOOOOOOOOOOOOOOOOOOOOOOOOOOOOOOOOOOOOO |
| Master Materials Change |  |  |  |  |  |  |  |  |  |
| Item | Foxconn P/N | Orig._Usage | New_Usage | Part Description | Manufacturer Full Name | Manufacturer P/N | RoHS | Location | Sheet |
| 1 | ISL68137IRAZ-GG04 | 0 | 8 | IC,PWM Controller,ISL68137IRAZ-T,G,QFN-48,SMD | INTERSIL CORPORATION | ISL68137IRAZ-GG04 | G | (+)PBMU1,PBFU1,PBEU1,PBAU1,PAMU1,PAFU1,PAEU1,PAAU1 | PWA BOM |
| 2 | UCD90160RGCR-C11 | 0 | 1 | IC,Power Controller,UCD90160RGCR,G,VQFN-64,SMD | TEXAS INSTRUMENTS | UCD90160RGCR-C11 | G | (+)U5 | PWA BOM |
| 3 | 87898-0318 | 0 | 10 | CONN,Header,Pin Header,1X3,V/T,2.54mm,30u,G,SMD-3 | MOLEX INCORPORATED | 87898-0318 | G | (+)J_BMC_DEBUG1,J1,J4,J5,J36,J41,J43,J48,J147,J149 | PWA BOM |
|  | 34068LN00-317-G |  |  | CONN,Header,Pin Header,1X3,V/T,2.54mm,30u,G,SMD-3 | MOLEX INCORPORATED | 87898-0315 |  |  | PWA BOM |
|  | 34068HT00-245-G |  |  | CONN,Header,Pin Header,1X3,V/T,Bla,2.54mm,30u,SMD-3 | AMPHENOL SHANGHAI CORP. | G800MU305010EU |  |  | PWA BOM |
|  | 34068GU00-309-G |  |  | CONN,Header,Pin Header,1X3,V/T,Bla,2.54mm,30u,SMD-3 | SAMTEC INC. | TSM-103-01-S-SV-P-TR |  |  | PWA BOM |
| 4 | 87898-0458 | 0 | 1 | CONN,Pin Header,1X4,V/T,Bla,2.54mm,30u,G,SMD-4 | MOLEX INCORPORATED | 87898-0458 | G | (+)J148 | PWA BOM |
|  | 340672300-317-G |  |  | CONN,Pin Header,1X4,V/T,Bla,2.54mm,30u,G,SMD-4 | MOLEX INCORPORATED | 87898-0455 |  |  | PWA BOM |
|  | 340692T00-245-G |  |  | CONN,Header,Pin Header,1X4,V/T,Bla,2.54mm,30u,G,SMD-4 | AMPHENOL SHANGHAI CORP. | G800MR304010HR |  |  | PWA BOM |
|  | 34068VT00-GRT-G |  |  | CONN,Header,Pin Header,1X4,V/T,Bla,2.54mm,30u,G,SMD-4 | PINREX TECHNOLOGY CORP. | 212-91-04SBEJ |  |  | PWA BOM |
| 5 | 320242200-230-G | 8 | 0 | IC,PWM Controller,ISL68137IRAZ-T,G,QFN-48,SMD | INTERSIL CORPORATION | ISL68137IRAZ-T | G | (-)PBMU1,PBFU1,PBEU1,PBAU1,PAMU1,PAFU1,PAEU1,PAAU1 | PWA BOM |
| 6 | 320241C00-183-G | 1 | 0 | IC,Power Controller,UCD90160RGCR,G,VQFN-64,SMD | TEXAS INSTRUMENTS | UCD90160RGCR | G | (-)U5 | PWA BOM |
| 7 | 34068LN00-317-G | 10 | 0 | CONN,Header,Pin Header,1X3,V/T,2.54mm,30u,G,SMD-3 | MOLEX INCORPORATED | 87898-0315 | G | (-)J_BMC_DEBUG1,J1,J4,J5,J36,J41,J43,J48,J147,J149 | PWA BOM |
|  | 34068HT00-245-G |  |  | CONN,Header,Pin Header,1X3,V/T,Bla,2.54mm,30u,SMD-3 | AMPHENOL SHANGHAI CORP. | G800MU305010EU |  |  | PWA BOM |
|  | 34068GU00-309-G |  |  | CONN,Header,Pin Header,1X3,V/T,Bla,2.54mm,30u,SMD-3 | SAMTEC INC. | TSM-103-01-S-SV-P-TR |  |  | PWA BOM |
| 8 | 340672300-317-G | 1 | 0 | CONN,Pin Header,1X4,V/T,Bla,2.54mm,30u,G,SMD-4 | MOLEX INCORPORATED | 87898-0455 | G | (-)J148 | PWA BOM |
|  | 340692T00-245-G |  |  | CONN,Header,Pin Header,1X4,V/T,Bla,2.54mm,30u,G,SMD-4 | AMPHENOL SHANGHAI CORP. | G800MR304010HR |  |  | PWA BOM |
|  | 34068VT00-GRT-G |  |  | CONN,Header,Pin Header,1X4,V/T,Bla,2.54mm,30u,G,SMD-4 | PINREX TECHNOLOGY CORP. | 212-91-04SBEJ |  |  | PWA BOM |
| OOOOOOOOOOOOOOOOOOOOOOOOOOOOOOOOOOOOOOOOOOOOOOOOOOOOOOOOOOOOOOOOOOOOOOOOOOOOOOOOOOOOOOOOOO | OOOOOOOOOOOOOOOOOOOOOOOOOOOOOOOOOOOOOOOOOOOOOOOOOOOOOOOOOOOOOOOOOOOOOOOOOOOOOOOOOOOOOOOOOO | OOOOOOOOOOOOOOOOOOOOOOOOOOOOOOOOOOOOOOOOOOOOOOOOOOOOOOOOOOOOOOOOOOOOOOOOOOOOOOOOOOOOOOOOOO | OOOOOOOOOOOOOOOOOOOOOOOOOOOOOOOOOOOOOOOOOOOOOOOOOOOOOOOOOOOOOOOOOOOOOOOOOOOOOOOOOOOOOOOOOO | OOOOOOOOOOOOOOOOOOOOOOOOOOOOOOOOOOOOOOOOOOOOOOOOOOOOOOOOOOOOOOOOOOOOOOOOOOOOOOOOOOOOOOOOOO | OOOOOOOOOOOOOOOOOOOOOOOOOOOOOOOOOOOOOOOOOOOOOOOOOOOOOOOOOOOOOOOOOOOOOOOOOOOOOOOOOOOOOOOOOO | OOOOOOOOOOOOOOOOOOOOOOOOOOOOOOOOOOOOOOOOOOOOOOOOOOOOOOOOOOOOOOOOOOOOOOOOOOOOOOOOOOOOOOOOOO | OOOOOOOOOOOOOOOOOOOOOOOOOOOOOOOOOOOOOOOOOOOOOOOOOOOOOOOOOOOOOOOOOOOOOOOOOOOOOOOOOOOOOOOOOO | OOOOOOOOOOOOOOOOOOOOOOOOOOOOOOOOOOOOOOOOOOOOOOOOOOOOOOOOOOOOOOOOOOOOOOOOOOOOOOOOOOOOOOOOOO | OOOOOOOOOOOOOOOOOOOOOOOOOOOOOOOOOOOOOOOOOOOOOOOOOOOOOOOOOOOOOOOOOOOOOOOOOOOOOOOOOOOOOOOOOO |
| TLA Parts Change |  |  |  |  |  |  |  |  |  |
| Item | Foxconn P/N | Qty | Part Description | Manufacturer Full Name | Manufacturer P/N | RoHS | Location | Remark | BOM |
| BOM Change List Date:Wed Sep 13 09:18:49 GMT+08:00 2017 |  |  |  |  |  |  |  |  |  |
| New BOM file : E:\barreleye g2\0912\Zaius BG2\Zaius 0913.xls |  |  |  |  |  |  |  |  |  |
| Old BOM file : E:\barreleye g2\0912\Zaius BG2\Zaius 0907.xls |  |  |  |  |  |  |  |  |  |
| ##### Add Parts |  |  |  |  |  |  |  |  |  |
| Item | Location | Qty | Foxconn P/N | Part Description | Manufacturer Full Name | Manufacturer P/N | RoHS | Sheet |  |
| ##### Remove Parts |  |  |  |  |  |  |  |  |  |
| Item | Location | Qty | Foxconn P/N | Part Description | Manufacturer Full Name | Manufacturer P/N | RoHS | Sheet |  |
| ##### Change Parts |  |  |  |  |  |  |  |  |  |
| Item | Location | Qty | Foxconn P/N | Part Description | Manufacturer Full Name | Manufacturer P/N | RoHS | Sheet | Remark |
| 1 | U5 | 1 | UCD90160RGCR-C13 | IC,Power Controller,UCD90160RGCR,G,VQFN-64,SMD | TEXAS INSTRUMENTS | UCD90160RGCR-C13 | G | PWA BOM | In New BOM |
|  | U5 | 1 | UCD90160RGCR-C11 | IC,Power Controller,UCD90160RGCR,G,VQFN-64,SMD | TEXAS INSTRUMENTS | UCD90160RGCR-C11 | G | PWA BOM | In Old BOM |
| ##### Change Revision |  |  |  |  |  |  |  |  |  |
| Sheet | REV OF BOM | CUSTOMER | CUSTOMER P/N | PWA PN | PWA DESCRIPTION | PWA REV | DATE | Remark |  |
| OOOOOOOOOOOOOOOOOOOOOOOOOOOOOOOOOOOOOOOOOOOOOOOOOOOOOOOOOOOOOOOOOOOOOOOOOOOOOOOOOOOOOOOOOO | OOOOOOOOOOOOOOOOOOOOOOOOOOOOOOOOOOOOOOOOOOOOOOOOOOOOOOOOOOOOOOOOOOOOOOOOOOOOOOOOOOOOOOOOOO | OOOOOOOOOOOOOOOOOOOOOOOOOOOOOOOOOOOOOOOOOOOOOOOOOOOOOOOOOOOOOOOOOOOOOOOOOOOOOOOOOOOOOOOOOO | OOOOOOOOOOOOOOOOOOOOOOOOOOOOOOOOOOOOOOOOOOOOOOOOOOOOOOOOOOOOOOOOOOOOOOOOOOOOOOOOOOOOOOOOOO | OOOOOOOOOOOOOOOOOOOOOOOOOOOOOOOOOOOOOOOOOOOOOOOOOOOOOOOOOOOOOOOOOOOOOOOOOOOOOOOOOOOOOOOOOO | OOOOOOOOOOOOOOOOOOOOOOOOOOOOOOOOOOOOOOOOOOOOOOOOOOOOOOOOOOOOOOOOOOOOOOOOOOOOOOOOOOOOOOOOOO | OOOOOOOOOOOOOOOOOOOOOOOOOOOOOOOOOOOOOOOOOOOOOOOOOOOOOOOOOOOOOOOOOOOOOOOOOOOOOOOOOOOOOOOOOO | OOOOOOOOOOOOOOOOOOOOOOOOOOOOOOOOOOOOOOOOOOOOOOOOOOOOOOOOOOOOOOOOOOOOOOOOOOOOOOOOOOOOOOOOOO | OOOOOOOOOOOOOOOOOOOOOOOOOOOOOOOOOOOOOOOOOOOOOOOOOOOOOOOOOOOOOOOOOOOOOOOOOOOOOOOOOOOOOOOOOO | OOOOOOOOOOOOOOOOOOOOOOOOOOOOOOOOOOOOOOOOOOOOOOOOOOOOOOOOOOOOOOOOOOOOOOOOOOOOOOOOOOOOOOOOOO |
| Second Source Change |  |  |  |  |  |  |  |  |  |
| Item | Location | Change Type | Foxconn P/N | Part Description | Manufacturer Full Name | Manufacturer P/N | RoHS | Sheet |  |
| OOOOOOOOOOOOOOOOOOOOOOOOOOOOOOOOOOOOOOOOOOOOOOOOOOOOOOOOOOOOOOOOOOOOOOOOOOOOOOOOOOOOOOOOOO | OOOOOOOOOOOOOOOOOOOOOOOOOOOOOOOOOOOOOOOOOOOOOOOOOOOOOOOOOOOOOOOOOOOOOOOOOOOOOOOOOOOOOOOOOO | OOOOOOOOOOOOOOOOOOOOOOOOOOOOOOOOOOOOOOOOOOOOOOOOOOOOOOOOOOOOOOOOOOOOOOOOOOOOOOOOOOOOOOOOOO | OOOOOOOOOOOOOOOOOOOOOOOOOOOOOOOOOOOOOOOOOOOOOOOOOOOOOOOOOOOOOOOOOOOOOOOOOOOOOOOOOOOOOOOOOO | OOOOOOOOOOOOOOOOOOOOOOOOOOOOOOOOOOOOOOOOOOOOOOOOOOOOOOOOOOOOOOOOOOOOOOOOOOOOOOOOOOOOOOOOOO | OOOOOOOOOOOOOOOOOOOOOOOOOOOOOOOOOOOOOOOOOOOOOOOOOOOOOOOOOOOOOOOOOOOOOOOOOOOOOOOOOOOOOOOOOO | OOOOOOOOOOOOOOOOOOOOOOOOOOOOOOOOOOOOOOOOOOOOOOOOOOOOOOOOOOOOOOOOOOOOOOOOOOOOOOOOOOOOOOOOOO | OOOOOOOOOOOOOOOOOOOOOOOOOOOOOOOOOOOOOOOOOOOOOOOOOOOOOOOOOOOOOOOOOOOOOOOOOOOOOOOOOOOOOOOOOO | OOOOOOOOOOOOOOOOOOOOOOOOOOOOOOOOOOOOOOOOOOOOOOOOOOOOOOOOOOOOOOOOOOOOOOOOOOOOOOOOOOOOOOOOOO | OOOOOOOOOOOOOOOOOOOOOOOOOOOOOOOOOOOOOOOOOOOOOOOOOOOOOOOOOOOOOOOOOOOOOOOOOOOOOOOOOOOOOOOOOO |
| Master Materials Change |  |  |  |  |  |  |  |  |  |
| Item | Foxconn P/N | Orig._Usage | New_Usage | Part Description | Manufacturer Full Name | Manufacturer P/N | RoHS | Location | Sheet |
| 1 | UCD90160RGCR-C13 | 0 | 1 | IC,Power Controller,UCD90160RGCR,G,VQFN-64,SMD | TEXAS INSTRUMENTS | UCD90160RGCR-C13 | G | (+)U5 | PWA BOM |
| 2 | UCD90160RGCR-C11 | 1 | 0 | IC,Power Controller,UCD90160RGCR,G,VQFN-64,SMD | TEXAS INSTRUMENTS | UCD90160RGCR-C11 | G | (-)U5 | PWA BOM |
| OOOOOOOOOOOOOOOOOOOOOOOOOOOOOOOOOOOOOOOOOOOOOOOOOOOOOOOOOOOOOOOOOOOOOOOOOOOOOOOOOOOOOOOOOO | OOOOOOOOOOOOOOOOOOOOOOOOOOOOOOOOOOOOOOOOOOOOOOOOOOOOOOOOOOOOOOOOOOOOOOOOOOOOOOOOOOOOOOOOOO | OOOOOOOOOOOOOOOOOOOOOOOOOOOOOOOOOOOOOOOOOOOOOOOOOOOOOOOOOOOOOOOOOOOOOOOOOOOOOOOOOOOOOOOOOO | OOOOOOOOOOOOOOOOOOOOOOOOOOOOOOOOOOOOOOOOOOOOOOOOOOOOOOOOOOOOOOOOOOOOOOOOOOOOOOOOOOOOOOOOOO | OOOOOOOOOOOOOOOOOOOOOOOOOOOOOOOOOOOOOOOOOOOOOOOOOOOOOOOOOOOOOOOOOOOOOOOOOOOOOOOOOOOOOOOOOO | OOOOOOOOOOOOOOOOOOOOOOOOOOOOOOOOOOOOOOOOOOOOOOOOOOOOOOOOOOOOOOOOOOOOOOOOOOOOOOOOOOOOOOOOOO | OOOOOOOOOOOOOOOOOOOOOOOOOOOOOOOOOOOOOOOOOOOOOOOOOOOOOOOOOOOOOOOOOOOOOOOOOOOOOOOOOOOOOOOOOO | OOOOOOOOOOOOOOOOOOOOOOOOOOOOOOOOOOOOOOOOOOOOOOOOOOOOOOOOOOOOOOOOOOOOOOOOOOOOOOOOOOOOOOOOOO | OOOOOOOOOOOOOOOOOOOOOOOOOOOOOOOOOOOOOOOOOOOOOOOOOOOOOOOOOOOOOOOOOOOOOOOOOOOOOOOOOOOOOOOOOO | OOOOOOOOOOOOOOOOOOOOOOOOOOOOOOOOOOOOOOOOOOOOOOOOOOOOOOOOOOOOOOOOOOOOOOOOOOOOOOOOOOOOOOOOOO |
| TLA Parts Change |  |  |  |  |  |  |  |  |  |
| Item | Foxconn P/N | Qty | Part Description | Manufacturer Full Name | Manufacturer P/N | RoHS | Location | Remark | BOM |
| BOM Change List Date:Thu Sep 28 18:52:32 GMT+08:00 2017 |  |  |  |  |  |  |  |  |  |
| New BOM file : C:\<user>\ZAIUS-MB-PVT-HW-EBOM-X04-20170928.xls |  |  |  |  |  |  |  |  |  |
| Old BOM file : C:\<user>\ZAIUS-MB-PVT-HW-EBOM-X04-20170830.xls |  |  |  |  |  |  |  |  |  |
| ##### Add Parts |  |  |  |  |  |  |  |  |  |
| Item | Location | Qty | Foxconn P/N | Part Description | Manufacturer Full Name | Manufacturer P/N | RoHS | Sheet |  |
| ##### Remove Parts |  |  |  |  |  |  |  |  |  |
| Item | Location | Qty | Foxconn P/N | Part Description | Manufacturer Full Name | Manufacturer P/N | RoHS | Sheet |  |
| 1 | C2092,C2120,C2121,C2122 | 4 | 620106200-015-G | CAP,10nF,+/-10%,X7R,16V,G,SMD0402 | MURATA ELEC. NORTH AMERICA | GRM155R71C103KA01D | Y | PWA BOM |  |
| 2 | C2008,C2010 | 2 | 620108100-015-G | CAP,15pF,+/-5%,NPO(C0G),50V,G,SMD0402 | MURATA ELEC. NORTH AMERICA | GRM1555C1H150J | N | PWA BOM |  |
| 3 | R1425,R1516,R1517,R1518 | 4 | 610114U00-017-G | RES,3.3KOhm,+/-1%,1/16W,G,SMD0402 | KOA SPEER ELECTRONICS, INC. | RK73H1ETTP3301F | N | PWA BOM |  |
| ##### Change Parts |  |  |  |  |  |  |  |  |  |
| Item | Location | Qty | Foxconn P/N | Part Description | Manufacturer Full Name | Manufacturer P/N | RoHS | Sheet | Remark |
| 1 | U5 | 1 | UCD90160RGCR-C13 | IC,Power Controller,UCD90160RGCR,G,VQFN-64,SMD | TEXAS INSTRUMENTS | UCD90160RGCR-C13 |  | PWA BOM | In New BOM |
|  | U5 | 1 | 320241C00-183-G | IC,Power Controller,UCD90160RGCR,G,VQFN-64,SMD | TEXAS INSTRUMENTS | UCD90160RGCR |  | PWA BOM | In Old BOM |
| ##### Change Revision |  |  |  |  |  |  |  |  |  |
| Sheet | REV OF BOM | CUSTOMER | CUSTOMER P/N | PWA PN | PWA DESCRIPTION | PWA REV | DATE | Remark |  |
| OOOOOOOOOOOOOOOOOOOOOOOOOOOOOOOOOOOOOOOOOOOOOOOOOOOOOOOOOOOOOOOOOOOOOOOOOOOOOOOOOOOOOOOOOO | OOOOOOOOOOOOOOOOOOOOOOOOOOOOOOOOOOOOOOOOOOOOOOOOOOOOOOOOOOOOOOOOOOOOOOOOOOOOOOOOOOOOOOOOOO | OOOOOOOOOOOOOOOOOOOOOOOOOOOOOOOOOOOOOOOOOOOOOOOOOOOOOOOOOOOOOOOOOOOOOOOOOOOOOOOOOOOOOOOOOO | OOOOOOOOOOOOOOOOOOOOOOOOOOOOOOOOOOOOOOOOOOOOOOOOOOOOOOOOOOOOOOOOOOOOOOOOOOOOOOOOOOOOOOOOOO | OOOOOOOOOOOOOOOOOOOOOOOOOOOOOOOOOOOOOOOOOOOOOOOOOOOOOOOOOOOOOOOOOOOOOOOOOOOOOOOOOOOOOOOOOO | OOOOOOOOOOOOOOOOOOOOOOOOOOOOOOOOOOOOOOOOOOOOOOOOOOOOOOOOOOOOOOOOOOOOOOOOOOOOOOOOOOOOOOOOOO | OOOOOOOOOOOOOOOOOOOOOOOOOOOOOOOOOOOOOOOOOOOOOOOOOOOOOOOOOOOOOOOOOOOOOOOOOOOOOOOOOOOOOOOOOO | OOOOOOOOOOOOOOOOOOOOOOOOOOOOOOOOOOOOOOOOOOOOOOOOOOOOOOOOOOOOOOOOOOOOOOOOOOOOOOOOOOOOOOOOOO | OOOOOOOOOOOOOOOOOOOOOOOOOOOOOOOOOOOOOOOOOOOOOOOOOOOOOOOOOOOOOOOOOOOOOOOOOOOOOOOOOOOOOOOOOO | OOOOOOOOOOOOOOOOOOOOOOOOOOOOOOOOOOOOOOOOOOOOOOOOOOOOOOOOOOOOOOOOOOOOOOOOOOOOOOOOOOOOOOOOOO |
| Second Source Change |  |  |  |  |  |  |  |  |  |
| Item | Location | Change Type | Foxconn P/N | Part Description | Manufacturer Full Name | Manufacturer P/N | RoHS | Sheet |  |
| OOOOOOOOOOOOOOOOOOOOOOOOOOOOOOOOOOOOOOOOOOOOOOOOOOOOOOOOOOOOOOOOOOOOOOOOOOOOOOOOOOOOOOOOOO | OOOOOOOOOOOOOOOOOOOOOOOOOOOOOOOOOOOOOOOOOOOOOOOOOOOOOOOOOOOOOOOOOOOOOOOOOOOOOOOOOOOOOOOOOO | OOOOOOOOOOOOOOOOOOOOOOOOOOOOOOOOOOOOOOOOOOOOOOOOOOOOOOOOOOOOOOOOOOOOOOOOOOOOOOOOOOOOOOOOOO | OOOOOOOOOOOOOOOOOOOOOOOOOOOOOOOOOOOOOOOOOOOOOOOOOOOOOOOOOOOOOOOOOOOOOOOOOOOOOOOOOOOOOOOOOO | OOOOOOOOOOOOOOOOOOOOOOOOOOOOOOOOOOOOOOOOOOOOOOOOOOOOOOOOOOOOOOOOOOOOOOOOOOOOOOOOOOOOOOOOOO | OOOOOOOOOOOOOOOOOOOOOOOOOOOOOOOOOOOOOOOOOOOOOOOOOOOOOOOOOOOOOOOOOOOOOOOOOOOOOOOOOOOOOOOOOO | OOOOOOOOOOOOOOOOOOOOOOOOOOOOOOOOOOOOOOOOOOOOOOOOOOOOOOOOOOOOOOOOOOOOOOOOOOOOOOOOOOOOOOOOOO | OOOOOOOOOOOOOOOOOOOOOOOOOOOOOOOOOOOOOOOOOOOOOOOOOOOOOOOOOOOOOOOOOOOOOOOOOOOOOOOOOOOOOOOOOO | OOOOOOOOOOOOOOOOOOOOOOOOOOOOOOOOOOOOOOOOOOOOOOOOOOOOOOOOOOOOOOOOOOOOOOOOOOOOOOOOOOOOOOOOOO | OOOOOOOOOOOOOOOOOOOOOOOOOOOOOOOOOOOOOOOOOOOOOOOOOOOOOOOOOOOOOOOOOOOOOOOOOOOOOOOOOOOOOOOOOO |
| Master Materials Change |  |  |  |  |  |  |  |  |  |
| Item | Foxconn P/N | Orig._Usage | New_Usage | Part Description | Manufacturer Full Name | Manufacturer P/N | RoHS | Location | Sheet |
| 1 | 620106200-015-G | 41 | 37 | CAP,10nF,+/-10%,X7R,16V,G,SMD0402 | MURATA ELEC. NORTH AMERICA | GRM155R71C103KA01D | Y | (-)C2092,C2120,C2121,C2122 | PWA BOM |
| 2 | 610114U00-017-G | 25 | 21 | RES,3.3KOhm,+/-1%,1/16W,G,SMD0402 | KOA SPEER ELECTRONICS, INC. | RK73H1ETTP3301F | N | (-)R1425,R1516,R1517,R1518 | PWA BOM |
| 3 | UCD90160RGCR-C13 | 0 | 1 | IC,Power Controller,UCD90160RGCR,G,VQFN-64,SMD | TEXAS INSTRUMENTS | UCD90160RGCR-C13 |  | (+)U5 | PWA BOM |
| 4 | 620108100-015-G | 2 | 0 | CAP,15pF,+/-5%,NPO(C0G),50V,G,SMD0402 | MURATA ELEC. NORTH AMERICA | GRM1555C1H150J | N | (-)C2008,C2010 | PWA BOM |
| 5 | 320241C00-183-G | 1 | 0 | IC,Power Controller,UCD90160RGCR,G,VQFN-64,SMD | TEXAS INSTRUMENTS | UCD90160RGCR |  | (-)U5 | PWA BOM |
| OOOOOOOOOOOOOOOOOOOOOOOOOOOOOOOOOOOOOOOOOOOOOOOOOOOOOOOOOOOOOOOOOOOOOOOOOOOOOOOOOOOOOOOOOO | OOOOOOOOOOOOOOOOOOOOOOOOOOOOOOOOOOOOOOOOOOOOOOOOOOOOOOOOOOOOOOOOOOOOOOOOOOOOOOOOOOOOOOOOOO | OOOOOOOOOOOOOOOOOOOOOOOOOOOOOOOOOOOOOOOOOOOOOOOOOOOOOOOOOOOOOOOOOOOOOOOOOOOOOOOOOOOOOOOOOO | OOOOOOOOOOOOOOOOOOOOOOOOOOOOOOOOOOOOOOOOOOOOOOOOOOOOOOOOOOOOOOOOOOOOOOOOOOOOOOOOOOOOOOOOOO | OOOOOOOOOOOOOOOOOOOOOOOOOOOOOOOOOOOOOOOOOOOOOOOOOOOOOOOOOOOOOOOOOOOOOOOOOOOOOOOOOOOOOOOOOO | OOOOOOOOOOOOOOOOOOOOOOOOOOOOOOOOOOOOOOOOOOOOOOOOOOOOOOOOOOOOOOOOOOOOOOOOOOOOOOOOOOOOOOOOOO | OOOOOOOOOOOOOOOOOOOOOOOOOOOOOOOOOOOOOOOOOOOOOOOOOOOOOOOOOOOOOOOOOOOOOOOOOOOOOOOOOOOOOOOOOO | OOOOOOOOOOOOOOOOOOOOOOOOOOOOOOOOOOOOOOOOOOOOOOOOOOOOOOOOOOOOOOOOOOOOOOOOOOOOOOOOOOOOOOOOOO | OOOOOOOOOOOOOOOOOOOOOOOOOOOOOOOOOOOOOOOOOOOOOOOOOOOOOOOOOOOOOOOOOOOOOOOOOOOOOOOOOOOOOOOOOO |  |
| TLA Parts Change |  |  |  |  |  |  |  |  |  |
| Item | Foxconn P/N | Qty | Part Description | Manufacturer Full Name | Manufacturer P/N | RoHS | Location | Remark |  |
| BOM Change List Date:Fri Sep 29 16:53:09 GMT+08:00 2017 |  |  |  |  |  |  |  |  |  |
| New BOM file : E:\barreleye g2\0928\ZAIUS-MB-PVT-X04-BOM_X25_20170929.xls |  |  |  |  |  |  |  |  |  |
| Old BOM file : E:\barreleye g2\0928\ZAIUS0913.xls |  |  |  |  |  |  |  |  |  |
| ##### Add Parts |  |  |  |  |  |  |  |  |  |
| Item | Location | Qty | Foxconn P/N | Part Description | Manufacturer Full Name | Manufacturer P/N | RoHS | Sheet |  |
| ##### Remove Parts |  |  |  |  |  |  |  |  |  |
| Item | Location | Qty | Foxconn P/N | Part Description | Manufacturer Full Name | Manufacturer P/N | RoHS | Sheet |  |
| 1 | C2092,C2120,C2121,C2122 | 4 | 620106200-015-G | CAP,10nF,+/-10%,X7R,16V,G,SMD0402 | MURATA ELEC. NORTH AMERICA | GRM155R71C103KA01D | G | PWA BOM |  |
|  |  |  | 620106200-026-G | CAP,10nF,+/-10%,X7R,16V,G,SMD0402 | SAMSUNG SEMICONDUCTOR | CL05B103KO5NNNC | G | PWA BOM |  |
|  |  |  | 620106200-023-G | CAP,10nF,+/-10%,X7R,16V,G,SMD0402 | TAIYO ELECTRIC IND.CO.LTD | EMK105B7103KV-F | G | PWA BOM |  |
| 2 | C2008,C2010 | 2 | 620108100-015-G | CAP,15pF,+/-5%,NPO(C0G),50V,G,SMD0402 | MURATA ELEC. NORTH AMERICA | GRM1555C1H150J | G | PWA BOM |  |
| 3 | R1425,R1516,R1517,R1518 | 4 | 610114U00-017-G | RES,3.3KOhm,+/-1%,1/16W,G,SMD0402 | KOA SPEER ELECTRONICS, INC. | RK73H1ETTP3301F | G | PWA BOM |  |
|  |  |  | 610114U00-024-G | RES,3.3KOhm,+/-1%,1/16W,G,SMD0402 | PANASONIC INDUSTRIAL CO.,LTD. | ERJ2RKF3301X | G | PWA BOM |  |
|  |  |  | 610114U00-011-G | RES,3.3KOhm,+/-1%,1/16W,G,SMD0402 | YAGEO CORPORATION COMPONENT | RC0402FR-073K3L | G | PWA BOM |  |
|  |  |  | 610114U00-044-G | RES,3.3KOhm,+/-1%,1/16W,G,SMD0402 | TA-I TECHNOLOGY CO., LTD. | RM04FTN3301 | G | PWA BOM |  |
| ##### Change Parts |  |  |  |  |  |  |  |  |  |
| Item | Location | Qty | Foxconn P/N | Part Description | Manufacturer Full Name | Manufacturer P/N | RoHS | Sheet | Remark |
| 1 | PHAR9,PALR16,PBLR18,PBNR21,PANR21,PBMR40,PBFR40,PBER40,PBAR40,PAMR40,PAFR40,PAER40,PAAR40,R865,R866,R1155,R1169,R1181,R1193,R1205,R1217,R1258,R1329,R1333,R1334,R1335,R1498,R1500,R1729,R1733,R1737,R1741,R1824 | 33 | 61010L300-017-G | RES,1KOhm,+/-1%,1/16W,G,SMD0402 | KOA SPEER ELECTRONICS, INC. | RK73H1ETTP1001F | G | PWA BOM | In New BOM |
|  |  |  | 61010L300-029-G | RES,1KOhm,+/-1%,1/16W,G,SMD0402 | VISHAY ENTER TECHNO LOGY.INC | CRCW04021K00FKED | G | PWA BOM | In New BOM |
|  |  |  | 61010L300-024-G | RES,1KOhm,+/-1%,1/16W,G,SMD0402 | PANASONIC INDUSTRIAL CO.,LTD. | ERJ2RKF1001X | G | PWA BOM | In New BOM |
|  | PHAR9,PALR16,PBLR18,PBNR21,PANR21,PBMR40,PBFR40,PBER40,PBAR40,PAMR40,PAFR40,PAER40,PAAR40,R865,R866,R1155,R1169,R1181,R1193,R1205,R1217,R1258,R1329,R1333,R1334,R1335,R1498,R1500,R1729,R1733,R1737,R1741,R1824 | 33 | 61010L300-017-G | RES,1KOhm,+/-1%,1/16W,G,SMD0402 | KOA SPEER ELECTRONICS, INC. | RK73H1ETTP1001F | G | PWA BOM | In Old BOM |
|  |  |  | 61010L300-029-G | RES,1KOhm,+/-1%,1/16W,G,SMD0402 | VISHAY ENTER TECHNO LOGY.INC | CRCW04021K00FKED | G | PWA BOM | In Old BOM |
|  |  |  | 610151600-024-G | RES,thick film,1KOhm,+/-1%,1/10W,SMD0402,G | PANASONIC INDUSTRIAL CO.,LTD. | ERJ2RKF1001X | G | PWA BOM | In Old BOM |
| 2 | PCIE2,PCIE3,PCIE4 | 3 | 10061913-103HLF | CONN,PCIE-16X,V/T,Bla,1mm,30u,G,SMD-164 | FCI CONNECTORS HONGKONG LTD. | 10061913-103HLF | G | PWA BOM | In New BOM |
|  |  |  | 340321600-278-G | CONN,PCIE-16X,V/T,Bla,1mm,30u,G,SMD-164 | TYCO ELECTRONICS CORPORATION | 2041366-9 | G | PWA BOM | In New BOM |
|  | PCIE2,PCIE3,PCIE4 | 3 | 10061913-103HLF | CONN,PCIE-16X,V/T,Bla,1mm,30u,G,SMD-164 | FCI CONNECTORS HONGKONG LTD. | 10061913-103HLF | G | PWA BOM | In Old BOM |
|  |  |  | 2041366-9 | CONN,PCIE-16X,V/T,Bla,1mm,30u,G,SMD-164 | TYCO ELECTRONICS CORPORATION | 2041366-9 | G | PWA BOM | In Old BOM |
| 3 | R1492 | 1 | 610118800-017-G | RES,499KOhm,+/-1%,1/8W,G,SMD0805 | KOA SPEER ELECTRONICS, INC. | RK73H2ATTD4993F | G | PWA BOM | In New BOM |
|  |  |  | 610118800-024-G | RES,499KOhm,+/-1%,1/8W,G,SMD0805 | PANASONIC INDUSTRIAL CO.,LTD. | ERJ6ENF4993V | G | PWA BOM | In New BOM |
|  |  |  | 610118800-011-G | RES,499KOhm,+/-1%,1/8W,G,SMD0805 | YAGEO CORPORATION COMPONENT | RC0805FR-07499KL | G | PWA BOM | In New BOM |
|  | R1492 | 1 | 610118800-017-G | RES,499KOhm,+/-1%,1/8W,G,SMD0805 | KOA SPEER ELECTRONICS, INC. | RK73H2ATTD4993F | G | PWA BOM | In Old BOM |
|  |  |  | 610118800-024-G | RES,499KOhm,+/-1%,1/8W,G,SMD0805 | PANASONIC INDUSTRIAL CO.,LTD. | ERJ6ENF4993V | G | PWA BOM | In Old BOM |
|  |  |  | RC0805FR-07499KL | RES,499KOhm,+/-1%,1/8W,G,SMD0805 | YAGEO CORPORATION COMPONENT | RC0805FR-07499KL | G | PWA BOM | In Old BOM |
| 4 | PBMJ1,PBEJ1,PBAJ1,PAMJ1,PAEJ1,PAAJ1 | 6 | 340634U00-600-G | CONN,Pin Header,2X3,V/T,Bla,2.54mm,30u,G,SMD-6 | FOXCONN TECHNOLOGY CO.,LTD. | HS1103H-RN | G | PWA BOM | In New BOM |
|  |  |  | 34068GL00-317-G | CONN,Header,Pin Header,2X3,V/T,Bla,2.54mm,30u,SMD-6 | MOLEX INCORPORATED | 015-91-6063 | G | PWA BOM | In New BOM |
|  |  |  | 3406AY700-637-G | Header&Socket Connector,11006A5807,Pin Header,6,SMD,NY6T,2.54mm,30u",Black,G | LONG SHOUNG CO.,LTD. | 11006A5807 | G | PWA BOM | In New BOM |
|  | PBMJ1,PBEJ1,PBAJ1,PAMJ1,PAEJ1,PAAJ1 | 6 | 340634U00-600-G | CONN,Pin Header,2X3,V/T,Bla,2.54mm,30u,G,SMD-6 | FOXCONN TECHNOLOGY CO.,LTD. | HS1103H-RN | G | PWA BOM | In Old BOM |
|  |  |  | 34065EA00-317-G | CONN,Header,Pin Header,2X3,V/T,Bla,2.54mm,30u,G,SMD-6 | MOLEX INCORPORATED | 015-91-3060 | G | PWA BOM | In Old BOM |
|  |  |  | 3406AY700-637-G | Header&Socket Connector,11006A5807,Pin Header,6,SMD,NY6T,2.54mm,30u",Black,G | LONG SHOUNG CO.,LTD. | 11006A5807 | G | PWA BOM | In Old BOM |
| 5 | PCB | 1 | 0101FBQ00-000-G | PCB | GCE | 0101FBQ00-000-G | G | PWA BOM | In New BOM |
|  | PCB | 1 | 0101FBQ00-000-G | PCB,Zaius-MB PVT-X04,OSP,Gre,22L,22.20*13.00,G | GOLD CIRCUIT ELECTRONICS LTD. | 0101FBQ00-000-G | G | PWA BOM | In Old BOM |
| 6 | PBMU1,PBFU1,PBEU1,PBAU1,PAMU1,PAFU1,PAEU1,PAAU1 | 8 | 320242200-230-G | IC,PWM Controller,ISL68137IRAZ-T,G,QFN-48,SMD | INTERSIL CORPORATION | ISL68137IRAZ-T | G | PWA BOM | In New BOM |
|  | PBMU1,PBFU1,PBEU1,PBAU1,PAMU1,PAFU1,PAEU1,PAAU1 | 8 | ISL68137IRAZ-GG04 | IC,PWM Controller,ISL68137IRAZ-T,G,QFN-48,SMD | INTERSIL CORPORATION | ISL68137IRAZ-GG04 | G | PWA BOM | In Old BOM |
| ##### Change Revision |  |  |  |  |  |  |  |  |  |
| Sheet | REV OF BOM | CUSTOMER | CUSTOMER P/N | PWA PN | PWA DESCRIPTION | PWA REV | DATE | Remark |  |
| OOOOOOOOOOOOOOOOOOOOOOOOOOOOOOOOOOOOOOOOOOOOOOOOOOOOOOOOOOOOOOOOOOOOOOOOOOOOOOOOOOOOOOOOOO | OOOOOOOOOOOOOOOOOOOOOOOOOOOOOOOOOOOOOOOOOOOOOOOOOOOOOOOOOOOOOOOOOOOOOOOOOOOOOOOOOOOOOOOOOO | OOOOOOOOOOOOOOOOOOOOOOOOOOOOOOOOOOOOOOOOOOOOOOOOOOOOOOOOOOOOOOOOOOOOOOOOOOOOOOOOOOOOOOOOOO | OOOOOOOOOOOOOOOOOOOOOOOOOOOOOOOOOOOOOOOOOOOOOOOOOOOOOOOOOOOOOOOOOOOOOOOOOOOOOOOOOOOOOOOOOO | OOOOOOOOOOOOOOOOOOOOOOOOOOOOOOOOOOOOOOOOOOOOOOOOOOOOOOOOOOOOOOOOOOOOOOOOOOOOOOOOOOOOOOOOOO | OOOOOOOOOOOOOOOOOOOOOOOOOOOOOOOOOOOOOOOOOOOOOOOOOOOOOOOOOOOOOOOOOOOOOOOOOOOOOOOOOOOOOOOOOO | OOOOOOOOOOOOOOOOOOOOOOOOOOOOOOOOOOOOOOOOOOOOOOOOOOOOOOOOOOOOOOOOOOOOOOOOOOOOOOOOOOOOOOOOOO | OOOOOOOOOOOOOOOOOOOOOOOOOOOOOOOOOOOOOOOOOOOOOOOOOOOOOOOOOOOOOOOOOOOOOOOOOOOOOOOOOOOOOOOOOO | OOOOOOOOOOOOOOOOOOOOOOOOOOOOOOOOOOOOOOOOOOOOOOOOOOOOOOOOOOOOOOOOOOOOOOOOOOOOOOOOOOOOOOOOOO | OOOOOOOOOOOOOOOOOOOOOOOOOOOOOOOOOOOOOOOOOOOOOOOOOOOOOOOOOOOOOOOOOOOOOOOOOOOOOOOOOOOOOOOOOO |
| Second Source Change |  |  |  |  |  |  |  |  |  |
| Item | Location | Change Type | Foxconn P/N | Part Description | Manufacturer Full Name | Manufacturer P/N | RoHS | Sheet |  |
| 1 | PHAR9,PALR16,PBLR18,PBNR21,PANR21,PBMR40,PBFR40,PBER40,PBAR40,PAMR40,PAFR40,PAER40,PAAR40,R865,R866,R1155,R1169,R1181,R1193,R1205,R1217,R1258,R1329,R1333,R1334,R1335,R1498,R1500,R1729,R1733,R1737,R1741,R1824 |  | 61010L300-017-G | RES,1KOhm,+/-1%,1/16W,G,SMD0402 | KOA SPEER ELECTRONICS, INC. | RK73H1ETTP1001F | G | PWA BOM |  |
|  |  | NO | 61010L300-029-G | RES,1KOhm,+/-1%,1/16W,G,SMD0402 | VISHAY ENTER TECHNO LOGY.INC | CRCW04021K00FKED | G | PWA BOM |  |
|  |  | ADD | 61010L300-024-G | RES,1KOhm,+/-1%,1/16W,G,SMD0402 | PANASONIC INDUSTRIAL CO.,LTD. | ERJ2RKF1001X | G | PWA BOM |  |
|  |  | Delete | 610151600-024-G | RES,thick film,1KOhm,+/-1%,1/10W,SMD0402,G | PANASONIC INDUSTRIAL CO.,LTD. | ERJ2RKF1001X | G | PWA BOM |  |
| 2 | PCIE2,PCIE3,PCIE4 |  | 10061913-103HLF | CONN,PCIE-16X,V/T,Bla,1mm,30u,G,SMD-164 | FCI CONNECTORS HONGKONG LTD. | 10061913-103HLF | G | PWA BOM |  |
|  |  | ADD | 340321600-278-G | CONN,PCIE-16X,V/T,Bla,1mm,30u,G,SMD-164 | TYCO ELECTRONICS CORPORATION | 2041366-9 | G | PWA BOM |  |
|  |  | Delete | 2041366-9 | CONN,PCIE-16X,V/T,Bla,1mm,30u,G,SMD-164 | TYCO ELECTRONICS CORPORATION | 2041366-9 | G | PWA BOM |  |
| 3 | R1492 |  | 610118800-017-G | RES,499KOhm,+/-1%,1/8W,G,SMD0805 | KOA SPEER ELECTRONICS, INC. | RK73H2ATTD4993F | G | PWA BOM |  |
|  |  | NO | 610118800-024-G | RES,499KOhm,+/-1%,1/8W,G,SMD0805 | PANASONIC INDUSTRIAL CO.,LTD. | ERJ6ENF4993V | G | PWA BOM |  |
|  |  | ADD | 610118800-011-G | RES,499KOhm,+/-1%,1/8W,G,SMD0805 | YAGEO CORPORATION COMPONENT | RC0805FR-07499KL | G | PWA BOM |  |
|  |  | Delete | RC0805FR-07499KL | RES,499KOhm,+/-1%,1/8W,G,SMD0805 | YAGEO CORPORATION COMPONENT | RC0805FR-07499KL | G | PWA BOM |  |
| 4 | PBMJ1,PBEJ1,PBAJ1,PAMJ1,PAEJ1,PAAJ1 |  | 340634U00-600-G | CONN,Pin Header,2X3,V/T,Bla,2.54mm,30u,G,SMD-6 | FOXCONN TECHNOLOGY CO.,LTD. | HS1103H-RN | G | PWA BOM |  |
|  |  | ADD | 34068GL00-317-G | CONN,Header,Pin Header,2X3,V/T,Bla,2.54mm,30u,SMD-6 | MOLEX INCORPORATED | 015-91-6063 | G | PWA BOM |  |
|  |  | NO | 3406AY700-637-G | Header&Socket Connector,11006A5807,Pin Header,6,SMD,NY6T,2.54mm,30u",Black,G | LONG SHOUNG CO.,LTD. | 11006A5807 | G | PWA BOM |  |
|  |  | Delete | 34065EA00-317-G | CONN,Header,Pin Header,2X3,V/T,Bla,2.54mm,30u,G,SMD-6 | MOLEX INCORPORATED | 015-91-3060 | G | PWA BOM |  |
| OOOOOOOOOOOOOOOOOOOOOOOOOOOOOOOOOOOOOOOOOOOOOOOOOOOOOOOOOOOOOOOOOOOOOOOOOOOOOOOOOOOOOOOOOO | OOOOOOOOOOOOOOOOOOOOOOOOOOOOOOOOOOOOOOOOOOOOOOOOOOOOOOOOOOOOOOOOOOOOOOOOOOOOOOOOOOOOOOOOOO | OOOOOOOOOOOOOOOOOOOOOOOOOOOOOOOOOOOOOOOOOOOOOOOOOOOOOOOOOOOOOOOOOOOOOOOOOOOOOOOOOOOOOOOOOO | OOOOOOOOOOOOOOOOOOOOOOOOOOOOOOOOOOOOOOOOOOOOOOOOOOOOOOOOOOOOOOOOOOOOOOOOOOOOOOOOOOOOOOOOOO | OOOOOOOOOOOOOOOOOOOOOOOOOOOOOOOOOOOOOOOOOOOOOOOOOOOOOOOOOOOOOOOOOOOOOOOOOOOOOOOOOOOOOOOOOO | OOOOOOOOOOOOOOOOOOOOOOOOOOOOOOOOOOOOOOOOOOOOOOOOOOOOOOOOOOOOOOOOOOOOOOOOOOOOOOOOOOOOOOOOOO | OOOOOOOOOOOOOOOOOOOOOOOOOOOOOOOOOOOOOOOOOOOOOOOOOOOOOOOOOOOOOOOOOOOOOOOOOOOOOOOOOOOOOOOOOO | OOOOOOOOOOOOOOOOOOOOOOOOOOOOOOOOOOOOOOOOOOOOOOOOOOOOOOOOOOOOOOOOOOOOOOOOOOOOOOOOOOOOOOOOOO | OOOOOOOOOOOOOOOOOOOOOOOOOOOOOOOOOOOOOOOOOOOOOOOOOOOOOOOOOOOOOOOOOOOOOOOOOOOOOOOOOOOOOOOOOO | OOOOOOOOOOOOOOOOOOOOOOOOOOOOOOOOOOOOOOOOOOOOOOOOOOOOOOOOOOOOOOOOOOOOOOOOOOOOOOOOOOOOOOOOOO |
| Master Materials Change |  |  |  |  |  |  |  |  |  |
| Item | Foxconn P/N | Orig._Usage | New_Usage | Part Description | Manufacturer Full Name | Manufacturer P/N | RoHS | Location | Sheet |
| 1 | 620106200-015-G | 41 | 37 | CAP,10nF,+/-10%,X7R,16V,G,SMD0402 | MURATA ELEC. NORTH AMERICA | GRM155R71C103KA01D | G | (-)C2092,C2120,C2121,C2122 | PWA BOM |
|  | 620106200-026-G |  |  | CAP,10nF,+/-10%,X7R,16V,G,SMD0402 | SAMSUNG SEMICONDUCTOR | CL05B103KO5NNNC |  |  | PWA BOM |
|  | 620106200-023-G |  |  | CAP,10nF,+/-10%,X7R,16V,G,SMD0402 | TAIYO ELECTRIC IND.CO.LTD | EMK105B7103KV-F |  |  | PWA BOM |
| 2 | 320242200-230-G | 0 | 8 | IC,PWM Controller,ISL68137IRAZ-T,G,QFN-48,SMD | INTERSIL CORPORATION | ISL68137IRAZ-T | G | (+)PBMU1,PBFU1,PBEU1,PBAU1,PAMU1,PAFU1,PAEU1,PAAU1 | PWA BOM |
| 3 | 610114U00-017-G | 25 | 21 | RES,3.3KOhm,+/-1%,1/16W,G,SMD0402 | KOA SPEER ELECTRONICS, INC. | RK73H1ETTP3301F | G | (-)R1425,R1516,R1517,R1518 | PWA BOM |
|  | 610114U00-024-G |  |  | RES,3.3KOhm,+/-1%,1/16W,G,SMD0402 | PANASONIC INDUSTRIAL CO.,LTD. | ERJ2RKF3301X |  |  | PWA BOM |
|  | 610114U00-011-G |  |  | RES,3.3KOhm,+/-1%,1/16W,G,SMD0402 | YAGEO CORPORATION COMPONENT | RC0402FR-073K3L |  |  | PWA BOM |
|  | 610114U00-044-G |  |  | RES,3.3KOhm,+/-1%,1/16W,G,SMD0402 | TA-I TECHNOLOGY CO., LTD. | RM04FTN3301 |  |  | PWA BOM |
| 4 | 620108100-015-G | 2 | 0 | CAP,15pF,+/-5%,NPO(C0G),50V,G,SMD0402 | MURATA ELEC. NORTH AMERICA | GRM1555C1H150J | G | (-)C2008,C2010 | PWA BOM |
| 5 | ISL68137IRAZ-GG04 | 8 | 0 | IC,PWM Controller,ISL68137IRAZ-T,G,QFN-48,SMD | INTERSIL CORPORATION | ISL68137IRAZ-GG04 | G | (-)PBMU1,PBFU1,PBEU1,PBAU1,PAMU1,PAFU1,PAEU1,PAAU1 | PWA BOM |
| OOOOOOOOOOOOOOOOOOOOOOOOOOOOOOOOOOOOOOOOOOOOOOOOOOOOOOOOOOOOOOOOOOOOOOOOOOOOOOOOOOOOOOOOOO | OOOOOOOOOOOOOOOOOOOOOOOOOOOOOOOOOOOOOOOOOOOOOOOOOOOOOOOOOOOOOOOOOOOOOOOOOOOOOOOOOOOOOOOOOO | OOOOOOOOOOOOOOOOOOOOOOOOOOOOOOOOOOOOOOOOOOOOOOOOOOOOOOOOOOOOOOOOOOOOOOOOOOOOOOOOOOOOOOOOOO | OOOOOOOOOOOOOOOOOOOOOOOOOOOOOOOOOOOOOOOOOOOOOOOOOOOOOOOOOOOOOOOOOOOOOOOOOOOOOOOOOOOOOOOOOO | OOOOOOOOOOOOOOOOOOOOOOOOOOOOOOOOOOOOOOOOOOOOOOOOOOOOOOOOOOOOOOOOOOOOOOOOOOOOOOOOOOOOOOOOOO | OOOOOOOOOOOOOOOOOOOOOOOOOOOOOOOOOOOOOOOOOOOOOOOOOOOOOOOOOOOOOOOOOOOOOOOOOOOOOOOOOOOOOOOOOO | OOOOOOOOOOOOOOOOOOOOOOOOOOOOOOOOOOOOOOOOOOOOOOOOOOOOOOOOOOOOOOOOOOOOOOOOOOOOOOOOOOOOOOOOOO | OOOOOOOOOOOOOOOOOOOOOOOOOOOOOOOOOOOOOOOOOOOOOOOOOOOOOOOOOOOOOOOOOOOOOOOOOOOOOOOOOOOOOOOOOO | OOOOOOOOOOOOOOOOOOOOOOOOOOOOOOOOOOOOOOOOOOOOOOOOOOOOOOOOOOOOOOOOOOOOOOOOOOOOOOOOOOOOOOOOOO |  |
| TLA Parts Change |  |  |  |  |  |  |  |  |  |
| Item | Foxconn P/N | Qty | Part Description | Manufacturer Full Name | Manufacturer P/N | RoHS | Location | Remark |  |
| BOM Change List Date:Thu Sep 28 18:52:32 GMT+08:00 2017 |  |  |  |  |  |  |  |  |  |
| New BOM file : C:\<user>\ZAIUS-MB-PVT-HW-EBOM-X04-20170928.xls |  |  |  |  |  |  |  |  |  |
| Old BOM file : C:\<user>\ZAIUS-MB-PVT-HW-EBOM-X04-20170830.xls |  |  |  |  |  |  |  |  |  |
| ##### Add Parts |  |  |  |  |  |  |  |  |  |
| Item | Location | Qty | Foxconn P/N | Part Description | Manufacturer Full Name | Manufacturer P/N | RoHS | Sheet |  |
| ##### Remove Parts |  |  |  |  |  |  |  |  |  |
| Item | Location | Qty | Foxconn P/N | Part Description | Manufacturer Full Name | Manufacturer P/N | RoHS | Sheet |  |
| 1 | C2092,C2120,C2121,C2122 | 4 | 620106200-015-G | CAP,10nF,+/-10%,X7R,16V,G,SMD0402 | MURATA ELEC. NORTH AMERICA | GRM155R71C103KA01D | Y | PWA BOM |  |
| 2 | C2008,C2010 | 2 | 620108100-015-G | CAP,15pF,+/-5%,NPO(C0G),50V,G,SMD0402 | MURATA ELEC. NORTH AMERICA | GRM1555C1H150J | N | PWA BOM |  |
| 3 | R1425,R1516,R1517,R1518 | 4 | 610114U00-017-G | RES,3.3KOhm,+/-1%,1/16W,G,SMD0402 | KOA SPEER ELECTRONICS, INC. | RK73H1ETTP3301F | N | PWA BOM |  |
| ##### Change Parts |  |  |  |  |  |  |  |  |  |
| Item | Location | Qty | Foxconn P/N | Part Description | Manufacturer Full Name | Manufacturer P/N | RoHS | Sheet | Remark |
| 1 | U5 | 1 | UCD90160RGCR-C13 | IC,Power Controller,UCD90160RGCR,G,VQFN-64,SMD | TEXAS INSTRUMENTS | UCD90160RGCR-C13 |  | PWA BOM | In New BOM |
|  | U5 | 1 | 320241C00-183-G | IC,Power Controller,UCD90160RGCR,G,VQFN-64,SMD | TEXAS INSTRUMENTS | UCD90160RGCR |  | PWA BOM | In Old BOM |
| ##### Change Revision |  |  |  |  |  |  |  |  |  |
| Sheet | REV OF BOM | CUSTOMER | CUSTOMER P/N | PWA PN | PWA DESCRIPTION | PWA REV | DATE | Remark |  |
| OOOOOOOOOOOOOOOOOOOOOOOOOOOOOOOOOOOOOOOOOOOOOOOOOOOOOOOOOOOOOOOOOOOOOOOOOOOOOOOOOOOOOOOOOO | OOOOOOOOOOOOOOOOOOOOOOOOOOOOOOOOOOOOOOOOOOOOOOOOOOOOOOOOOOOOOOOOOOOOOOOOOOOOOOOOOOOOOOOOOO | OOOOOOOOOOOOOOOOOOOOOOOOOOOOOOOOOOOOOOOOOOOOOOOOOOOOOOOOOOOOOOOOOOOOOOOOOOOOOOOOOOOOOOOOOO | OOOOOOOOOOOOOOOOOOOOOOOOOOOOOOOOOOOOOOOOOOOOOOOOOOOOOOOOOOOOOOOOOOOOOOOOOOOOOOOOOOOOOOOOOO | OOOOOOOOOOOOOOOOOOOOOOOOOOOOOOOOOOOOOOOOOOOOOOOOOOOOOOOOOOOOOOOOOOOOOOOOOOOOOOOOOOOOOOOOOO | OOOOOOOOOOOOOOOOOOOOOOOOOOOOOOOOOOOOOOOOOOOOOOOOOOOOOOOOOOOOOOOOOOOOOOOOOOOOOOOOOOOOOOOOOO | OOOOOOOOOOOOOOOOOOOOOOOOOOOOOOOOOOOOOOOOOOOOOOOOOOOOOOOOOOOOOOOOOOOOOOOOOOOOOOOOOOOOOOOOOO | OOOOOOOOOOOOOOOOOOOOOOOOOOOOOOOOOOOOOOOOOOOOOOOOOOOOOOOOOOOOOOOOOOOOOOOOOOOOOOOOOOOOOOOOOO | OOOOOOOOOOOOOOOOOOOOOOOOOOOOOOOOOOOOOOOOOOOOOOOOOOOOOOOOOOOOOOOOOOOOOOOOOOOOOOOOOOOOOOOOOO | OOOOOOOOOOOOOOOOOOOOOOOOOOOOOOOOOOOOOOOOOOOOOOOOOOOOOOOOOOOOOOOOOOOOOOOOOOOOOOOOOOOOOOOOOO |
| Second Source Change |  |  |  |  |  |  |  |  |  |
| Item | Location | Change Type | Foxconn P/N | Part Description | Manufacturer Full Name | Manufacturer P/N | RoHS | Sheet |  |
| OOOOOOOOOOOOOOOOOOOOOOOOOOOOOOOOOOOOOOOOOOOOOOOOOOOOOOOOOOOOOOOOOOOOOOOOOOOOOOOOOOOOOOOOOO | OOOOOOOOOOOOOOOOOOOOOOOOOOOOOOOOOOOOOOOOOOOOOOOOOOOOOOOOOOOOOOOOOOOOOOOOOOOOOOOOOOOOOOOOOO | OOOOOOOOOOOOOOOOOOOOOOOOOOOOOOOOOOOOOOOOOOOOOOOOOOOOOOOOOOOOOOOOOOOOOOOOOOOOOOOOOOOOOOOOOO | OOOOOOOOOOOOOOOOOOOOOOOOOOOOOOOOOOOOOOOOOOOOOOOOOOOOOOOOOOOOOOOOOOOOOOOOOOOOOOOOOOOOOOOOOO | OOOOOOOOOOOOOOOOOOOOOOOOOOOOOOOOOOOOOOOOOOOOOOOOOOOOOOOOOOOOOOOOOOOOOOOOOOOOOOOOOOOOOOOOOO | OOOOOOOOOOOOOOOOOOOOOOOOOOOOOOOOOOOOOOOOOOOOOOOOOOOOOOOOOOOOOOOOOOOOOOOOOOOOOOOOOOOOOOOOOO | OOOOOOOOOOOOOOOOOOOOOOOOOOOOOOOOOOOOOOOOOOOOOOOOOOOOOOOOOOOOOOOOOOOOOOOOOOOOOOOOOOOOOOOOOO | OOOOOOOOOOOOOOOOOOOOOOOOOOOOOOOOOOOOOOOOOOOOOOOOOOOOOOOOOOOOOOOOOOOOOOOOOOOOOOOOOOOOOOOOOO | OOOOOOOOOOOOOOOOOOOOOOOOOOOOOOOOOOOOOOOOOOOOOOOOOOOOOOOOOOOOOOOOOOOOOOOOOOOOOOOOOOOOOOOOOO | OOOOOOOOOOOOOOOOOOOOOOOOOOOOOOOOOOOOOOOOOOOOOOOOOOOOOOOOOOOOOOOOOOOOOOOOOOOOOOOOOOOOOOOOOO |
| Master Materials Change |  |  |  |  |  |  |  |  |  |
| Item | Foxconn P/N | Orig._Usage | New_Usage | Part Description | Manufacturer Full Name | Manufacturer P/N | RoHS | Location | Sheet |
| 1 | 620106200-015-G | 41 | 37 | CAP,10nF,+/-10%,X7R,16V,G,SMD0402 | MURATA ELEC. NORTH AMERICA | GRM155R71C103KA01D | Y | (-)C2092,C2120,C2121,C2122 | PWA BOM |
| 2 | 610114U00-017-G | 25 | 21 | RES,3.3KOhm,+/-1%,1/16W,G,SMD0402 | KOA SPEER ELECTRONICS, INC. | RK73H1ETTP3301F | N | (-)R1425,R1516,R1517,R1518 | PWA BOM |
| 3 | UCD90160RGCR-C13 | 0 | 1 | IC,Power Controller,UCD90160RGCR,G,VQFN-64,SMD | TEXAS INSTRUMENTS | UCD90160RGCR-C13 |  | (+)U5 | PWA BOM |
| 4 | 620108100-015-G | 2 | 0 | CAP,15pF,+/-5%,NPO(C0G),50V,G,SMD0402 | MURATA ELEC. NORTH AMERICA | GRM1555C1H150J | N | (-)C2008,C2010 | PWA BOM |
| 5 | 320241C00-183-G | 1 | 0 | IC,Power Controller,UCD90160RGCR,G,VQFN-64,SMD | TEXAS INSTRUMENTS | UCD90160RGCR |  | (-)U5 | PWA BOM |
| OOOOOOOOOOOOOOOOOOOOOOOOOOOOOOOOOOOOOOOOOOOOOOOOOOOOOOOOOOOOOOOOOOOOOOOOOOOOOOOOOOOOOOOOOO | OOOOOOOOOOOOOOOOOOOOOOOOOOOOOOOOOOOOOOOOOOOOOOOOOOOOOOOOOOOOOOOOOOOOOOOOOOOOOOOOOOOOOOOOOO | OOOOOOOOOOOOOOOOOOOOOOOOOOOOOOOOOOOOOOOOOOOOOOOOOOOOOOOOOOOOOOOOOOOOOOOOOOOOOOOOOOOOOOOOOO | OOOOOOOOOOOOOOOOOOOOOOOOOOOOOOOOOOOOOOOOOOOOOOOOOOOOOOOOOOOOOOOOOOOOOOOOOOOOOOOOOOOOOOOOOO | OOOOOOOOOOOOOOOOOOOOOOOOOOOOOOOOOOOOOOOOOOOOOOOOOOOOOOOOOOOOOOOOOOOOOOOOOOOOOOOOOOOOOOOOOO | OOOOOOOOOOOOOOOOOOOOOOOOOOOOOOOOOOOOOOOOOOOOOOOOOOOOOOOOOOOOOOOOOOOOOOOOOOOOOOOOOOOOOOOOOO | OOOOOOOOOOOOOOOOOOOOOOOOOOOOOOOOOOOOOOOOOOOOOOOOOOOOOOOOOOOOOOOOOOOOOOOOOOOOOOOOOOOOOOOOOO | OOOOOOOOOOOOOOOOOOOOOOOOOOOOOOOOOOOOOOOOOOOOOOOOOOOOOOOOOOOOOOOOOOOOOOOOOOOOOOOOOOOOOOOOOO | OOOOOOOOOOOOOOOOOOOOOOOOOOOOOOOOOOOOOOOOOOOOOOOOOOOOOOOOOOOOOOOOOOOOOOOOOOOOOOOOOOOOOOOOOO |  |
| TLA Parts Change |  |  |  |  |  |  |  |  |  |
| Item | Foxconn P/N | Qty | Part Description | Manufacturer Full Name | Manufacturer P/N | RoHS | Location | Remark |  |
| BOM Change List Date:Fri Sep 29 16:53:09 GMT+08:00 2017 |  |  |  |  |  |  |  |  |  |
| New BOM file : E:\barreleye g2\0928\ZAIUS-MB-PVT-X04-BOM_X25_20170929.xls |  |  |  |  |  |  |  |  |  |
| Old BOM file : E:\barreleye g2\0928\ZAIUS0913.xls |  |  |  |  |  |  |  |  |  |
| ##### Add Parts |  |  |  |  |  |  |  |  |  |
| Item | Location | Qty | Foxconn P/N | Part Description | Manufacturer Full Name | Manufacturer P/N | RoHS | Sheet |  |
| ##### Remove Parts |  |  |  |  |  |  |  |  |  |
| Item | Location | Qty | Foxconn P/N | Part Description | Manufacturer Full Name | Manufacturer P/N | RoHS | Sheet |  |
| 1 | C2092,C2120,C2121,C2122 | 4 | 620106200-015-G | CAP,10nF,+/-10%,X7R,16V,G,SMD0402 | MURATA ELEC. NORTH AMERICA | GRM155R71C103KA01D | G | PWA BOM |  |
|  |  |  | 620106200-026-G | CAP,10nF,+/-10%,X7R,16V,G,SMD0402 | SAMSUNG SEMICONDUCTOR | CL05B103KO5NNNC | G | PWA BOM |  |
|  |  |  | 620106200-023-G | CAP,10nF,+/-10%,X7R,16V,G,SMD0402 | TAIYO ELECTRIC IND.CO.LTD | EMK105B7103KV-F | G | PWA BOM |  |
| 2 | C2008,C2010 | 2 | 620108100-015-G | CAP,15pF,+/-5%,NPO(C0G),50V,G,SMD0402 | MURATA ELEC. NORTH AMERICA | GRM1555C1H150J | G | PWA BOM |  |
| 3 | R1425,R1516,R1517,R1518 | 4 | 610114U00-017-G | RES,3.3KOhm,+/-1%,1/16W,G,SMD0402 | KOA SPEER ELECTRONICS, INC. | RK73H1ETTP3301F | G | PWA BOM |  |
|  |  |  | 610114U00-024-G | RES,3.3KOhm,+/-1%,1/16W,G,SMD0402 | PANASONIC INDUSTRIAL CO.,LTD. | ERJ2RKF3301X | G | PWA BOM |  |
|  |  |  | 610114U00-011-G | RES,3.3KOhm,+/-1%,1/16W,G,SMD0402 | YAGEO CORPORATION COMPONENT | RC0402FR-073K3L | G | PWA BOM |  |
|  |  |  | 610114U00-044-G | RES,3.3KOhm,+/-1%,1/16W,G,SMD0402 | TA-I TECHNOLOGY CO., LTD. | RM04FTN3301 | G | PWA BOM |  |
| ##### Change Parts |  |  |  |  |  |  |  |  |  |
| Item | Location | Qty | Foxconn P/N | Part Description | Manufacturer Full Name | Manufacturer P/N | RoHS | Sheet | Remark |
| 1 | PHAR9,PALR16,PBLR18,PBNR21,PANR21,PBMR40,PBFR40,PBER40,PBAR40,PAMR40,PAFR40,PAER40,PAAR40,R865,R866,R1155,R1169,R1181,R1193,R1205,R1217,R1258,R1329,R1333,R1334,R1335,R1498,R1500,R1729,R1733,R1737,R1741,R1824 | 33 | 61010L300-017-G | RES,1KOhm,+/-1%,1/16W,G,SMD0402 | KOA SPEER ELECTRONICS, INC. | RK73H1ETTP1001F | G | PWA BOM | In New BOM |
|  |  |  | 61010L300-029-G | RES,1KOhm,+/-1%,1/16W,G,SMD0402 | VISHAY ENTER TECHNO LOGY.INC | CRCW04021K00FKED | G | PWA BOM | In New BOM |
|  |  |  | 61010L300-024-G | RES,1KOhm,+/-1%,1/16W,G,SMD0402 | PANASONIC INDUSTRIAL CO.,LTD. | ERJ2RKF1001X | G | PWA BOM | In New BOM |
|  | PHAR9,PALR16,PBLR18,PBNR21,PANR21,PBMR40,PBFR40,PBER40,PBAR40,PAMR40,PAFR40,PAER40,PAAR40,R865,R866,R1155,R1169,R1181,R1193,R1205,R1217,R1258,R1329,R1333,R1334,R1335,R1498,R1500,R1729,R1733,R1737,R1741,R1824 | 33 | 61010L300-017-G | RES,1KOhm,+/-1%,1/16W,G,SMD0402 | KOA SPEER ELECTRONICS, INC. | RK73H1ETTP1001F | G | PWA BOM | In Old BOM |
|  |  |  | 61010L300-029-G | RES,1KOhm,+/-1%,1/16W,G,SMD0402 | VISHAY ENTER TECHNO LOGY.INC | CRCW04021K00FKED | G | PWA BOM | In Old BOM |
|  |  |  | 610151600-024-G | RES,thick film,1KOhm,+/-1%,1/10W,SMD0402,G | PANASONIC INDUSTRIAL CO.,LTD. | ERJ2RKF1001X | G | PWA BOM | In Old BOM |
| 2 | PCIE2,PCIE3,PCIE4 | 3 | 10061913-103HLF | CONN,PCIE-16X,V/T,Bla,1mm,30u,G,SMD-164 | FCI CONNECTORS HONGKONG LTD. | 10061913-103HLF | G | PWA BOM | In New BOM |
|  |  |  | 340321600-278-G | CONN,PCIE-16X,V/T,Bla,1mm,30u,G,SMD-164 | TYCO ELECTRONICS CORPORATION | 2041366-9 | G | PWA BOM | In New BOM |
|  | PCIE2,PCIE3,PCIE4 | 3 | 10061913-103HLF | CONN,PCIE-16X,V/T,Bla,1mm,30u,G,SMD-164 | FCI CONNECTORS HONGKONG LTD. | 10061913-103HLF | G | PWA BOM | In Old BOM |
|  |  |  | 2041366-9 | CONN,PCIE-16X,V/T,Bla,1mm,30u,G,SMD-164 | TYCO ELECTRONICS CORPORATION | 2041366-9 | G | PWA BOM | In Old BOM |
| 3 | R1492 | 1 | 610118800-017-G | RES,499KOhm,+/-1%,1/8W,G,SMD0805 | KOA SPEER ELECTRONICS, INC. | RK73H2ATTD4993F | G | PWA BOM | In New BOM |
|  |  |  | 610118800-024-G | RES,499KOhm,+/-1%,1/8W,G,SMD0805 | PANASONIC INDUSTRIAL CO.,LTD. | ERJ6ENF4993V | G | PWA BOM | In New BOM |
|  |  |  | 610118800-011-G | RES,499KOhm,+/-1%,1/8W,G,SMD0805 | YAGEO CORPORATION COMPONENT | RC0805FR-07499KL | G | PWA BOM | In New BOM |
|  | R1492 | 1 | 610118800-017-G | RES,499KOhm,+/-1%,1/8W,G,SMD0805 | KOA SPEER ELECTRONICS, INC. | RK73H2ATTD4993F | G | PWA BOM | In Old BOM |
|  |  |  | 610118800-024-G | RES,499KOhm,+/-1%,1/8W,G,SMD0805 | PANASONIC INDUSTRIAL CO.,LTD. | ERJ6ENF4993V | G | PWA BOM | In Old BOM |
|  |  |  | RC0805FR-07499KL | RES,499KOhm,+/-1%,1/8W,G,SMD0805 | YAGEO CORPORATION COMPONENT | RC0805FR-07499KL | G | PWA BOM | In Old BOM |
| 4 | PBMJ1,PBEJ1,PBAJ1,PAMJ1,PAEJ1,PAAJ1 | 6 | 340634U00-600-G | CONN,Pin Header,2X3,V/T,Bla,2.54mm,30u,G,SMD-6 | FOXCONN TECHNOLOGY CO.,LTD. | HS1103H-RN | G | PWA BOM | In New BOM |
|  |  |  | 34068GL00-317-G | CONN,Header,Pin Header,2X3,V/T,Bla,2.54mm,30u,SMD-6 | MOLEX INCORPORATED | 015-91-6063 | G | PWA BOM | In New BOM |
|  |  |  | 3406AY700-637-G | Header&Socket Connector,11006A5807,Pin Header,6,SMD,NY6T,2.54mm,30u",Black,G | LONG SHOUNG CO.,LTD. | 11006A5807 | G | PWA BOM | In New BOM |
|  | PBMJ1,PBEJ1,PBAJ1,PAMJ1,PAEJ1,PAAJ1 | 6 | 340634U00-600-G | CONN,Pin Header,2X3,V/T,Bla,2.54mm,30u,G,SMD-6 | FOXCONN TECHNOLOGY CO.,LTD. | HS1103H-RN | G | PWA BOM | In Old BOM |
|  |  |  | 34065EA00-317-G | CONN,Header,Pin Header,2X3,V/T,Bla,2.54mm,30u,G,SMD-6 | MOLEX INCORPORATED | 015-91-3060 | G | PWA BOM | In Old BOM |
|  |  |  | 3406AY700-637-G | Header&Socket Connector,11006A5807,Pin Header,6,SMD,NY6T,2.54mm,30u",Black,G | LONG SHOUNG CO.,LTD. | 11006A5807 | G | PWA BOM | In Old BOM |
| 5 | PCB | 1 | 0101FBQ00-000-G | PCB | GCE | 0101FBQ00-000-G | G | PWA BOM | In New BOM |
|  | PCB | 1 | 0101FBQ00-000-G | PCB,Zaius-MB PVT-X04,OSP,Gre,22L,22.20*13.00,G | GOLD CIRCUIT ELECTRONICS LTD. | 0101FBQ00-000-G | G | PWA BOM | In Old BOM |
| 6 | PBMU1,PBFU1,PBEU1,PBAU1,PAMU1,PAFU1,PAEU1,PAAU1 | 8 | 320242200-230-G | IC,PWM Controller,ISL68137IRAZ-T,G,QFN-48,SMD | INTERSIL CORPORATION | ISL68137IRAZ-T | G | PWA BOM | In New BOM |
|  | PBMU1,PBFU1,PBEU1,PBAU1,PAMU1,PAFU1,PAEU1,PAAU1 | 8 | ISL68137IRAZ-GG04 | IC,PWM Controller,ISL68137IRAZ-T,G,QFN-48,SMD | INTERSIL CORPORATION | ISL68137IRAZ-GG04 | G | PWA BOM | In Old BOM |
| ##### Change Revision |  |  |  |  |  |  |  |  |  |
| Sheet | REV OF BOM | CUSTOMER | CUSTOMER P/N | PWA PN | PWA DESCRIPTION | PWA REV | DATE | Remark |  |
| OOOOOOOOOOOOOOOOOOOOOOOOOOOOOOOOOOOOOOOOOOOOOOOOOOOOOOOOOOOOOOOOOOOOOOOOOOOOOOOOOOOOOOOOOO | OOOOOOOOOOOOOOOOOOOOOOOOOOOOOOOOOOOOOOOOOOOOOOOOOOOOOOOOOOOOOOOOOOOOOOOOOOOOOOOOOOOOOOOOOO | OOOOOOOOOOOOOOOOOOOOOOOOOOOOOOOOOOOOOOOOOOOOOOOOOOOOOOOOOOOOOOOOOOOOOOOOOOOOOOOOOOOOOOOOOO | OOOOOOOOOOOOOOOOOOOOOOOOOOOOOOOOOOOOOOOOOOOOOOOOOOOOOOOOOOOOOOOOOOOOOOOOOOOOOOOOOOOOOOOOOO | OOOOOOOOOOOOOOOOOOOOOOOOOOOOOOOOOOOOOOOOOOOOOOOOOOOOOOOOOOOOOOOOOOOOOOOOOOOOOOOOOOOOOOOOOO | OOOOOOOOOOOOOOOOOOOOOOOOOOOOOOOOOOOOOOOOOOOOOOOOOOOOOOOOOOOOOOOOOOOOOOOOOOOOOOOOOOOOOOOOOO | OOOOOOOOOOOOOOOOOOOOOOOOOOOOOOOOOOOOOOOOOOOOOOOOOOOOOOOOOOOOOOOOOOOOOOOOOOOOOOOOOOOOOOOOOO | OOOOOOOOOOOOOOOOOOOOOOOOOOOOOOOOOOOOOOOOOOOOOOOOOOOOOOOOOOOOOOOOOOOOOOOOOOOOOOOOOOOOOOOOOO | OOOOOOOOOOOOOOOOOOOOOOOOOOOOOOOOOOOOOOOOOOOOOOOOOOOOOOOOOOOOOOOOOOOOOOOOOOOOOOOOOOOOOOOOOO | OOOOOOOOOOOOOOOOOOOOOOOOOOOOOOOOOOOOOOOOOOOOOOOOOOOOOOOOOOOOOOOOOOOOOOOOOOOOOOOOOOOOOOOOOO |
| Second Source Change |  |  |  |  |  |  |  |  |  |
| Item | Location | Change Type | Foxconn P/N | Part Description | Manufacturer Full Name | Manufacturer P/N | RoHS | Sheet |  |
| 1 | PHAR9,PALR16,PBLR18,PBNR21,PANR21,PBMR40,PBFR40,PBER40,PBAR40,PAMR40,PAFR40,PAER40,PAAR40,R865,R866,R1155,R1169,R1181,R1193,R1205,R1217,R1258,R1329,R1333,R1334,R1335,R1498,R1500,R1729,R1733,R1737,R1741,R1824 |  | 61010L300-017-G | RES,1KOhm,+/-1%,1/16W,G,SMD0402 | KOA SPEER ELECTRONICS, INC. | RK73H1ETTP1001F | G | PWA BOM |  |
|  |  | NO | 61010L300-029-G | RES,1KOhm,+/-1%,1/16W,G,SMD0402 | VISHAY ENTER TECHNO LOGY.INC | CRCW04021K00FKED | G | PWA BOM |  |
|  |  | ADD | 61010L300-024-G | RES,1KOhm,+/-1%,1/16W,G,SMD0402 | PANASONIC INDUSTRIAL CO.,LTD. | ERJ2RKF1001X | G | PWA BOM |  |
|  |  | Delete | 610151600-024-G | RES,thick film,1KOhm,+/-1%,1/10W,SMD0402,G | PANASONIC INDUSTRIAL CO.,LTD. | ERJ2RKF1001X | G | PWA BOM |  |
| 2 | PCIE2,PCIE3,PCIE4 |  | 10061913-103HLF | CONN,PCIE-16X,V/T,Bla,1mm,30u,G,SMD-164 | FCI CONNECTORS HONGKONG LTD. | 10061913-103HLF | G | PWA BOM |  |
|  |  | ADD | 340321600-278-G | CONN,PCIE-16X,V/T,Bla,1mm,30u,G,SMD-164 | TYCO ELECTRONICS CORPORATION | 2041366-9 | G | PWA BOM |  |
|  |  | Delete | 2041366-9 | CONN,PCIE-16X,V/T,Bla,1mm,30u,G,SMD-164 | TYCO ELECTRONICS CORPORATION | 2041366-9 | G | PWA BOM |  |
| 3 | R1492 |  | 610118800-017-G | RES,499KOhm,+/-1%,1/8W,G,SMD0805 | KOA SPEER ELECTRONICS, INC. | RK73H2ATTD4993F | G | PWA BOM |  |
|  |  | NO | 610118800-024-G | RES,499KOhm,+/-1%,1/8W,G,SMD0805 | PANASONIC INDUSTRIAL CO.,LTD. | ERJ6ENF4993V | G | PWA BOM |  |
|  |  | ADD | 610118800-011-G | RES,499KOhm,+/-1%,1/8W,G,SMD0805 | YAGEO CORPORATION COMPONENT | RC0805FR-07499KL | G | PWA BOM |  |
|  |  | Delete | RC0805FR-07499KL | RES,499KOhm,+/-1%,1/8W,G,SMD0805 | YAGEO CORPORATION COMPONENT | RC0805FR-07499KL | G | PWA BOM |  |
| 4 | PBMJ1,PBEJ1,PBAJ1,PAMJ1,PAEJ1,PAAJ1 |  | 340634U00-600-G | CONN,Pin Header,2X3,V/T,Bla,2.54mm,30u,G,SMD-6 | FOXCONN TECHNOLOGY CO.,LTD. | HS1103H-RN | G | PWA BOM |  |
|  |  | ADD | 34068GL00-317-G | CONN,Header,Pin Header,2X3,V/T,Bla,2.54mm,30u,SMD-6 | MOLEX INCORPORATED | 015-91-6063 | G | PWA BOM |  |
|  |  | NO | 3406AY700-637-G | Header&Socket Connector,11006A5807,Pin Header,6,SMD,NY6T,2.54mm,30u",Black,G | LONG SHOUNG CO.,LTD. | 11006A5807 | G | PWA BOM |  |
|  |  | Delete | 34065EA00-317-G | CONN,Header,Pin Header,2X3,V/T,Bla,2.54mm,30u,G,SMD-6 | MOLEX INCORPORATED | 015-91-3060 | G | PWA BOM |  |
| OOOOOOOOOOOOOOOOOOOOOOOOOOOOOOOOOOOOOOOOOOOOOOOOOOOOOOOOOOOOOOOOOOOOOOOOOOOOOOOOOOOOOOOOOO | OOOOOOOOOOOOOOOOOOOOOOOOOOOOOOOOOOOOOOOOOOOOOOOOOOOOOOOOOOOOOOOOOOOOOOOOOOOOOOOOOOOOOOOOOO | OOOOOOOOOOOOOOOOOOOOOOOOOOOOOOOOOOOOOOOOOOOOOOOOOOOOOOOOOOOOOOOOOOOOOOOOOOOOOOOOOOOOOOOOOO | OOOOOOOOOOOOOOOOOOOOOOOOOOOOOOOOOOOOOOOOOOOOOOOOOOOOOOOOOOOOOOOOOOOOOOOOOOOOOOOOOOOOOOOOOO | OOOOOOOOOOOOOOOOOOOOOOOOOOOOOOOOOOOOOOOOOOOOOOOOOOOOOOOOOOOOOOOOOOOOOOOOOOOOOOOOOOOOOOOOOO | OOOOOOOOOOOOOOOOOOOOOOOOOOOOOOOOOOOOOOOOOOOOOOOOOOOOOOOOOOOOOOOOOOOOOOOOOOOOOOOOOOOOOOOOOO | OOOOOOOOOOOOOOOOOOOOOOOOOOOOOOOOOOOOOOOOOOOOOOOOOOOOOOOOOOOOOOOOOOOOOOOOOOOOOOOOOOOOOOOOOO | OOOOOOOOOOOOOOOOOOOOOOOOOOOOOOOOOOOOOOOOOOOOOOOOOOOOOOOOOOOOOOOOOOOOOOOOOOOOOOOOOOOOOOOOOO | OOOOOOOOOOOOOOOOOOOOOOOOOOOOOOOOOOOOOOOOOOOOOOOOOOOOOOOOOOOOOOOOOOOOOOOOOOOOOOOOOOOOOOOOOO | OOOOOOOOOOOOOOOOOOOOOOOOOOOOOOOOOOOOOOOOOOOOOOOOOOOOOOOOOOOOOOOOOOOOOOOOOOOOOOOOOOOOOOOOOO |
| Master Materials Change |  |  |  |  |  |  |  |  |  |
| Item | Foxconn P/N | Orig._Usage | New_Usage | Part Description | Manufacturer Full Name | Manufacturer P/N | RoHS | Location | Sheet |
| 1 | 620106200-015-G | 41 | 37 | CAP,10nF,+/-10%,X7R,16V,G,SMD0402 | MURATA ELEC. NORTH AMERICA | GRM155R71C103KA01D | G | (-)C2092,C2120,C2121,C2122 | PWA BOM |
|  | 620106200-026-G |  |  | CAP,10nF,+/-10%,X7R,16V,G,SMD0402 | SAMSUNG SEMICONDUCTOR | CL05B103KO5NNNC |  |  | PWA BOM |
|  | 620106200-023-G |  |  | CAP,10nF,+/-10%,X7R,16V,G,SMD0402 | TAIYO ELECTRIC IND.CO.LTD | EMK105B7103KV-F |  |  | PWA BOM |
| 2 | 320242200-230-G | 0 | 8 | IC,PWM Controller,ISL68137IRAZ-T,G,QFN-48,SMD | INTERSIL CORPORATION | ISL68137IRAZ-T | G | (+)PBMU1,PBFU1,PBEU1,PBAU1,PAMU1,PAFU1,PAEU1,PAAU1 | PWA BOM |
| 3 | 610114U00-017-G | 25 | 21 | RES,3.3KOhm,+/-1%,1/16W,G,SMD0402 | KOA SPEER ELECTRONICS, INC. | RK73H1ETTP3301F | G | (-)R1425,R1516,R1517,R1518 | PWA BOM |
|  | 610114U00-024-G |  |  | RES,3.3KOhm,+/-1%,1/16W,G,SMD0402 | PANASONIC INDUSTRIAL CO.,LTD. | ERJ2RKF3301X |  |  | PWA BOM |
|  | 610114U00-011-G |  |  | RES,3.3KOhm,+/-1%,1/16W,G,SMD0402 | YAGEO CORPORATION COMPONENT | RC0402FR-073K3L |  |  | PWA BOM |
|  | 610114U00-044-G |  |  | RES,3.3KOhm,+/-1%,1/16W,G,SMD0402 | TA-I TECHNOLOGY CO., LTD. | RM04FTN3301 |  |  | PWA BOM |
| 4 | 620108100-015-G | 2 | 0 | CAP,15pF,+/-5%,NPO(C0G),50V,G,SMD0402 | MURATA ELEC. NORTH AMERICA | GRM1555C1H150J | G | (-)C2008,C2010 | PWA BOM |
| 5 | ISL68137IRAZ-GG04 | 8 | 0 | IC,PWM Controller,ISL68137IRAZ-T,G,QFN-48,SMD | INTERSIL CORPORATION | ISL68137IRAZ-GG04 | G | (-)PBMU1,PBFU1,PBEU1,PBAU1,PAMU1,PAFU1,PAEU1,PAAU1 | PWA BOM |
| OOOOOOOOOOOOOOOOOOOOOOOOOOOOOOOOOOOOOOOOOOOOOOOOOOOOOOOOOOOOOOOOOOOOOOOOOOOOOOOOOOOOOOOOOO | OOOOOOOOOOOOOOOOOOOOOOOOOOOOOOOOOOOOOOOOOOOOOOOOOOOOOOOOOOOOOOOOOOOOOOOOOOOOOOOOOOOOOOOOOO | OOOOOOOOOOOOOOOOOOOOOOOOOOOOOOOOOOOOOOOOOOOOOOOOOOOOOOOOOOOOOOOOOOOOOOOOOOOOOOOOOOOOOOOOOO | OOOOOOOOOOOOOOOOOOOOOOOOOOOOOOOOOOOOOOOOOOOOOOOOOOOOOOOOOOOOOOOOOOOOOOOOOOOOOOOOOOOOOOOOOO | OOOOOOOOOOOOOOOOOOOOOOOOOOOOOOOOOOOOOOOOOOOOOOOOOOOOOOOOOOOOOOOOOOOOOOOOOOOOOOOOOOOOOOOOOO | OOOOOOOOOOOOOOOOOOOOOOOOOOOOOOOOOOOOOOOOOOOOOOOOOOOOOOOOOOOOOOOOOOOOOOOOOOOOOOOOOOOOOOOOOO | OOOOOOOOOOOOOOOOOOOOOOOOOOOOOOOOOOOOOOOOOOOOOOOOOOOOOOOOOOOOOOOOOOOOOOOOOOOOOOOOOOOOOOOOOO | OOOOOOOOOOOOOOOOOOOOOOOOOOOOOOOOOOOOOOOOOOOOOOOOOOOOOOOOOOOOOOOOOOOOOOOOOOOOOOOOOOOOOOOOOO | OOOOOOOOOOOOOOOOOOOOOOOOOOOOOOOOOOOOOOOOOOOOOOOOOOOOOOOOOOOOOOOOOOOOOOOOOOOOOOOOOOOOOOOOOO |  |
| TLA Parts Change |  |  |  |  |  |  |  |  |  |
| Item | Foxconn P/N | Qty | Part Description | Manufacturer Full Name | Manufacturer P/N | RoHS | Location | Remark |  |
| BOM Change List Date:Fri Oct 20 14:55:34 GMT+08:00 2017 |  |  |  |  |  |  |  |  |  |
| New BOM file : C:\<user>\ZAIUS-MB-PVT-HW-EBOM-X04-20171020.xls |  |  |  |  |  |  |  |  |  |
| Old BOM file : C:\<user>\ZAIUS-MB-PVT-HW-EBOM-X04-20170928.xls |  |  |  |  |  |  |  |  |  |
| ##### Add Parts |  |  |  |  |  |  |  |  |  |
| Item | Location | Qty | Foxconn P/N | Part Description | Manufacturer Full Name | Manufacturer P/N | RoHS | Sheet |  |
| ##### Remove Parts |  |  |  |  |  |  |  |  |  |
| Item | Location | Qty | Foxconn P/N | Part Description | Manufacturer Full Name | Manufacturer P/N | RoHS | Sheet |  |
| ##### Change Parts |  |  |  |  |  |  |  |  |  |
| Item | Location | Qty | Foxconn P/N | Part Description | Manufacturer Full Name | Manufacturer P/N | RoHS | Sheet | Remark |
| 1 | PHAC3 | 1 | 62011DB01-015-G | CAP,1nF,+/-10%,X7R,100V,G,SMD0402 | MURATA ELEC. NORTH AMERICA | GRM155R72A102K | Y | PWA BOM | In New BOM |
|  | PHAC3 | 1 | 620133600-015-G | CAP,1nF,+/-5%,X7R,100V,G,SMD0805 | MURATA ELEC. NORTH AMERICA | GRM219R72A102JA01D |  | PWA BOM | In Old BOM |
| ##### Change Revision |  |  |  |  |  |  |  |  |  |
| Sheet | REV OF BOM | CUSTOMER | CUSTOMER P/N | PWA PN | PWA DESCRIPTION | PWA REV | DATE | Remark |  |
| OOOOOOOOOOOOOOOOOOOOOOOOOOOOOOOOOOOOOOOOOOOOOOOOOOOOOOOOOOOOOOOOOOOOOOOOOOOOOOOOOOOOOOOOOO | OOOOOOOOOOOOOOOOOOOOOOOOOOOOOOOOOOOOOOOOOOOOOOOOOOOOOOOOOOOOOOOOOOOOOOOOOOOOOOOOOOOOOOOOOO | OOOOOOOOOOOOOOOOOOOOOOOOOOOOOOOOOOOOOOOOOOOOOOOOOOOOOOOOOOOOOOOOOOOOOOOOOOOOOOOOOOOOOOOOOO | OOOOOOOOOOOOOOOOOOOOOOOOOOOOOOOOOOOOOOOOOOOOOOOOOOOOOOOOOOOOOOOOOOOOOOOOOOOOOOOOOOOOOOOOOO | OOOOOOOOOOOOOOOOOOOOOOOOOOOOOOOOOOOOOOOOOOOOOOOOOOOOOOOOOOOOOOOOOOOOOOOOOOOOOOOOOOOOOOOOOO | OOOOOOOOOOOOOOOOOOOOOOOOOOOOOOOOOOOOOOOOOOOOOOOOOOOOOOOOOOOOOOOOOOOOOOOOOOOOOOOOOOOOOOOOOO | OOOOOOOOOOOOOOOOOOOOOOOOOOOOOOOOOOOOOOOOOOOOOOOOOOOOOOOOOOOOOOOOOOOOOOOOOOOOOOOOOOOOOOOOOO | OOOOOOOOOOOOOOOOOOOOOOOOOOOOOOOOOOOOOOOOOOOOOOOOOOOOOOOOOOOOOOOOOOOOOOOOOOOOOOOOOOOOOOOOOO | OOOOOOOOOOOOOOOOOOOOOOOOOOOOOOOOOOOOOOOOOOOOOOOOOOOOOOOOOOOOOOOOOOOOOOOOOOOOOOOOOOOOOOOOOO | OOOOOOOOOOOOOOOOOOOOOOOOOOOOOOOOOOOOOOOOOOOOOOOOOOOOOOOOOOOOOOOOOOOOOOOOOOOOOOOOOOOOOOOOOO |
| Second Source Change |  |  |  |  |  |  |  |  |  |
| Item | Location | Change Type | Foxconn P/N | Part Description | Manufacturer Full Name | Manufacturer P/N | RoHS | Sheet |  |
| OOOOOOOOOOOOOOOOOOOOOOOOOOOOOOOOOOOOOOOOOOOOOOOOOOOOOOOOOOOOOOOOOOOOOOOOOOOOOOOOOOOOOOOOOO | OOOOOOOOOOOOOOOOOOOOOOOOOOOOOOOOOOOOOOOOOOOOOOOOOOOOOOOOOOOOOOOOOOOOOOOOOOOOOOOOOOOOOOOOOO | OOOOOOOOOOOOOOOOOOOOOOOOOOOOOOOOOOOOOOOOOOOOOOOOOOOOOOOOOOOOOOOOOOOOOOOOOOOOOOOOOOOOOOOOOO | OOOOOOOOOOOOOOOOOOOOOOOOOOOOOOOOOOOOOOOOOOOOOOOOOOOOOOOOOOOOOOOOOOOOOOOOOOOOOOOOOOOOOOOOOO | OOOOOOOOOOOOOOOOOOOOOOOOOOOOOOOOOOOOOOOOOOOOOOOOOOOOOOOOOOOOOOOOOOOOOOOOOOOOOOOOOOOOOOOOOO | OOOOOOOOOOOOOOOOOOOOOOOOOOOOOOOOOOOOOOOOOOOOOOOOOOOOOOOOOOOOOOOOOOOOOOOOOOOOOOOOOOOOOOOOOO | OOOOOOOOOOOOOOOOOOOOOOOOOOOOOOOOOOOOOOOOOOOOOOOOOOOOOOOOOOOOOOOOOOOOOOOOOOOOOOOOOOOOOOOOOO | OOOOOOOOOOOOOOOOOOOOOOOOOOOOOOOOOOOOOOOOOOOOOOOOOOOOOOOOOOOOOOOOOOOOOOOOOOOOOOOOOOOOOOOOOO | OOOOOOOOOOOOOOOOOOOOOOOOOOOOOOOOOOOOOOOOOOOOOOOOOOOOOOOOOOOOOOOOOOOOOOOOOOOOOOOOOOOOOOOOOO | OOOOOOOOOOOOOOOOOOOOOOOOOOOOOOOOOOOOOOOOOOOOOOOOOOOOOOOOOOOOOOOOOOOOOOOOOOOOOOOOOOOOOOOOOO |
| Master Materials Change |  |  |  |  |  |  |  |  |  |
| Item | Foxconn P/N | Orig._Usage | New_Usage | Part Description | Manufacturer Full Name | Manufacturer P/N | RoHS | Location | Sheet |
| 1 | 62011DB01-015-G | 0 | 1 | CAP,1nF,+/-10%,X7R,100V,G,SMD0402 | MURATA ELEC. NORTH AMERICA | GRM155R72A102K | Y | (+)PHAC3 | PWA BOM |
| 2 | 620133600-015-G | 1 | 0 | CAP,1nF,+/-5%,X7R,100V,G,SMD0805 | MURATA ELEC. NORTH AMERICA | GRM219R72A102JA01D |  | (-)PHAC3 | PWA BOM |
| OOOOOOOOOOOOOOOOOOOOOOOOOOOOOOOOOOOOOOOOOOOOOOOOOOOOOOOOOOOOOOOOOOOOOOOOOOOOOOOOOOOOOOOOOO | OOOOOOOOOOOOOOOOOOOOOOOOOOOOOOOOOOOOOOOOOOOOOOOOOOOOOOOOOOOOOOOOOOOOOOOOOOOOOOOOOOOOOOOOOO | OOOOOOOOOOOOOOOOOOOOOOOOOOOOOOOOOOOOOOOOOOOOOOOOOOOOOOOOOOOOOOOOOOOOOOOOOOOOOOOOOOOOOOOOOO | OOOOOOOOOOOOOOOOOOOOOOOOOOOOOOOOOOOOOOOOOOOOOOOOOOOOOOOOOOOOOOOOOOOOOOOOOOOOOOOOOOOOOOOOOO | OOOOOOOOOOOOOOOOOOOOOOOOOOOOOOOOOOOOOOOOOOOOOOOOOOOOOOOOOOOOOOOOOOOOOOOOOOOOOOOOOOOOOOOOOO | OOOOOOOOOOOOOOOOOOOOOOOOOOOOOOOOOOOOOOOOOOOOOOOOOOOOOOOOOOOOOOOOOOOOOOOOOOOOOOOOOOOOOOOOOO | OOOOOOOOOOOOOOOOOOOOOOOOOOOOOOOOOOOOOOOOOOOOOOOOOOOOOOOOOOOOOOOOOOOOOOOOOOOOOOOOOOOOOOOOOO | OOOOOOOOOOOOOOOOOOOOOOOOOOOOOOOOOOOOOOOOOOOOOOOOOOOOOOOOOOOOOOOOOOOOOOOOOOOOOOOOOOOOOOOOOO | OOOOOOOOOOOOOOOOOOOOOOOOOOOOOOOOOOOOOOOOOOOOOOOOOOOOOOOOOOOOOOOOOOOOOOOOOOOOOOOOOOOOOOOOOO |  |
| TLA Parts Change |  |  |  |  |  |  |  |  |  |
| Item | Foxconn P/N | Qty | Part Description | Manufacturer Full Name | Manufacturer P/N | RoHS | Location | Remark |  |
| BOM Change List Date:Thu Sep 28 18:52:32 GMT+08:00 2017 |  |  |  |  |  |  |  |  |  |
| New BOM file : C:\<user>\ZAIUS-MB-PVT-HW-EBOM-X04-20170928.xls |  |  |  |  |  |  |  |  |  |
| Old BOM file : C:\<user>\ZAIUS-MB-PVT-HW-EBOM-X04-20170830.xls |  |  |  |  |  |  |  |  |  |
| ##### Add Parts |  |  |  |  |  |  |  |  |  |
| Item | Location | Qty | Foxconn P/N | Part Description | Manufacturer Full Name | Manufacturer P/N | RoHS | Sheet |  |
| ##### Remove Parts |  |  |  |  |  |  |  |  |  |
| Item | Location | Qty | Foxconn P/N | Part Description | Manufacturer Full Name | Manufacturer P/N | RoHS | Sheet |  |
| 1 | C2092,C2120,C2121,C2122 | 4 | 620106200-015-G | CAP,10nF,+/-10%,X7R,16V,G,SMD0402 | MURATA ELEC. NORTH AMERICA | GRM155R71C103KA01D | Y | PWA BOM |  |
| 2 | C2008,C2010 | 2 | 620108100-015-G | CAP,15pF,+/-5%,NPO(C0G),50V,G,SMD0402 | MURATA ELEC. NORTH AMERICA | GRM1555C1H150J | N | PWA BOM |  |
| 3 | R1425,R1516,R1517,R1518 | 4 | 610114U00-017-G | RES,3.3KOhm,+/-1%,1/16W,G,SMD0402 | KOA SPEER ELECTRONICS, INC. | RK73H1ETTP3301F | N | PWA BOM |  |
| ##### Change Parts |  |  |  |  |  |  |  |  |  |
| Item | Location | Qty | Foxconn P/N | Part Description | Manufacturer Full Name | Manufacturer P/N | RoHS | Sheet | Remark |
| 1 | U5 | 1 | UCD90160RGCR-C13 | IC,Power Controller,UCD90160RGCR,G,VQFN-64,SMD | TEXAS INSTRUMENTS | UCD90160RGCR-C13 |  | PWA BOM | In New BOM |
|  | U5 | 1 | 320241C00-183-G | IC,Power Controller,UCD90160RGCR,G,VQFN-64,SMD | TEXAS INSTRUMENTS | UCD90160RGCR |  | PWA BOM | In Old BOM |
| ##### Change Revision |  |  |  |  |  |  |  |  |  |
| Sheet | REV OF BOM | CUSTOMER | CUSTOMER P/N | PWA PN | PWA DESCRIPTION | PWA REV | DATE | Remark |  |
| OOOOOOOOOOOOOOOOOOOOOOOOOOOOOOOOOOOOOOOOOOOOOOOOOOOOOOOOOOOOOOOOOOOOOOOOOOOOOOOOOOOOOOOOOO | OOOOOOOOOOOOOOOOOOOOOOOOOOOOOOOOOOOOOOOOOOOOOOOOOOOOOOOOOOOOOOOOOOOOOOOOOOOOOOOOOOOOOOOOOO | OOOOOOOOOOOOOOOOOOOOOOOOOOOOOOOOOOOOOOOOOOOOOOOOOOOOOOOOOOOOOOOOOOOOOOOOOOOOOOOOOOOOOOOOOO | OOOOOOOOOOOOOOOOOOOOOOOOOOOOOOOOOOOOOOOOOOOOOOOOOOOOOOOOOOOOOOOOOOOOOOOOOOOOOOOOOOOOOOOOOO | OOOOOOOOOOOOOOOOOOOOOOOOOOOOOOOOOOOOOOOOOOOOOOOOOOOOOOOOOOOOOOOOOOOOOOOOOOOOOOOOOOOOOOOOOO | OOOOOOOOOOOOOOOOOOOOOOOOOOOOOOOOOOOOOOOOOOOOOOOOOOOOOOOOOOOOOOOOOOOOOOOOOOOOOOOOOOOOOOOOOO | OOOOOOOOOOOOOOOOOOOOOOOOOOOOOOOOOOOOOOOOOOOOOOOOOOOOOOOOOOOOOOOOOOOOOOOOOOOOOOOOOOOOOOOOOO | OOOOOOOOOOOOOOOOOOOOOOOOOOOOOOOOOOOOOOOOOOOOOOOOOOOOOOOOOOOOOOOOOOOOOOOOOOOOOOOOOOOOOOOOOO | OOOOOOOOOOOOOOOOOOOOOOOOOOOOOOOOOOOOOOOOOOOOOOOOOOOOOOOOOOOOOOOOOOOOOOOOOOOOOOOOOOOOOOOOOO | OOOOOOOOOOOOOOOOOOOOOOOOOOOOOOOOOOOOOOOOOOOOOOOOOOOOOOOOOOOOOOOOOOOOOOOOOOOOOOOOOOOOOOOOOO |
| Second Source Change |  |  |  |  |  |  |  |  |  |
| Item | Location | Change Type | Foxconn P/N | Part Description | Manufacturer Full Name | Manufacturer P/N | RoHS | Sheet |  |
| OOOOOOOOOOOOOOOOOOOOOOOOOOOOOOOOOOOOOOOOOOOOOOOOOOOOOOOOOOOOOOOOOOOOOOOOOOOOOOOOOOOOOOOOOO | OOOOOOOOOOOOOOOOOOOOOOOOOOOOOOOOOOOOOOOOOOOOOOOOOOOOOOOOOOOOOOOOOOOOOOOOOOOOOOOOOOOOOOOOOO | OOOOOOOOOOOOOOOOOOOOOOOOOOOOOOOOOOOOOOOOOOOOOOOOOOOOOOOOOOOOOOOOOOOOOOOOOOOOOOOOOOOOOOOOOO | OOOOOOOOOOOOOOOOOOOOOOOOOOOOOOOOOOOOOOOOOOOOOOOOOOOOOOOOOOOOOOOOOOOOOOOOOOOOOOOOOOOOOOOOOO | OOOOOOOOOOOOOOOOOOOOOOOOOOOOOOOOOOOOOOOOOOOOOOOOOOOOOOOOOOOOOOOOOOOOOOOOOOOOOOOOOOOOOOOOOO | OOOOOOOOOOOOOOOOOOOOOOOOOOOOOOOOOOOOOOOOOOOOOOOOOOOOOOOOOOOOOOOOOOOOOOOOOOOOOOOOOOOOOOOOOO | OOOOOOOOOOOOOOOOOOOOOOOOOOOOOOOOOOOOOOOOOOOOOOOOOOOOOOOOOOOOOOOOOOOOOOOOOOOOOOOOOOOOOOOOOO | OOOOOOOOOOOOOOOOOOOOOOOOOOOOOOOOOOOOOOOOOOOOOOOOOOOOOOOOOOOOOOOOOOOOOOOOOOOOOOOOOOOOOOOOOO | OOOOOOOOOOOOOOOOOOOOOOOOOOOOOOOOOOOOOOOOOOOOOOOOOOOOOOOOOOOOOOOOOOOOOOOOOOOOOOOOOOOOOOOOOO | OOOOOOOOOOOOOOOOOOOOOOOOOOOOOOOOOOOOOOOOOOOOOOOOOOOOOOOOOOOOOOOOOOOOOOOOOOOOOOOOOOOOOOOOOO |
| Master Materials Change |  |  |  |  |  |  |  |  |  |
| Item | Foxconn P/N | Orig._Usage | New_Usage | Part Description | Manufacturer Full Name | Manufacturer P/N | RoHS | Location | Sheet |
| 1 | 620106200-015-G | 41 | 37 | CAP,10nF,+/-10%,X7R,16V,G,SMD0402 | MURATA ELEC. NORTH AMERICA | GRM155R71C103KA01D | Y | (-)C2092,C2120,C2121,C2122 | PWA BOM |
| 2 | 610114U00-017-G | 25 | 21 | RES,3.3KOhm,+/-1%,1/16W,G,SMD0402 | KOA SPEER ELECTRONICS, INC. | RK73H1ETTP3301F | N | (-)R1425,R1516,R1517,R1518 | PWA BOM |
| 3 | UCD90160RGCR-C13 | 0 | 1 | IC,Power Controller,UCD90160RGCR,G,VQFN-64,SMD | TEXAS INSTRUMENTS | UCD90160RGCR-C13 |  | (+)U5 | PWA BOM |
| 4 | 620108100-015-G | 2 | 0 | CAP,15pF,+/-5%,NPO(C0G),50V,G,SMD0402 | MURATA ELEC. NORTH AMERICA | GRM1555C1H150J | N | (-)C2008,C2010 | PWA BOM |
| 5 | 320241C00-183-G | 1 | 0 | IC,Power Controller,UCD90160RGCR,G,VQFN-64,SMD | TEXAS INSTRUMENTS | UCD90160RGCR |  | (-)U5 | PWA BOM |
| OOOOOOOOOOOOOOOOOOOOOOOOOOOOOOOOOOOOOOOOOOOOOOOOOOOOOOOOOOOOOOOOOOOOOOOOOOOOOOOOOOOOOOOOOO | OOOOOOOOOOOOOOOOOOOOOOOOOOOOOOOOOOOOOOOOOOOOOOOOOOOOOOOOOOOOOOOOOOOOOOOOOOOOOOOOOOOOOOOOOO | OOOOOOOOOOOOOOOOOOOOOOOOOOOOOOOOOOOOOOOOOOOOOOOOOOOOOOOOOOOOOOOOOOOOOOOOOOOOOOOOOOOOOOOOOO | OOOOOOOOOOOOOOOOOOOOOOOOOOOOOOOOOOOOOOOOOOOOOOOOOOOOOOOOOOOOOOOOOOOOOOOOOOOOOOOOOOOOOOOOOO | OOOOOOOOOOOOOOOOOOOOOOOOOOOOOOOOOOOOOOOOOOOOOOOOOOOOOOOOOOOOOOOOOOOOOOOOOOOOOOOOOOOOOOOOOO | OOOOOOOOOOOOOOOOOOOOOOOOOOOOOOOOOOOOOOOOOOOOOOOOOOOOOOOOOOOOOOOOOOOOOOOOOOOOOOOOOOOOOOOOOO | OOOOOOOOOOOOOOOOOOOOOOOOOOOOOOOOOOOOOOOOOOOOOOOOOOOOOOOOOOOOOOOOOOOOOOOOOOOOOOOOOOOOOOOOOO | OOOOOOOOOOOOOOOOOOOOOOOOOOOOOOOOOOOOOOOOOOOOOOOOOOOOOOOOOOOOOOOOOOOOOOOOOOOOOOOOOOOOOOOOOO | OOOOOOOOOOOOOOOOOOOOOOOOOOOOOOOOOOOOOOOOOOOOOOOOOOOOOOOOOOOOOOOOOOOOOOOOOOOOOOOOOOOOOOOOOO |  |
| TLA Parts Change |  |  |  |  |  |  |  |  |  |
| Item | Foxconn P/N | Qty | Part Description | Manufacturer Full Name | Manufacturer P/N | RoHS | Location | Remark |  |
| BOM Change List Date:Fri Sep 29 16:53:09 GMT+08:00 2017 |  |  |  |  |  |  |  |  |  |
| New BOM file : E:\barreleye g2\0928\ZAIUS-MB-PVT-X04-BOM_X25_20170929.xls |  |  |  |  |  |  |  |  |  |
| Old BOM file : E:\barreleye g2\0928\ZAIUS0913.xls |  |  |  |  |  |  |  |  |  |
| ##### Add Parts |  |  |  |  |  |  |  |  |  |
| Item | Location | Qty | Foxconn P/N | Part Description | Manufacturer Full Name | Manufacturer P/N | RoHS | Sheet |  |
| ##### Remove Parts |  |  |  |  |  |  |  |  |  |
| Item | Location | Qty | Foxconn P/N | Part Description | Manufacturer Full Name | Manufacturer P/N | RoHS | Sheet |  |
| 1 | C2092,C2120,C2121,C2122 | 4 | 620106200-015-G | CAP,10nF,+/-10%,X7R,16V,G,SMD0402 | MURATA ELEC. NORTH AMERICA | GRM155R71C103KA01D | G | PWA BOM |  |
|  |  |  | 620106200-026-G | CAP,10nF,+/-10%,X7R,16V,G,SMD0402 | SAMSUNG SEMICONDUCTOR | CL05B103KO5NNNC | G | PWA BOM |  |
|  |  |  | 620106200-023-G | CAP,10nF,+/-10%,X7R,16V,G,SMD0402 | TAIYO ELECTRIC IND.CO.LTD | EMK105B7103KV-F | G | PWA BOM |  |
| 2 | C2008,C2010 | 2 | 620108100-015-G | CAP,15pF,+/-5%,NPO(C0G),50V,G,SMD0402 | MURATA ELEC. NORTH AMERICA | GRM1555C1H150J | G | PWA BOM |  |
| 3 | R1425,R1516,R1517,R1518 | 4 | 610114U00-017-G | RES,3.3KOhm,+/-1%,1/16W,G,SMD0402 | KOA SPEER ELECTRONICS, INC. | RK73H1ETTP3301F | G | PWA BOM |  |
|  |  |  | 610114U00-024-G | RES,3.3KOhm,+/-1%,1/16W,G,SMD0402 | PANASONIC INDUSTRIAL CO.,LTD. | ERJ2RKF3301X | G | PWA BOM |  |
|  |  |  | 610114U00-011-G | RES,3.3KOhm,+/-1%,1/16W,G,SMD0402 | YAGEO CORPORATION COMPONENT | RC0402FR-073K3L | G | PWA BOM |  |
|  |  |  | 610114U00-044-G | RES,3.3KOhm,+/-1%,1/16W,G,SMD0402 | TA-I TECHNOLOGY CO., LTD. | RM04FTN3301 | G | PWA BOM |  |
| ##### Change Parts |  |  |  |  |  |  |  |  |  |
| Item | Location | Qty | Foxconn P/N | Part Description | Manufacturer Full Name | Manufacturer P/N | RoHS | Sheet | Remark |
| 1 | PHAR9,PALR16,PBLR18,PBNR21,PANR21,PBMR40,PBFR40,PBER40,PBAR40,PAMR40,PAFR40,PAER40,PAAR40,R865,R866,R1155,R1169,R1181,R1193,R1205,R1217,R1258,R1329,R1333,R1334,R1335,R1498,R1500,R1729,R1733,R1737,R1741,R1824 | 33 | 61010L300-017-G | RES,1KOhm,+/-1%,1/16W,G,SMD0402 | KOA SPEER ELECTRONICS, INC. | RK73H1ETTP1001F | G | PWA BOM | In New BOM |
|  |  |  | 61010L300-029-G | RES,1KOhm,+/-1%,1/16W,G,SMD0402 | VISHAY ENTER TECHNO LOGY.INC | CRCW04021K00FKED | G | PWA BOM | In New BOM |
|  |  |  | 61010L300-024-G | RES,1KOhm,+/-1%,1/16W,G,SMD0402 | PANASONIC INDUSTRIAL CO.,LTD. | ERJ2RKF1001X | G | PWA BOM | In New BOM |
|  | PHAR9,PALR16,PBLR18,PBNR21,PANR21,PBMR40,PBFR40,PBER40,PBAR40,PAMR40,PAFR40,PAER40,PAAR40,R865,R866,R1155,R1169,R1181,R1193,R1205,R1217,R1258,R1329,R1333,R1334,R1335,R1498,R1500,R1729,R1733,R1737,R1741,R1824 | 33 | 61010L300-017-G | RES,1KOhm,+/-1%,1/16W,G,SMD0402 | KOA SPEER ELECTRONICS, INC. | RK73H1ETTP1001F | G | PWA BOM | In Old BOM |
|  |  |  | 61010L300-029-G | RES,1KOhm,+/-1%,1/16W,G,SMD0402 | VISHAY ENTER TECHNO LOGY.INC | CRCW04021K00FKED | G | PWA BOM | In Old BOM |
|  |  |  | 610151600-024-G | RES,thick film,1KOhm,+/-1%,1/10W,SMD0402,G | PANASONIC INDUSTRIAL CO.,LTD. | ERJ2RKF1001X | G | PWA BOM | In Old BOM |
| 2 | PCIE2,PCIE3,PCIE4 | 3 | 10061913-103HLF | CONN,PCIE-16X,V/T,Bla,1mm,30u,G,SMD-164 | FCI CONNECTORS HONGKONG LTD. | 10061913-103HLF | G | PWA BOM | In New BOM |
|  |  |  | 340321600-278-G | CONN,PCIE-16X,V/T,Bla,1mm,30u,G,SMD-164 | TYCO ELECTRONICS CORPORATION | 2041366-9 | G | PWA BOM | In New BOM |
|  | PCIE2,PCIE3,PCIE4 | 3 | 10061913-103HLF | CONN,PCIE-16X,V/T,Bla,1mm,30u,G,SMD-164 | FCI CONNECTORS HONGKONG LTD. | 10061913-103HLF | G | PWA BOM | In Old BOM |
|  |  |  | 2041366-9 | CONN,PCIE-16X,V/T,Bla,1mm,30u,G,SMD-164 | TYCO ELECTRONICS CORPORATION | 2041366-9 | G | PWA BOM | In Old BOM |
| 3 | R1492 | 1 | 610118800-017-G | RES,499KOhm,+/-1%,1/8W,G,SMD0805 | KOA SPEER ELECTRONICS, INC. | RK73H2ATTD4993F | G | PWA BOM | In New BOM |
|  |  |  | 610118800-024-G | RES,499KOhm,+/-1%,1/8W,G,SMD0805 | PANASONIC INDUSTRIAL CO.,LTD. | ERJ6ENF4993V | G | PWA BOM | In New BOM |
|  |  |  | 610118800-011-G | RES,499KOhm,+/-1%,1/8W,G,SMD0805 | YAGEO CORPORATION COMPONENT | RC0805FR-07499KL | G | PWA BOM | In New BOM |
|  | R1492 | 1 | 610118800-017-G | RES,499KOhm,+/-1%,1/8W,G,SMD0805 | KOA SPEER ELECTRONICS, INC. | RK73H2ATTD4993F | G | PWA BOM | In Old BOM |
|  |  |  | 610118800-024-G | RES,499KOhm,+/-1%,1/8W,G,SMD0805 | PANASONIC INDUSTRIAL CO.,LTD. | ERJ6ENF4993V | G | PWA BOM | In Old BOM |
|  |  |  | RC0805FR-07499KL | RES,499KOhm,+/-1%,1/8W,G,SMD0805 | YAGEO CORPORATION COMPONENT | RC0805FR-07499KL | G | PWA BOM | In Old BOM |
| 4 | PBMJ1,PBEJ1,PBAJ1,PAMJ1,PAEJ1,PAAJ1 | 6 | 340634U00-600-G | CONN,Pin Header,2X3,V/T,Bla,2.54mm,30u,G,SMD-6 | FOXCONN TECHNOLOGY CO.,LTD. | HS1103H-RN | G | PWA BOM | In New BOM |
|  |  |  | 34068GL00-317-G | CONN,Header,Pin Header,2X3,V/T,Bla,2.54mm,30u,SMD-6 | MOLEX INCORPORATED | 015-91-6063 | G | PWA BOM | In New BOM |
|  |  |  | 3406AY700-637-G | Header&Socket Connector,11006A5807,Pin Header,6,SMD,NY6T,2.54mm,30u",Black,G | LONG SHOUNG CO.,LTD. | 11006A5807 | G | PWA BOM | In New BOM |
|  | PBMJ1,PBEJ1,PBAJ1,PAMJ1,PAEJ1,PAAJ1 | 6 | 340634U00-600-G | CONN,Pin Header,2X3,V/T,Bla,2.54mm,30u,G,SMD-6 | FOXCONN TECHNOLOGY CO.,LTD. | HS1103H-RN | G | PWA BOM | In Old BOM |
|  |  |  | 34065EA00-317-G | CONN,Header,Pin Header,2X3,V/T,Bla,2.54mm,30u,G,SMD-6 | MOLEX INCORPORATED | 015-91-3060 | G | PWA BOM | In Old BOM |
|  |  |  | 3406AY700-637-G | Header&Socket Connector,11006A5807,Pin Header,6,SMD,NY6T,2.54mm,30u",Black,G | LONG SHOUNG CO.,LTD. | 11006A5807 | G | PWA BOM | In Old BOM |
| 5 | PCB | 1 | 0101FBQ00-000-G | PCB | GCE | 0101FBQ00-000-G | G | PWA BOM | In New BOM |
|  | PCB | 1 | 0101FBQ00-000-G | PCB,Zaius-MB PVT-X04,OSP,Gre,22L,22.20*13.00,G | GOLD CIRCUIT ELECTRONICS LTD. | 0101FBQ00-000-G | G | PWA BOM | In Old BOM |
| 6 | PBMU1,PBFU1,PBEU1,PBAU1,PAMU1,PAFU1,PAEU1,PAAU1 | 8 | 320242200-230-G | IC,PWM Controller,ISL68137IRAZ-T,G,QFN-48,SMD | INTERSIL CORPORATION | ISL68137IRAZ-T | G | PWA BOM | In New BOM |
|  | PBMU1,PBFU1,PBEU1,PBAU1,PAMU1,PAFU1,PAEU1,PAAU1 | 8 | ISL68137IRAZ-GG04 | IC,PWM Controller,ISL68137IRAZ-T,G,QFN-48,SMD | INTERSIL CORPORATION | ISL68137IRAZ-GG04 | G | PWA BOM | In Old BOM |
| ##### Change Revision |  |  |  |  |  |  |  |  |  |
| Sheet | REV OF BOM | CUSTOMER | CUSTOMER P/N | PWA PN | PWA DESCRIPTION | PWA REV | DATE | Remark |  |
| OOOOOOOOOOOOOOOOOOOOOOOOOOOOOOOOOOOOOOOOOOOOOOOOOOOOOOOOOOOOOOOOOOOOOOOOOOOOOOOOOOOOOOOOOO | OOOOOOOOOOOOOOOOOOOOOOOOOOOOOOOOOOOOOOOOOOOOOOOOOOOOOOOOOOOOOOOOOOOOOOOOOOOOOOOOOOOOOOOOOO | OOOOOOOOOOOOOOOOOOOOOOOOOOOOOOOOOOOOOOOOOOOOOOOOOOOOOOOOOOOOOOOOOOOOOOOOOOOOOOOOOOOOOOOOOO | OOOOOOOOOOOOOOOOOOOOOOOOOOOOOOOOOOOOOOOOOOOOOOOOOOOOOOOOOOOOOOOOOOOOOOOOOOOOOOOOOOOOOOOOOO | OOOOOOOOOOOOOOOOOOOOOOOOOOOOOOOOOOOOOOOOOOOOOOOOOOOOOOOOOOOOOOOOOOOOOOOOOOOOOOOOOOOOOOOOOO | OOOOOOOOOOOOOOOOOOOOOOOOOOOOOOOOOOOOOOOOOOOOOOOOOOOOOOOOOOOOOOOOOOOOOOOOOOOOOOOOOOOOOOOOOO | OOOOOOOOOOOOOOOOOOOOOOOOOOOOOOOOOOOOOOOOOOOOOOOOOOOOOOOOOOOOOOOOOOOOOOOOOOOOOOOOOOOOOOOOOO | OOOOOOOOOOOOOOOOOOOOOOOOOOOOOOOOOOOOOOOOOOOOOOOOOOOOOOOOOOOOOOOOOOOOOOOOOOOOOOOOOOOOOOOOOO | OOOOOOOOOOOOOOOOOOOOOOOOOOOOOOOOOOOOOOOOOOOOOOOOOOOOOOOOOOOOOOOOOOOOOOOOOOOOOOOOOOOOOOOOOO | OOOOOOOOOOOOOOOOOOOOOOOOOOOOOOOOOOOOOOOOOOOOOOOOOOOOOOOOOOOOOOOOOOOOOOOOOOOOOOOOOOOOOOOOOO |
| Second Source Change |  |  |  |  |  |  |  |  |  |
| Item | Location | Change Type | Foxconn P/N | Part Description | Manufacturer Full Name | Manufacturer P/N | RoHS | Sheet |  |
| 1 | PHAR9,PALR16,PBLR18,PBNR21,PANR21,PBMR40,PBFR40,PBER40,PBAR40,PAMR40,PAFR40,PAER40,PAAR40,R865,R866,R1155,R1169,R1181,R1193,R1205,R1217,R1258,R1329,R1333,R1334,R1335,R1498,R1500,R1729,R1733,R1737,R1741,R1824 |  | 61010L300-017-G | RES,1KOhm,+/-1%,1/16W,G,SMD0402 | KOA SPEER ELECTRONICS, INC. | RK73H1ETTP1001F | G | PWA BOM |  |
|  |  | NO | 61010L300-029-G | RES,1KOhm,+/-1%,1/16W,G,SMD0402 | VISHAY ENTER TECHNO LOGY.INC | CRCW04021K00FKED | G | PWA BOM |  |
|  |  | ADD | 61010L300-024-G | RES,1KOhm,+/-1%,1/16W,G,SMD0402 | PANASONIC INDUSTRIAL CO.,LTD. | ERJ2RKF1001X | G | PWA BOM |  |
|  |  | Delete | 610151600-024-G | RES,thick film,1KOhm,+/-1%,1/10W,SMD0402,G | PANASONIC INDUSTRIAL CO.,LTD. | ERJ2RKF1001X | G | PWA BOM |  |
| 2 | PCIE2,PCIE3,PCIE4 |  | 10061913-103HLF | CONN,PCIE-16X,V/T,Bla,1mm,30u,G,SMD-164 | FCI CONNECTORS HONGKONG LTD. | 10061913-103HLF | G | PWA BOM |  |
|  |  | ADD | 340321600-278-G | CONN,PCIE-16X,V/T,Bla,1mm,30u,G,SMD-164 | TYCO ELECTRONICS CORPORATION | 2041366-9 | G | PWA BOM |  |
|  |  | Delete | 2041366-9 | CONN,PCIE-16X,V/T,Bla,1mm,30u,G,SMD-164 | TYCO ELECTRONICS CORPORATION | 2041366-9 | G | PWA BOM |  |
| 3 | R1492 |  | 610118800-017-G | RES,499KOhm,+/-1%,1/8W,G,SMD0805 | KOA SPEER ELECTRONICS, INC. | RK73H2ATTD4993F | G | PWA BOM |  |
|  |  | NO | 610118800-024-G | RES,499KOhm,+/-1%,1/8W,G,SMD0805 | PANASONIC INDUSTRIAL CO.,LTD. | ERJ6ENF4993V | G | PWA BOM |  |
|  |  | ADD | 610118800-011-G | RES,499KOhm,+/-1%,1/8W,G,SMD0805 | YAGEO CORPORATION COMPONENT | RC0805FR-07499KL | G | PWA BOM |  |
|  |  | Delete | RC0805FR-07499KL | RES,499KOhm,+/-1%,1/8W,G,SMD0805 | YAGEO CORPORATION COMPONENT | RC0805FR-07499KL | G | PWA BOM |  |
| 4 | PBMJ1,PBEJ1,PBAJ1,PAMJ1,PAEJ1,PAAJ1 |  | 340634U00-600-G | CONN,Pin Header,2X3,V/T,Bla,2.54mm,30u,G,SMD-6 | FOXCONN TECHNOLOGY CO.,LTD. | HS1103H-RN | G | PWA BOM |  |
|  |  | ADD | 34068GL00-317-G | CONN,Header,Pin Header,2X3,V/T,Bla,2.54mm,30u,SMD-6 | MOLEX INCORPORATED | 015-91-6063 | G | PWA BOM |  |
|  |  | NO | 3406AY700-637-G | Header&Socket Connector,11006A5807,Pin Header,6,SMD,NY6T,2.54mm,30u",Black,G | LONG SHOUNG CO.,LTD. | 11006A5807 | G | PWA BOM |  |
|  |  | Delete | 34065EA00-317-G | CONN,Header,Pin Header,2X3,V/T,Bla,2.54mm,30u,G,SMD-6 | MOLEX INCORPORATED | 015-91-3060 | G | PWA BOM |  |
| OOOOOOOOOOOOOOOOOOOOOOOOOOOOOOOOOOOOOOOOOOOOOOOOOOOOOOOOOOOOOOOOOOOOOOOOOOOOOOOOOOOOOOOOOO | OOOOOOOOOOOOOOOOOOOOOOOOOOOOOOOOOOOOOOOOOOOOOOOOOOOOOOOOOOOOOOOOOOOOOOOOOOOOOOOOOOOOOOOOOO | OOOOOOOOOOOOOOOOOOOOOOOOOOOOOOOOOOOOOOOOOOOOOOOOOOOOOOOOOOOOOOOOOOOOOOOOOOOOOOOOOOOOOOOOOO | OOOOOOOOOOOOOOOOOOOOOOOOOOOOOOOOOOOOOOOOOOOOOOOOOOOOOOOOOOOOOOOOOOOOOOOOOOOOOOOOOOOOOOOOOO | OOOOOOOOOOOOOOOOOOOOOOOOOOOOOOOOOOOOOOOOOOOOOOOOOOOOOOOOOOOOOOOOOOOOOOOOOOOOOOOOOOOOOOOOOO | OOOOOOOOOOOOOOOOOOOOOOOOOOOOOOOOOOOOOOOOOOOOOOOOOOOOOOOOOOOOOOOOOOOOOOOOOOOOOOOOOOOOOOOOOO | OOOOOOOOOOOOOOOOOOOOOOOOOOOOOOOOOOOOOOOOOOOOOOOOOOOOOOOOOOOOOOOOOOOOOOOOOOOOOOOOOOOOOOOOOO | OOOOOOOOOOOOOOOOOOOOOOOOOOOOOOOOOOOOOOOOOOOOOOOOOOOOOOOOOOOOOOOOOOOOOOOOOOOOOOOOOOOOOOOOOO | OOOOOOOOOOOOOOOOOOOOOOOOOOOOOOOOOOOOOOOOOOOOOOOOOOOOOOOOOOOOOOOOOOOOOOOOOOOOOOOOOOOOOOOOOO | OOOOOOOOOOOOOOOOOOOOOOOOOOOOOOOOOOOOOOOOOOOOOOOOOOOOOOOOOOOOOOOOOOOOOOOOOOOOOOOOOOOOOOOOOO |
| Master Materials Change |  |  |  |  |  |  |  |  |  |
| Item | Foxconn P/N | Orig._Usage | New_Usage | Part Description | Manufacturer Full Name | Manufacturer P/N | RoHS | Location | Sheet |
| 1 | 620106200-015-G | 41 | 37 | CAP,10nF,+/-10%,X7R,16V,G,SMD0402 | MURATA ELEC. NORTH AMERICA | GRM155R71C103KA01D | G | (-)C2092,C2120,C2121,C2122 | PWA BOM |
|  | 620106200-026-G |  |  | CAP,10nF,+/-10%,X7R,16V,G,SMD0402 | SAMSUNG SEMICONDUCTOR | CL05B103KO5NNNC |  |  | PWA BOM |
|  | 620106200-023-G |  |  | CAP,10nF,+/-10%,X7R,16V,G,SMD0402 | TAIYO ELECTRIC IND.CO.LTD | EMK105B7103KV-F |  |  | PWA BOM |
| 2 | 320242200-230-G | 0 | 8 | IC,PWM Controller,ISL68137IRAZ-T,G,QFN-48,SMD | INTERSIL CORPORATION | ISL68137IRAZ-T | G | (+)PBMU1,PBFU1,PBEU1,PBAU1,PAMU1,PAFU1,PAEU1,PAAU1 | PWA BOM |
| 3 | 610114U00-017-G | 25 | 21 | RES,3.3KOhm,+/-1%,1/16W,G,SMD0402 | KOA SPEER ELECTRONICS, INC. | RK73H1ETTP3301F | G | (-)R1425,R1516,R1517,R1518 | PWA BOM |
|  | 610114U00-024-G |  |  | RES,3.3KOhm,+/-1%,1/16W,G,SMD0402 | PANASONIC INDUSTRIAL CO.,LTD. | ERJ2RKF3301X |  |  | PWA BOM |
|  | 610114U00-011-G |  |  | RES,3.3KOhm,+/-1%,1/16W,G,SMD0402 | YAGEO CORPORATION COMPONENT | RC0402FR-073K3L |  |  | PWA BOM |
|  | 610114U00-044-G |  |  | RES,3.3KOhm,+/-1%,1/16W,G,SMD0402 | TA-I TECHNOLOGY CO., LTD. | RM04FTN3301 |  |  | PWA BOM |
| 4 | 620108100-015-G | 2 | 0 | CAP,15pF,+/-5%,NPO(C0G),50V,G,SMD0402 | MURATA ELEC. NORTH AMERICA | GRM1555C1H150J | G | (-)C2008,C2010 | PWA BOM |
| 5 | ISL68137IRAZ-GG04 | 8 | 0 | IC,PWM Controller,ISL68137IRAZ-T,G,QFN-48,SMD | INTERSIL CORPORATION | ISL68137IRAZ-GG04 | G | (-)PBMU1,PBFU1,PBEU1,PBAU1,PAMU1,PAFU1,PAEU1,PAAU1 | PWA BOM |
| OOOOOOOOOOOOOOOOOOOOOOOOOOOOOOOOOOOOOOOOOOOOOOOOOOOOOOOOOOOOOOOOOOOOOOOOOOOOOOOOOOOOOOOOOO | OOOOOOOOOOOOOOOOOOOOOOOOOOOOOOOOOOOOOOOOOOOOOOOOOOOOOOOOOOOOOOOOOOOOOOOOOOOOOOOOOOOOOOOOOO | OOOOOOOOOOOOOOOOOOOOOOOOOOOOOOOOOOOOOOOOOOOOOOOOOOOOOOOOOOOOOOOOOOOOOOOOOOOOOOOOOOOOOOOOOO | OOOOOOOOOOOOOOOOOOOOOOOOOOOOOOOOOOOOOOOOOOOOOOOOOOOOOOOOOOOOOOOOOOOOOOOOOOOOOOOOOOOOOOOOOO | OOOOOOOOOOOOOOOOOOOOOOOOOOOOOOOOOOOOOOOOOOOOOOOOOOOOOOOOOOOOOOOOOOOOOOOOOOOOOOOOOOOOOOOOOO | OOOOOOOOOOOOOOOOOOOOOOOOOOOOOOOOOOOOOOOOOOOOOOOOOOOOOOOOOOOOOOOOOOOOOOOOOOOOOOOOOOOOOOOOOO | OOOOOOOOOOOOOOOOOOOOOOOOOOOOOOOOOOOOOOOOOOOOOOOOOOOOOOOOOOOOOOOOOOOOOOOOOOOOOOOOOOOOOOOOOO | OOOOOOOOOOOOOOOOOOOOOOOOOOOOOOOOOOOOOOOOOOOOOOOOOOOOOOOOOOOOOOOOOOOOOOOOOOOOOOOOOOOOOOOOOO | OOOOOOOOOOOOOOOOOOOOOOOOOOOOOOOOOOOOOOOOOOOOOOOOOOOOOOOOOOOOOOOOOOOOOOOOOOOOOOOOOOOOOOOOOO |  |
| TLA Parts Change |  |  |  |  |  |  |  |  |  |
| Item | Foxconn P/N | Qty | Part Description | Manufacturer Full Name | Manufacturer P/N | RoHS | Location | Remark |  |
| BOM Change List Date:Fri Oct 20 14:55:34 GMT+08:00 2017 |  |  |  |  |  |  |  |  |  |
| New BOM file : C:\<user>\ZAIUS-MB-PVT-HW-EBOM-X04-20171020.xls |  |  |  |  |  |  |  |  |  |
| Old BOM file : C:\<user>\ZAIUS-MB-PVT-HW-EBOM-X04-20170928.xls |  |  |  |  |  |  |  |  |  |
| ##### Add Parts |  |  |  |  |  |  |  |  |  |
| Item | Location | Qty | Foxconn P/N | Part Description | Manufacturer Full Name | Manufacturer P/N | RoHS | Sheet |  |
| ##### Remove Parts |  |  |  |  |  |  |  |  |  |
| Item | Location | Qty | Foxconn P/N | Part Description | Manufacturer Full Name | Manufacturer P/N | RoHS | Sheet |  |
| ##### Change Parts |  |  |  |  |  |  |  |  |  |
| Item | Location | Qty | Foxconn P/N | Part Description | Manufacturer Full Name | Manufacturer P/N | RoHS | Sheet | Remark |
| 1 | PHAC3 | 1 | 62011DB01-015-G | CAP,1nF,+/-10%,X7R,100V,G,SMD0402 | MURATA ELEC. NORTH AMERICA | GRM155R72A102K | Y | PWA BOM | In New BOM |
|  | PHAC3 | 1 | 620133600-015-G | CAP,1nF,+/-5%,X7R,100V,G,SMD0805 | MURATA ELEC. NORTH AMERICA | GRM219R72A102JA01D |  | PWA BOM | In Old BOM |
| ##### Change Revision |  |  |  |  |  |  |  |  |  |
| Sheet | REV OF BOM | CUSTOMER | CUSTOMER P/N | PWA PN | PWA DESCRIPTION | PWA REV | DATE | Remark |  |
| OOOOOOOOOOOOOOOOOOOOOOOOOOOOOOOOOOOOOOOOOOOOOOOOOOOOOOOOOOOOOOOOOOOOOOOOOOOOOOOOOOOOOOOOOO | OOOOOOOOOOOOOOOOOOOOOOOOOOOOOOOOOOOOOOOOOOOOOOOOOOOOOOOOOOOOOOOOOOOOOOOOOOOOOOOOOOOOOOOOOO | OOOOOOOOOOOOOOOOOOOOOOOOOOOOOOOOOOOOOOOOOOOOOOOOOOOOOOOOOOOOOOOOOOOOOOOOOOOOOOOOOOOOOOOOOO | OOOOOOOOOOOOOOOOOOOOOOOOOOOOOOOOOOOOOOOOOOOOOOOOOOOOOOOOOOOOOOOOOOOOOOOOOOOOOOOOOOOOOOOOOO | OOOOOOOOOOOOOOOOOOOOOOOOOOOOOOOOOOOOOOOOOOOOOOOOOOOOOOOOOOOOOOOOOOOOOOOOOOOOOOOOOOOOOOOOOO | OOOOOOOOOOOOOOOOOOOOOOOOOOOOOOOOOOOOOOOOOOOOOOOOOOOOOOOOOOOOOOOOOOOOOOOOOOOOOOOOOOOOOOOOOO | OOOOOOOOOOOOOOOOOOOOOOOOOOOOOOOOOOOOOOOOOOOOOOOOOOOOOOOOOOOOOOOOOOOOOOOOOOOOOOOOOOOOOOOOOO | OOOOOOOOOOOOOOOOOOOOOOOOOOOOOOOOOOOOOOOOOOOOOOOOOOOOOOOOOOOOOOOOOOOOOOOOOOOOOOOOOOOOOOOOOO | OOOOOOOOOOOOOOOOOOOOOOOOOOOOOOOOOOOOOOOOOOOOOOOOOOOOOOOOOOOOOOOOOOOOOOOOOOOOOOOOOOOOOOOOOO | OOOOOOOOOOOOOOOOOOOOOOOOOOOOOOOOOOOOOOOOOOOOOOOOOOOOOOOOOOOOOOOOOOOOOOOOOOOOOOOOOOOOOOOOOO |
| Second Source Change |  |  |  |  |  |  |  |  |  |
| Item | Location | Change Type | Foxconn P/N | Part Description | Manufacturer Full Name | Manufacturer P/N | RoHS | Sheet |  |
| OOOOOOOOOOOOOOOOOOOOOOOOOOOOOOOOOOOOOOOOOOOOOOOOOOOOOOOOOOOOOOOOOOOOOOOOOOOOOOOOOOOOOOOOOO | OOOOOOOOOOOOOOOOOOOOOOOOOOOOOOOOOOOOOOOOOOOOOOOOOOOOOOOOOOOOOOOOOOOOOOOOOOOOOOOOOOOOOOOOOO | OOOOOOOOOOOOOOOOOOOOOOOOOOOOOOOOOOOOOOOOOOOOOOOOOOOOOOOOOOOOOOOOOOOOOOOOOOOOOOOOOOOOOOOOOO | OOOOOOOOOOOOOOOOOOOOOOOOOOOOOOOOOOOOOOOOOOOOOOOOOOOOOOOOOOOOOOOOOOOOOOOOOOOOOOOOOOOOOOOOOO | OOOOOOOOOOOOOOOOOOOOOOOOOOOOOOOOOOOOOOOOOOOOOOOOOOOOOOOOOOOOOOOOOOOOOOOOOOOOOOOOOOOOOOOOOO | OOOOOOOOOOOOOOOOOOOOOOOOOOOOOOOOOOOOOOOOOOOOOOOOOOOOOOOOOOOOOOOOOOOOOOOOOOOOOOOOOOOOOOOOOO | OOOOOOOOOOOOOOOOOOOOOOOOOOOOOOOOOOOOOOOOOOOOOOOOOOOOOOOOOOOOOOOOOOOOOOOOOOOOOOOOOOOOOOOOOO | OOOOOOOOOOOOOOOOOOOOOOOOOOOOOOOOOOOOOOOOOOOOOOOOOOOOOOOOOOOOOOOOOOOOOOOOOOOOOOOOOOOOOOOOOO | OOOOOOOOOOOOOOOOOOOOOOOOOOOOOOOOOOOOOOOOOOOOOOOOOOOOOOOOOOOOOOOOOOOOOOOOOOOOOOOOOOOOOOOOOO | OOOOOOOOOOOOOOOOOOOOOOOOOOOOOOOOOOOOOOOOOOOOOOOOOOOOOOOOOOOOOOOOOOOOOOOOOOOOOOOOOOOOOOOOOO |
| Master Materials Change |  |  |  |  |  |  |  |  |  |
| Item | Foxconn P/N | Orig._Usage | New_Usage | Part Description | Manufacturer Full Name | Manufacturer P/N | RoHS | Location | Sheet |
| 1 | 62011DB01-015-G | 0 | 1 | CAP,1nF,+/-10%,X7R,100V,G,SMD0402 | MURATA ELEC. NORTH AMERICA | GRM155R72A102K | Y | (+)PHAC3 | PWA BOM |
| 2 | 620133600-015-G | 1 | 0 | CAP,1nF,+/-5%,X7R,100V,G,SMD0805 | MURATA ELEC. NORTH AMERICA | GRM219R72A102JA01D |  | (-)PHAC3 | PWA BOM |
| OOOOOOOOOOOOOOOOOOOOOOOOOOOOOOOOOOOOOOOOOOOOOOOOOOOOOOOOOOOOOOOOOOOOOOOOOOOOOOOOOOOOOOOOOO | OOOOOOOOOOOOOOOOOOOOOOOOOOOOOOOOOOOOOOOOOOOOOOOOOOOOOOOOOOOOOOOOOOOOOOOOOOOOOOOOOOOOOOOOOO | OOOOOOOOOOOOOOOOOOOOOOOOOOOOOOOOOOOOOOOOOOOOOOOOOOOOOOOOOOOOOOOOOOOOOOOOOOOOOOOOOOOOOOOOOO | OOOOOOOOOOOOOOOOOOOOOOOOOOOOOOOOOOOOOOOOOOOOOOOOOOOOOOOOOOOOOOOOOOOOOOOOOOOOOOOOOOOOOOOOOO | OOOOOOOOOOOOOOOOOOOOOOOOOOOOOOOOOOOOOOOOOOOOOOOOOOOOOOOOOOOOOOOOOOOOOOOOOOOOOOOOOOOOOOOOOO | OOOOOOOOOOOOOOOOOOOOOOOOOOOOOOOOOOOOOOOOOOOOOOOOOOOOOOOOOOOOOOOOOOOOOOOOOOOOOOOOOOOOOOOOOO | OOOOOOOOOOOOOOOOOOOOOOOOOOOOOOOOOOOOOOOOOOOOOOOOOOOOOOOOOOOOOOOOOOOOOOOOOOOOOOOOOOOOOOOOOO | OOOOOOOOOOOOOOOOOOOOOOOOOOOOOOOOOOOOOOOOOOOOOOOOOOOOOOOOOOOOOOOOOOOOOOOOOOOOOOOOOOOOOOOOOO | OOOOOOOOOOOOOOOOOOOOOOOOOOOOOOOOOOOOOOOOOOOOOOOOOOOOOOOOOOOOOOOOOOOOOOOOOOOOOOOOOOOOOOOOOO |  |
| TLA Parts Change |  |  |  |  |  |  |  |  |  |
| Item | Foxconn P/N | Qty | Part Description | Manufacturer Full Name | Manufacturer P/N | RoHS | Location | Remark |  |
| BOM Change List Date:Tue Oct 31 10:06:15 GMT+08:00 2017 |  |  |  |  |  |  |  |  |  |
| New BOM file : E:\barreleye g2\1031\foxbis\ZAIUS 1031.xls |  |  |  |  |  |  |  |  |  |
| Old BOM file : E:\barreleye g2\1031\foxbis\ZAIUS 1021.xls |  |  |  |  |  |  |  |  |  |
| ##### Add Parts |  |  |  |  |  |  |  |  |  |
| Item | Location | Qty | Foxconn P/N | Part Description | Manufacturer Full Name | Manufacturer P/N | RoHS | Sheet |  |
| ##### Remove Parts |  |  |  |  |  |  |  |  |  |
| Item | Location | Qty | Foxconn P/N | Part Description | Manufacturer Full Name | Manufacturer P/N | RoHS | Sheet |  |
| ##### Change Parts |  |  |  |  |  |  |  |  |  |
| Item | Location | Qty | Foxconn P/N | Part Description | Manufacturer Full Name | Manufacturer P/N | RoHS | Sheet | Remark |
| 1 | PUAC4,PSAC4,PRAC4,PQAC4,PPAC4,PIAC4,PFAC4,PEAC4,PUAC5,PSAC5,PRAC5,PQAC5,PPAC5,PIAC5,PFAC5,PEAC5,PUAC6,PSAC6,PRAC6,PQAC6,PPAC6,PIAC6,PFAC6,PEAC6 | 24 | 62011DD00-015-G | CAP,22uF,+/-10%,X6S,6.3V,G,SMD1206 | MURATA ELEC. NORTH AMERICA | GRM31CC80J226K | G | PWA BOM | In New BOM |
|  |  |  | 62011DD00-026-G | CAP,22uF,+/-10%,X6S,6.3V,G,SMD1206 | SAMSUNG SEMICONDUCTOR | CL31X226KQHNNNE | G | PWA BOM | In New BOM |
|  | PUAC4,PSAC4,PRAC4,PQAC4,PPAC4,PIAC4,PFAC4,PEAC4,PUAC5,PSAC5,PRAC5,PQAC5,PPAC5,PIAC5,PFAC5,PEAC5,PUAC6,PSAC6,PRAC6,PQAC6,PPAC6,PIAC6,PFAC6,PEAC6 | 24 | 62011DD00-015-G | CAP,22uF,+/-10%,X6S,6.3V,G,SMD1206 | MURATA ELEC. NORTH AMERICA | GRM31CC80J226K | G | PWA BOM | In Old BOM |
|  |  |  | CL31X226KQHNNNE | CAP,22uF,+/-10%,X6S,6.3V,G,SMD1206 | SAMSUNG SEMICONDUCTOR | CL31X226KQHNNNE | G | PWA BOM | In Old BOM |
| 2 | ED2,ED3 | 2 | 521800900-227-G | DIODE,Array-TVS,SRV05-4.TCT,5V,12A,G,SOT23-6,SMD | SEMTECH CORPORATION. | SRV05-4.TCT | G | PWA BOM | In New BOM |
|  |  |  | 52180C200-086-G | Diode,Array-TVS,SRV05-4HTG,SOT-23,6P,G | LITTELFUSE FAR EAST PTE LTD | SRV05-4HTG | G | PWA BOM | In New BOM |
|  | ED2,ED3 | 2 | SRV05-4ATCT | DIODE,Array-TVS,SRV05-4.TCT,5V,12A,G,SOT23-6,SMD | SEMTECH CORPORATION. | SRV05-4ATCT | G | PWA BOM | In Old BOM |
|  |  |  | 521800900-227-G | DIODE,Array-TVS,SRV05-4.TCT,5V,12A,G,SOT23-6,SMD | SEMTECH CORPORATION. | SRV05-4.TCT | G | PWA BOM | In Old BOM |
|  |  |  | 52180C200-086-G | Diode,Array-TVS,SRV05-4HTG,SOT-23,6P,G | LITTELFUSE FAR EAST PTE LTD | SRV05-4HTG | G | PWA BOM | In Old BOM |
| ##### Change Revision |  |  |  |  |  |  |  |  |  |
| Sheet | REV OF BOM | CUSTOMER | CUSTOMER P/N | PWA PN | PWA DESCRIPTION | PWA REV | DATE | Remark |  |
| OOOOOOOOOOOOOOOOOOOOOOOOOOOOOOOOOOOOOOOOOOOOOOOOOOOOOOOOOOOOOOOOOOOOOOOOOOOOOOOOOOOOOOOOOO | OOOOOOOOOOOOOOOOOOOOOOOOOOOOOOOOOOOOOOOOOOOOOOOOOOOOOOOOOOOOOOOOOOOOOOOOOOOOOOOOOOOOOOOOOO | OOOOOOOOOOOOOOOOOOOOOOOOOOOOOOOOOOOOOOOOOOOOOOOOOOOOOOOOOOOOOOOOOOOOOOOOOOOOOOOOOOOOOOOOOO | OOOOOOOOOOOOOOOOOOOOOOOOOOOOOOOOOOOOOOOOOOOOOOOOOOOOOOOOOOOOOOOOOOOOOOOOOOOOOOOOOOOOOOOOOO | OOOOOOOOOOOOOOOOOOOOOOOOOOOOOOOOOOOOOOOOOOOOOOOOOOOOOOOOOOOOOOOOOOOOOOOOOOOOOOOOOOOOOOOOOO | OOOOOOOOOOOOOOOOOOOOOOOOOOOOOOOOOOOOOOOOOOOOOOOOOOOOOOOOOOOOOOOOOOOOOOOOOOOOOOOOOOOOOOOOOO | OOOOOOOOOOOOOOOOOOOOOOOOOOOOOOOOOOOOOOOOOOOOOOOOOOOOOOOOOOOOOOOOOOOOOOOOOOOOOOOOOOOOOOOOOO | OOOOOOOOOOOOOOOOOOOOOOOOOOOOOOOOOOOOOOOOOOOOOOOOOOOOOOOOOOOOOOOOOOOOOOOOOOOOOOOOOOOOOOOOOO | OOOOOOOOOOOOOOOOOOOOOOOOOOOOOOOOOOOOOOOOOOOOOOOOOOOOOOOOOOOOOOOOOOOOOOOOOOOOOOOOOOOOOOOOOO | OOOOOOOOOOOOOOOOOOOOOOOOOOOOOOOOOOOOOOOOOOOOOOOOOOOOOOOOOOOOOOOOOOOOOOOOOOOOOOOOOOOOOOOOOO |
| Second Source Change |  |  |  |  |  |  |  |  |  |
| Item | Location | Change Type | Foxconn P/N | Part Description | Manufacturer Full Name | Manufacturer P/N | RoHS | Sheet |  |
| 1 | PUAC4,PSAC4,PRAC4,PQAC4,PPAC4,PIAC4,PFAC4,PEAC4,PUAC5,PSAC5,PRAC5,PQAC5,PPAC5,PIAC5,PFAC5,PEAC5,PUAC6,PSAC6,PRAC6,PQAC6,PPAC6,PIAC6,PFAC6,PEAC6 |  | 62011DD00-015-G | CAP,22uF,+/-10%,X6S,6.3V,G,SMD1206 | MURATA ELEC. NORTH AMERICA | GRM31CC80J226K | G | PWA BOM |  |
|  |  | ADD | 62011DD00-026-G | CAP,22uF,+/-10%,X6S,6.3V,G,SMD1206 | SAMSUNG SEMICONDUCTOR | CL31X226KQHNNNE | G | PWA BOM |  |
|  |  | Delete | CL31X226KQHNNNE | CAP,22uF,+/-10%,X6S,6.3V,G,SMD1206 | SAMSUNG SEMICONDUCTOR | CL31X226KQHNNNE | G | PWA BOM |  |
| OOOOOOOOOOOOOOOOOOOOOOOOOOOOOOOOOOOOOOOOOOOOOOOOOOOOOOOOOOOOOOOOOOOOOOOOOOOOOOOOOOOOOOOOOO | OOOOOOOOOOOOOOOOOOOOOOOOOOOOOOOOOOOOOOOOOOOOOOOOOOOOOOOOOOOOOOOOOOOOOOOOOOOOOOOOOOOOOOOOOO | OOOOOOOOOOOOOOOOOOOOOOOOOOOOOOOOOOOOOOOOOOOOOOOOOOOOOOOOOOOOOOOOOOOOOOOOOOOOOOOOOOOOOOOOOO | OOOOOOOOOOOOOOOOOOOOOOOOOOOOOOOOOOOOOOOOOOOOOOOOOOOOOOOOOOOOOOOOOOOOOOOOOOOOOOOOOOOOOOOOOO | OOOOOOOOOOOOOOOOOOOOOOOOOOOOOOOOOOOOOOOOOOOOOOOOOOOOOOOOOOOOOOOOOOOOOOOOOOOOOOOOOOOOOOOOOO | OOOOOOOOOOOOOOOOOOOOOOOOOOOOOOOOOOOOOOOOOOOOOOOOOOOOOOOOOOOOOOOOOOOOOOOOOOOOOOOOOOOOOOOOOO | OOOOOOOOOOOOOOOOOOOOOOOOOOOOOOOOOOOOOOOOOOOOOOOOOOOOOOOOOOOOOOOOOOOOOOOOOOOOOOOOOOOOOOOOOO | OOOOOOOOOOOOOOOOOOOOOOOOOOOOOOOOOOOOOOOOOOOOOOOOOOOOOOOOOOOOOOOOOOOOOOOOOOOOOOOOOOOOOOOOOO | OOOOOOOOOOOOOOOOOOOOOOOOOOOOOOOOOOOOOOOOOOOOOOOOOOOOOOOOOOOOOOOOOOOOOOOOOOOOOOOOOOOOOOOOOO | OOOOOOOOOOOOOOOOOOOOOOOOOOOOOOOOOOOOOOOOOOOOOOOOOOOOOOOOOOOOOOOOOOOOOOOOOOOOOOOOOOOOOOOOOO |
| Master Materials Change |  |  |  |  |  |  |  |  |  |
| Item | Foxconn P/N | Orig._Usage | New_Usage | Part Description | Manufacturer Full Name | Manufacturer P/N | RoHS | Location | Sheet |
| 1 | 521800900-227-G | 0 | 2 | DIODE,Array-TVS,SRV05-4.TCT,5V,12A,G,SOT23-6,SMD | SEMTECH CORPORATION. | SRV05-4.TCT | G | (+)ED2,ED3 | PWA BOM |
|  | 52180C200-086-G |  |  | Diode,Array-TVS,SRV05-4HTG,SOT-23,6P,G | LITTELFUSE FAR EAST PTE LTD | SRV05-4HTG |  |  | PWA BOM |
| 2 | SRV05-4ATCT | 2 | 0 | DIODE,Array-TVS,SRV05-4.TCT,5V,12A,G,SOT23-6,SMD | SEMTECH CORPORATION. | SRV05-4ATCT | G | (-)ED2,ED3 | PWA BOM |
|  | 521800900-227-G |  |  | DIODE,Array-TVS,SRV05-4.TCT,5V,12A,G,SOT23-6,SMD | SEMTECH CORPORATION. | SRV05-4.TCT |  |  | PWA BOM |
|  | 52180C200-086-G |  |  | Diode,Array-TVS,SRV05-4HTG,SOT-23,6P,G | LITTELFUSE FAR EAST PTE LTD | SRV05-4HTG |  |  | PWA BOM |
| OOOOOOOOOOOOOOOOOOOOOOOOOOOOOOOOOOOOOOOOOOOOOOOOOOOOOOOOOOOOOOOOOOOOOOOOOOOOOOOOOOOOOOOOOO | OOOOOOOOOOOOOOOOOOOOOOOOOOOOOOOOOOOOOOOOOOOOOOOOOOOOOOOOOOOOOOOOOOOOOOOOOOOOOOOOOOOOOOOOOO | OOOOOOOOOOOOOOOOOOOOOOOOOOOOOOOOOOOOOOOOOOOOOOOOOOOOOOOOOOOOOOOOOOOOOOOOOOOOOOOOOOOOOOOOOO | OOOOOOOOOOOOOOOOOOOOOOOOOOOOOOOOOOOOOOOOOOOOOOOOOOOOOOOOOOOOOOOOOOOOOOOOOOOOOOOOOOOOOOOOOO | OOOOOOOOOOOOOOOOOOOOOOOOOOOOOOOOOOOOOOOOOOOOOOOOOOOOOOOOOOOOOOOOOOOOOOOOOOOOOOOOOOOOOOOOOO | OOOOOOOOOOOOOOOOOOOOOOOOOOOOOOOOOOOOOOOOOOOOOOOOOOOOOOOOOOOOOOOOOOOOOOOOOOOOOOOOOOOOOOOOOO | OOOOOOOOOOOOOOOOOOOOOOOOOOOOOOOOOOOOOOOOOOOOOOOOOOOOOOOOOOOOOOOOOOOOOOOOOOOOOOOOOOOOOOOOOO | OOOOOOOOOOOOOOOOOOOOOOOOOOOOOOOOOOOOOOOOOOOOOOOOOOOOOOOOOOOOOOOOOOOOOOOOOOOOOOOOOOOOOOOOOO | OOOOOOOOOOOOOOOOOOOOOOOOOOOOOOOOOOOOOOOOOOOOOOOOOOOOOOOOOOOOOOOOOOOOOOOOOOOOOOOOOOOOOOOOOO | OOOOOOOOOOOOOOOOOOOOOOOOOOOOOOOOOOOOOOOOOOOOOOOOOOOOOOOOOOOOOOOOOOOOOOOOOOOOOOOOOOOOOOOOOO |
| TLA Parts Change |  |  |  |  |  |  |  |  |  |
| Item | Foxconn P/N | Qty | Part Description | Manufacturer Full Name | Manufacturer P/N | RoHS | Location | Remark | BOM |
| BOM Change List Date:Fri Nov 17 18:12:04 GMT+08:00 2017 |  |  |  |  |  |  |  |  |  |
| New BOM file : C:\<user>\ZAIUS-MB-PVT-HW-EBOM-X04-20171117.xls |  |  |  |  |  |  |  |  |  |
| Old BOM file : C:\<user>\ZAIUS-MB-PVT-HW-EBOM-X04-20171020.xls |  |  |  |  |  |  |  |  |  |
| ##### Add Parts |  |  |  |  |  |  |  |  |  |
| Item | Location | Qty | Foxconn P/N | Part Description | Manufacturer Full Name | Manufacturer P/N | RoHS | Sheet |  |
| ##### Remove Parts |  |  |  |  |  |  |  |  |  |
| Item | Location | Qty | Foxconn P/N | Part Description | Manufacturer Full Name | Manufacturer P/N | RoHS | Sheet |  |
| 1 | R1240 | 1 | 61010LA00-017-G | RES,4.7KOhm,+/-1%,1/16W,G,SMD0402 | KOA SPEER ELECTRONICS, INC. | RK73H1ETTP4701F | N | PWA BOM |  |
| ##### Change Parts |  |  |  |  |  |  |  |  |  |
| Item | Location | Qty | Foxconn P/N | Part Description | Manufacturer Full Name | Manufacturer P/N | RoHS | Sheet | Remark |
| 1 | ED2,ED3 | 2 | 521800900-227-G | DIODE,Array-TVS,SRV05-4.TCT,5V,12A,G,SOT23-6,SMD | SEMTECH CORPORATION. | SRV05-4.TCT | N | PWA BOM | In New BOM |
|  | ED2,ED3 | 2 | SRV05-4ATCT | DIODE,Array-TVS,SRV05-4.TCT,5V,12A,G,SOT23-6,SMD | SEMTECH CORPORATION. | SRV05-4ATCT | N | PWA BOM | In Old BOM |
| ##### Change Revision |  |  |  |  |  |  |  |  |  |
| Sheet | REV OF BOM | CUSTOMER | CUSTOMER P/N | PWA PN | PWA DESCRIPTION | PWA REV | DATE | Remark |  |
| OOOOOOOOOOOOOOOOOOOOOOOOOOOOOOOOOOOOOOOOOOOOOOOOOOOOOOOOOOOOOOOOOOOOOOOOOOOOOOOOOOOOOOOOOO | OOOOOOOOOOOOOOOOOOOOOOOOOOOOOOOOOOOOOOOOOOOOOOOOOOOOOOOOOOOOOOOOOOOOOOOOOOOOOOOOOOOOOOOOOO | OOOOOOOOOOOOOOOOOOOOOOOOOOOOOOOOOOOOOOOOOOOOOOOOOOOOOOOOOOOOOOOOOOOOOOOOOOOOOOOOOOOOOOOOOO | OOOOOOOOOOOOOOOOOOOOOOOOOOOOOOOOOOOOOOOOOOOOOOOOOOOOOOOOOOOOOOOOOOOOOOOOOOOOOOOOOOOOOOOOOO | OOOOOOOOOOOOOOOOOOOOOOOOOOOOOOOOOOOOOOOOOOOOOOOOOOOOOOOOOOOOOOOOOOOOOOOOOOOOOOOOOOOOOOOOOO | OOOOOOOOOOOOOOOOOOOOOOOOOOOOOOOOOOOOOOOOOOOOOOOOOOOOOOOOOOOOOOOOOOOOOOOOOOOOOOOOOOOOOOOOOO | OOOOOOOOOOOOOOOOOOOOOOOOOOOOOOOOOOOOOOOOOOOOOOOOOOOOOOOOOOOOOOOOOOOOOOOOOOOOOOOOOOOOOOOOOO | OOOOOOOOOOOOOOOOOOOOOOOOOOOOOOOOOOOOOOOOOOOOOOOOOOOOOOOOOOOOOOOOOOOOOOOOOOOOOOOOOOOOOOOOOO | OOOOOOOOOOOOOOOOOOOOOOOOOOOOOOOOOOOOOOOOOOOOOOOOOOOOOOOOOOOOOOOOOOOOOOOOOOOOOOOOOOOOOOOOOO | OOOOOOOOOOOOOOOOOOOOOOOOOOOOOOOOOOOOOOOOOOOOOOOOOOOOOOOOOOOOOOOOOOOOOOOOOOOOOOOOOOOOOOOOOO |
| Second Source Change |  |  |  |  |  |  |  |  |  |
| Item | Location | Change Type | Foxconn P/N | Part Description | Manufacturer Full Name | Manufacturer P/N | RoHS | Sheet |  |
| OOOOOOOOOOOOOOOOOOOOOOOOOOOOOOOOOOOOOOOOOOOOOOOOOOOOOOOOOOOOOOOOOOOOOOOOOOOOOOOOOOOOOOOOOO | OOOOOOOOOOOOOOOOOOOOOOOOOOOOOOOOOOOOOOOOOOOOOOOOOOOOOOOOOOOOOOOOOOOOOOOOOOOOOOOOOOOOOOOOOO | OOOOOOOOOOOOOOOOOOOOOOOOOOOOOOOOOOOOOOOOOOOOOOOOOOOOOOOOOOOOOOOOOOOOOOOOOOOOOOOOOOOOOOOOOO | OOOOOOOOOOOOOOOOOOOOOOOOOOOOOOOOOOOOOOOOOOOOOOOOOOOOOOOOOOOOOOOOOOOOOOOOOOOOOOOOOOOOOOOOOO | OOOOOOOOOOOOOOOOOOOOOOOOOOOOOOOOOOOOOOOOOOOOOOOOOOOOOOOOOOOOOOOOOOOOOOOOOOOOOOOOOOOOOOOOOO | OOOOOOOOOOOOOOOOOOOOOOOOOOOOOOOOOOOOOOOOOOOOOOOOOOOOOOOOOOOOOOOOOOOOOOOOOOOOOOOOOOOOOOOOOO | OOOOOOOOOOOOOOOOOOOOOOOOOOOOOOOOOOOOOOOOOOOOOOOOOOOOOOOOOOOOOOOOOOOOOOOOOOOOOOOOOOOOOOOOOO | OOOOOOOOOOOOOOOOOOOOOOOOOOOOOOOOOOOOOOOOOOOOOOOOOOOOOOOOOOOOOOOOOOOOOOOOOOOOOOOOOOOOOOOOOO | OOOOOOOOOOOOOOOOOOOOOOOOOOOOOOOOOOOOOOOOOOOOOOOOOOOOOOOOOOOOOOOOOOOOOOOOOOOOOOOOOOOOOOOOOO | OOOOOOOOOOOOOOOOOOOOOOOOOOOOOOOOOOOOOOOOOOOOOOOOOOOOOOOOOOOOOOOOOOOOOOOOOOOOOOOOOOOOOOOOOO |
| Master Materials Change |  |  |  |  |  |  |  |  |  |
| Item | Foxconn P/N | Orig._Usage | New_Usage | Part Description | Manufacturer Full Name | Manufacturer P/N | RoHS | Location | Sheet |
| 1 | 521800900-227-G | 0 | 2 | DIODE,Array-TVS,SRV05-4.TCT,5V,12A,G,SOT23-6,SMD | SEMTECH CORPORATION. | SRV05-4.TCT | N | (+)ED2,ED3 | PWA BOM |
| 2 | 61010LA00-017-G | 150 | 149 | RES,4.7KOhm,+/-1%,1/16W,G,SMD0402 | KOA SPEER ELECTRONICS, INC. | RK73H1ETTP4701F | N | (-)R1240 | PWA BOM |
| 3 | SRV05-4ATCT | 2 | 0 | DIODE,Array-TVS,SRV05-4.TCT,5V,12A,G,SOT23-6,SMD | SEMTECH CORPORATION. | SRV05-4ATCT | N | (-)ED2,ED3 | PWA BOM |
| OOOOOOOOOOOOOOOOOOOOOOOOOOOOOOOOOOOOOOOOOOOOOOOOOOOOOOOOOOOOOOOOOOOOOOOOOOOOOOOOOOOOOOOOOO | OOOOOOOOOOOOOOOOOOOOOOOOOOOOOOOOOOOOOOOOOOOOOOOOOOOOOOOOOOOOOOOOOOOOOOOOOOOOOOOOOOOOOOOOOO | OOOOOOOOOOOOOOOOOOOOOOOOOOOOOOOOOOOOOOOOOOOOOOOOOOOOOOOOOOOOOOOOOOOOOOOOOOOOOOOOOOOOOOOOOO | OOOOOOOOOOOOOOOOOOOOOOOOOOOOOOOOOOOOOOOOOOOOOOOOOOOOOOOOOOOOOOOOOOOOOOOOOOOOOOOOOOOOOOOOOO | OOOOOOOOOOOOOOOOOOOOOOOOOOOOOOOOOOOOOOOOOOOOOOOOOOOOOOOOOOOOOOOOOOOOOOOOOOOOOOOOOOOOOOOOOO | OOOOOOOOOOOOOOOOOOOOOOOOOOOOOOOOOOOOOOOOOOOOOOOOOOOOOOOOOOOOOOOOOOOOOOOOOOOOOOOOOOOOOOOOOO | OOOOOOOOOOOOOOOOOOOOOOOOOOOOOOOOOOOOOOOOOOOOOOOOOOOOOOOOOOOOOOOOOOOOOOOOOOOOOOOOOOOOOOOOOO | OOOOOOOOOOOOOOOOOOOOOOOOOOOOOOOOOOOOOOOOOOOOOOOOOOOOOOOOOOOOOOOOOOOOOOOOOOOOOOOOOOOOOOOOOO | OOOOOOOOOOOOOOOOOOOOOOOOOOOOOOOOOOOOOOOOOOOOOOOOOOOOOOOOOOOOOOOOOOOOOOOOOOOOOOOOOOOOOOOOOO |  |
| TLA Parts Change |  |  |  |  |  |  |  |  |  |
| Item | Foxconn P/N | Qty | Part Description | Manufacturer Full Name | Manufacturer P/N | RoHS | Location | Remark |  |
| BOM Change List Date:Tue Nov 21 14:27:38 GMT+08:00 2017 |  |  |  |  |  |  |  |  |  |
| New BOM file : E:\barreleye g2\1120\foxbis\zaius 1121.xls |  |  |  |  |  |  |  |  |  |
| Old BOM file : E:\barreleye g2\1120\foxbis\zaius 1031.xls |  |  |  |  |  |  |  |  |  |
| ##### Add Parts |  |  |  |  |  |  |  |  |  |
| Item | Location | Qty | Foxconn P/N | Part Description | Manufacturer Full Name | Manufacturer P/N | RoHS | Sheet |  |
| ##### Remove Parts |  |  |  |  |  |  |  |  |  |
| Item | Location | Qty | Foxconn P/N | Part Description | Manufacturer Full Name | Manufacturer P/N | RoHS | Sheet |  |
| 1 | R1240 | 1 | 61010LA00-017-G | RES,4.7KOhm,+/-1%,1/16W,G,SMD0402 | KOA SPEER ELECTRONICS, INC. | RK73H1ETTP4701F | G | PWA BOM |  |
|  |  |  | 61010LA00-029-G | RES,4.7KOhm,+/-1%,1/16W,G,SMD0402 | VISHAY ENTER TECHNO LOGY.INC | CRCW04024K70FKED | G | PWA BOM |  |
| ##### Change Parts |  |  |  |  |  |  |  |  |  |
| Item | Location | Qty | Foxconn P/N | Part Description | Manufacturer Full Name | Manufacturer P/N | RoHS | Sheet | Remark |
| 1 | U24 | 1 | 41050DL00-233-G | Flash,MX25L6445EMI-10G,2.7~3.6V,64M,SPI,G,SOP-16,SMD | MACRONIX INTERNATIONAL CO.,LTD. | MX25L6445EMI-10G | G | PWA BOM | In New BOM |
|  |  |  | 41050SF00-233-G | Flash,MX25L6435EMI-10G,2.7~3.6V,64M,SPI,G,SOP-16,SMD | MACRONIX INTERNATIONAL CO.,LTD. | MX25L6435EMI-10G | G | PWA BOM | In New BOM |
|  |  |  | MX25L6433FMI-08G | Flash,MX25L6433FMI-08G,2.7~3.6V,64M,SPI,G,SOP-16,SMD | MACRONIX INTERNATIONAL CO.,LTD. | MX25L6433FMI-08G | G | PWA BOM | In New BOM |
|  | U24 | 1 | 41050DL00-233-G | Flash,MX25L6445EMI-10G,2.7~3.6V,64M,SPI,G,SOP-16,SMD | MACRONIX INTERNATIONAL CO.,LTD. | MX25L6445EMI-10G | G | PWA BOM | In Old BOM |
|  |  |  | 41050SF00-233-G | Flash,MX25L6435EMI-10G,2.7~3.6V,64M,SPI,G,SOP-16,SMD | MACRONIX INTERNATIONAL CO.,LTD. | MX25L6435EMI-10G | G | PWA BOM | In Old BOM |
|  |  |  | MX25L6433FMI-08G | Flash,MX25L6433FMI-08G,2.7~3.6V,64M,SPI,G,SOP-16,SMD | MACRONIX INTERNATIONAL CO.,LTD. | MX25L6433FMI-08G |  | PWA BOM | In Old BOM |
| 2 | PBMU1,PBFU1,PBEU1,PBAU1,PAMU1,PAFU1,PAEU1,PAAU1 | 8 | ISL68137IRAZ-GG04 | IC,PWM Controller,ISL68137IRAZ-T,G,QFN-48,SMD | INTERSIL CORPORATION | ISL68137IRAZ-GG04 | G | PWA BOM | In New BOM |
|  | PBMU1,PBFU1,PBEU1,PBAU1,PAMU1,PAFU1,PAEU1,PAAU1 | 8 | 320242200-230-G | IC,PWM Controller,ISL68137IRAZ-T,G,QFN-48,SMD | INTERSIL CORPORATION | ISL68137IRAZ-T | G | PWA BOM | In Old BOM |
| ##### Change Revision |  |  |  |  |  |  |  |  |  |
| Sheet | REV OF BOM | CUSTOMER | CUSTOMER P/N | PWA PN | PWA DESCRIPTION | PWA REV | DATE | Remark |  |
| OOOOOOOOOOOOOOOOOOOOOOOOOOOOOOOOOOOOOOOOOOOOOOOOOOOOOOOOOOOOOOOOOOOOOOOOOOOOOOOOOOOOOOOOOO | OOOOOOOOOOOOOOOOOOOOOOOOOOOOOOOOOOOOOOOOOOOOOOOOOOOOOOOOOOOOOOOOOOOOOOOOOOOOOOOOOOOOOOOOOO | OOOOOOOOOOOOOOOOOOOOOOOOOOOOOOOOOOOOOOOOOOOOOOOOOOOOOOOOOOOOOOOOOOOOOOOOOOOOOOOOOOOOOOOOOO | OOOOOOOOOOOOOOOOOOOOOOOOOOOOOOOOOOOOOOOOOOOOOOOOOOOOOOOOOOOOOOOOOOOOOOOOOOOOOOOOOOOOOOOOOO | OOOOOOOOOOOOOOOOOOOOOOOOOOOOOOOOOOOOOOOOOOOOOOOOOOOOOOOOOOOOOOOOOOOOOOOOOOOOOOOOOOOOOOOOOO | OOOOOOOOOOOOOOOOOOOOOOOOOOOOOOOOOOOOOOOOOOOOOOOOOOOOOOOOOOOOOOOOOOOOOOOOOOOOOOOOOOOOOOOOOO | OOOOOOOOOOOOOOOOOOOOOOOOOOOOOOOOOOOOOOOOOOOOOOOOOOOOOOOOOOOOOOOOOOOOOOOOOOOOOOOOOOOOOOOOOO | OOOOOOOOOOOOOOOOOOOOOOOOOOOOOOOOOOOOOOOOOOOOOOOOOOOOOOOOOOOOOOOOOOOOOOOOOOOOOOOOOOOOOOOOOO | OOOOOOOOOOOOOOOOOOOOOOOOOOOOOOOOOOOOOOOOOOOOOOOOOOOOOOOOOOOOOOOOOOOOOOOOOOOOOOOOOOOOOOOOOO | OOOOOOOOOOOOOOOOOOOOOOOOOOOOOOOOOOOOOOOOOOOOOOOOOOOOOOOOOOOOOOOOOOOOOOOOOOOOOOOOOOOOOOOOOO |
| Second Source Change |  |  |  |  |  |  |  |  |  |
| Item | Location | Change Type | Foxconn P/N | Part Description | Manufacturer Full Name | Manufacturer P/N | RoHS | Sheet |  |
| OOOOOOOOOOOOOOOOOOOOOOOOOOOOOOOOOOOOOOOOOOOOOOOOOOOOOOOOOOOOOOOOOOOOOOOOOOOOOOOOOOOOOOOOOO | OOOOOOOOOOOOOOOOOOOOOOOOOOOOOOOOOOOOOOOOOOOOOOOOOOOOOOOOOOOOOOOOOOOOOOOOOOOOOOOOOOOOOOOOOO | OOOOOOOOOOOOOOOOOOOOOOOOOOOOOOOOOOOOOOOOOOOOOOOOOOOOOOOOOOOOOOOOOOOOOOOOOOOOOOOOOOOOOOOOOO | OOOOOOOOOOOOOOOOOOOOOOOOOOOOOOOOOOOOOOOOOOOOOOOOOOOOOOOOOOOOOOOOOOOOOOOOOOOOOOOOOOOOOOOOOO | OOOOOOOOOOOOOOOOOOOOOOOOOOOOOOOOOOOOOOOOOOOOOOOOOOOOOOOOOOOOOOOOOOOOOOOOOOOOOOOOOOOOOOOOOO | OOOOOOOOOOOOOOOOOOOOOOOOOOOOOOOOOOOOOOOOOOOOOOOOOOOOOOOOOOOOOOOOOOOOOOOOOOOOOOOOOOOOOOOOOO | OOOOOOOOOOOOOOOOOOOOOOOOOOOOOOOOOOOOOOOOOOOOOOOOOOOOOOOOOOOOOOOOOOOOOOOOOOOOOOOOOOOOOOOOOO | OOOOOOOOOOOOOOOOOOOOOOOOOOOOOOOOOOOOOOOOOOOOOOOOOOOOOOOOOOOOOOOOOOOOOOOOOOOOOOOOOOOOOOOOOO | OOOOOOOOOOOOOOOOOOOOOOOOOOOOOOOOOOOOOOOOOOOOOOOOOOOOOOOOOOOOOOOOOOOOOOOOOOOOOOOOOOOOOOOOOO | OOOOOOOOOOOOOOOOOOOOOOOOOOOOOOOOOOOOOOOOOOOOOOOOOOOOOOOOOOOOOOOOOOOOOOOOOOOOOOOOOOOOOOOOOO |
| Master Materials Change |  |  |  |  |  |  |  |  |  |
| Item | Foxconn P/N | Orig._Usage | New_Usage | Part Description | Manufacturer Full Name | Manufacturer P/N | RoHS | Location | Sheet |
| 1 | 61010LA00-017-G | 150 | 149 | RES,4.7KOhm,+/-1%,1/16W,G,SMD0402 | KOA SPEER ELECTRONICS, INC. | RK73H1ETTP4701F | G | (-)R1240 | PWA BOM |
|  | 61010LA00-029-G |  |  | RES,4.7KOhm,+/-1%,1/16W,G,SMD0402 | VISHAY ENTER TECHNO LOGY.INC | CRCW04024K70FKED |  |  | PWA BOM |
| 2 | ISL68137IRAZ-GG04 | 0 | 8 | IC,PWM Controller,ISL68137IRAZ-T,G,QFN-48,SMD | INTERSIL CORPORATION | ISL68137IRAZ-GG04 | G | (+)PBMU1,PBFU1,PBEU1,PBAU1,PAMU1,PAFU1,PAEU1,PAAU1 | PWA BOM |
| 3 | 320242200-230-G | 8 | 0 | IC,PWM Controller,ISL68137IRAZ-T,G,QFN-48,SMD | INTERSIL CORPORATION | ISL68137IRAZ-T | G | (-)PBMU1,PBFU1,PBEU1,PBAU1,PAMU1,PAFU1,PAEU1,PAAU1 | PWA BOM |
| OOOOOOOOOOOOOOOOOOOOOOOOOOOOOOOOOOOOOOOOOOOOOOOOOOOOOOOOOOOOOOOOOOOOOOOOOOOOOOOOOOOOOOOOOO | OOOOOOOOOOOOOOOOOOOOOOOOOOOOOOOOOOOOOOOOOOOOOOOOOOOOOOOOOOOOOOOOOOOOOOOOOOOOOOOOOOOOOOOOOO | OOOOOOOOOOOOOOOOOOOOOOOOOOOOOOOOOOOOOOOOOOOOOOOOOOOOOOOOOOOOOOOOOOOOOOOOOOOOOOOOOOOOOOOOOO | OOOOOOOOOOOOOOOOOOOOOOOOOOOOOOOOOOOOOOOOOOOOOOOOOOOOOOOOOOOOOOOOOOOOOOOOOOOOOOOOOOOOOOOOOO | OOOOOOOOOOOOOOOOOOOOOOOOOOOOOOOOOOOOOOOOOOOOOOOOOOOOOOOOOOOOOOOOOOOOOOOOOOOOOOOOOOOOOOOOOO | OOOOOOOOOOOOOOOOOOOOOOOOOOOOOOOOOOOOOOOOOOOOOOOOOOOOOOOOOOOOOOOOOOOOOOOOOOOOOOOOOOOOOOOOOO | OOOOOOOOOOOOOOOOOOOOOOOOOOOOOOOOOOOOOOOOOOOOOOOOOOOOOOOOOOOOOOOOOOOOOOOOOOOOOOOOOOOOOOOOOO | OOOOOOOOOOOOOOOOOOOOOOOOOOOOOOOOOOOOOOOOOOOOOOOOOOOOOOOOOOOOOOOOOOOOOOOOOOOOOOOOOOOOOOOOOO | OOOOOOOOOOOOOOOOOOOOOOOOOOOOOOOOOOOOOOOOOOOOOOOOOOOOOOOOOOOOOOOOOOOOOOOOOOOOOOOOOOOOOOOOOO | OOOOOOOOOOOOOOOOOOOOOOOOOOOOOOOOOOOOOOOOOOOOOOOOOOOOOOOOOOOOOOOOOOOOOOOOOOOOOOOOOOOOOOOOOO |
| TLA Parts Change |  |  |  |  |  |  |  |  |  |
| Item | Foxconn P/N | Qty | Part Description | Manufacturer Full Name | Manufacturer P/N | RoHS | Location | Remark | BOM |
| BOM Change List Date:Tue Nov 28 16:23:38 CST 2017 |  |  |  |  |  |  |  |  |  |
| New BOM file : E:\barreleye g2\1127\zaius1128.xls |  |  |  |  |  |  |  |  |  |
| Old BOM file : E:\barreleye g2\1127\zaius1120.xls |  |  |  |  |  |  |  |  |  |
| ##### Add Parts |  |  |  |  |  |  |  |  |  |
| Item | Location | Qty | Foxconn P/N | Part Description | Manufacturer Full Name | Manufacturer P/N | RoHS | Sheet |  |
| ##### Remove Parts |  |  |  |  |  |  |  |  |  |
| Item | Location | Qty | Foxconn P/N | Part Description | Manufacturer Full Name | Manufacturer P/N | RoHS | Sheet |  |
| ##### Change Parts |  |  |  |  |  |  |  |  |  |
| Item | Location | Qty | Foxconn P/N | Part Description | Manufacturer Full Name | Manufacturer P/N | RoHS | Sheet | Remark |
| 1 | U3,U4 | 2 | 320242G00-183-G | IC,Power Controller,LM3880MFX-1AA/NOPB,G,SOT-23-6,SMD | TEXAS INSTRUMENTS | LM3880MFX-1AA/NOPB | G | PWA BOM | In New BOM |
|  |  |  | LM3880MF-1AA/NOPB | IC,Power Controller,LM3880MF-1AA/NOPB,G,SOT-23-6,SMD | TEXAS INSTRUMENTS | LM3880MF-1AA/NOPB |  | PWA BOM | In New BOM |
|  | U3,U4 | 2 | 320242G00-183-G | IC,Power Controller,LM3880MFX-1AA/NOPB,G,SOT-23-6,SMD | TEXAS INSTRUMENTS | LM3880MFX-1AA/NOPB | G | PWA BOM | In Old BOM |
| ##### Change Revision |  |  |  |  |  |  |  |  |  |
| Sheet | REV OF BOM | CUSTOMER | CUSTOMER P/N | PWA PN | PWA DESCRIPTION | PWA REV | DATE | Remark |  |
| OOOOOOOOOOOOOOOOOOOOOOOOOOOOOOOOOOOOOOOOOOOOOOOOOOOOOOOOOOOOOOOOOOOOOOOOOOOOOOOOOOOOOOOOOO | OOOOOOOOOOOOOOOOOOOOOOOOOOOOOOOOOOOOOOOOOOOOOOOOOOOOOOOOOOOOOOOOOOOOOOOOOOOOOOOOOOOOOOOOOO | OOOOOOOOOOOOOOOOOOOOOOOOOOOOOOOOOOOOOOOOOOOOOOOOOOOOOOOOOOOOOOOOOOOOOOOOOOOOOOOOOOOOOOOOOO | OOOOOOOOOOOOOOOOOOOOOOOOOOOOOOOOOOOOOOOOOOOOOOOOOOOOOOOOOOOOOOOOOOOOOOOOOOOOOOOOOOOOOOOOOO | OOOOOOOOOOOOOOOOOOOOOOOOOOOOOOOOOOOOOOOOOOOOOOOOOOOOOOOOOOOOOOOOOOOOOOOOOOOOOOOOOOOOOOOOOO | OOOOOOOOOOOOOOOOOOOOOOOOOOOOOOOOOOOOOOOOOOOOOOOOOOOOOOOOOOOOOOOOOOOOOOOOOOOOOOOOOOOOOOOOOO | OOOOOOOOOOOOOOOOOOOOOOOOOOOOOOOOOOOOOOOOOOOOOOOOOOOOOOOOOOOOOOOOOOOOOOOOOOOOOOOOOOOOOOOOOO | OOOOOOOOOOOOOOOOOOOOOOOOOOOOOOOOOOOOOOOOOOOOOOOOOOOOOOOOOOOOOOOOOOOOOOOOOOOOOOOOOOOOOOOOOO | OOOOOOOOOOOOOOOOOOOOOOOOOOOOOOOOOOOOOOOOOOOOOOOOOOOOOOOOOOOOOOOOOOOOOOOOOOOOOOOOOOOOOOOOOO | OOOOOOOOOOOOOOOOOOOOOOOOOOOOOOOOOOOOOOOOOOOOOOOOOOOOOOOOOOOOOOOOOOOOOOOOOOOOOOOOOOOOOOOOOO |
| Second Source Change |  |  |  |  |  |  |  |  |  |
| Item | Location | Change Type | Foxconn P/N | Part Description | Manufacturer Full Name | Manufacturer P/N | RoHS | Sheet |  |
| 1 | U3,U4 |  | 320242G00-183-G | IC,Power Controller,LM3880MFX-1AA/NOPB,G,SOT-23-6,SMD | TEXAS INSTRUMENTS | LM3880MFX-1AA/NOPB | G | PWA BOM |  |
|  |  | ADD | LM3880MF-1AA/NOPB | IC,Power Controller,LM3880MF-1AA/NOPB,G,SOT-23-6,SMD | TEXAS INSTRUMENTS | LM3880MF-1AA/NOPB |  | PWA BOM |  |
| OOOOOOOOOOOOOOOOOOOOOOOOOOOOOOOOOOOOOOOOOOOOOOOOOOOOOOOOOOOOOOOOOOOOOOOOOOOOOOOOOOOOOOOOOO | OOOOOOOOOOOOOOOOOOOOOOOOOOOOOOOOOOOOOOOOOOOOOOOOOOOOOOOOOOOOOOOOOOOOOOOOOOOOOOOOOOOOOOOOOO | OOOOOOOOOOOOOOOOOOOOOOOOOOOOOOOOOOOOOOOOOOOOOOOOOOOOOOOOOOOOOOOOOOOOOOOOOOOOOOOOOOOOOOOOOO | OOOOOOOOOOOOOOOOOOOOOOOOOOOOOOOOOOOOOOOOOOOOOOOOOOOOOOOOOOOOOOOOOOOOOOOOOOOOOOOOOOOOOOOOOO | OOOOOOOOOOOOOOOOOOOOOOOOOOOOOOOOOOOOOOOOOOOOOOOOOOOOOOOOOOOOOOOOOOOOOOOOOOOOOOOOOOOOOOOOOO | OOOOOOOOOOOOOOOOOOOOOOOOOOOOOOOOOOOOOOOOOOOOOOOOOOOOOOOOOOOOOOOOOOOOOOOOOOOOOOOOOOOOOOOOOO | OOOOOOOOOOOOOOOOOOOOOOOOOOOOOOOOOOOOOOOOOOOOOOOOOOOOOOOOOOOOOOOOOOOOOOOOOOOOOOOOOOOOOOOOOO | OOOOOOOOOOOOOOOOOOOOOOOOOOOOOOOOOOOOOOOOOOOOOOOOOOOOOOOOOOOOOOOOOOOOOOOOOOOOOOOOOOOOOOOOOO | OOOOOOOOOOOOOOOOOOOOOOOOOOOOOOOOOOOOOOOOOOOOOOOOOOOOOOOOOOOOOOOOOOOOOOOOOOOOOOOOOOOOOOOOOO | OOOOOOOOOOOOOOOOOOOOOOOOOOOOOOOOOOOOOOOOOOOOOOOOOOOOOOOOOOOOOOOOOOOOOOOOOOOOOOOOOOOOOOOOOO |
| Master Materials Change |  |  |  |  |  |  |  |  |  |
| Item | Foxconn P/N | Orig._Usage | New_Usage | Part Description | Manufacturer Full Name | Manufacturer P/N | RoHS | Location | Sheet |
| OOOOOOOOOOOOOOOOOOOOOOOOOOOOOOOOOOOOOOOOOOOOOOOOOOOOOOOOOOOOOOOOOOOOOOOOOOOOOOOOOOOOOOOOOO | OOOOOOOOOOOOOOOOOOOOOOOOOOOOOOOOOOOOOOOOOOOOOOOOOOOOOOOOOOOOOOOOOOOOOOOOOOOOOOOOOOOOOOOOOO | OOOOOOOOOOOOOOOOOOOOOOOOOOOOOOOOOOOOOOOOOOOOOOOOOOOOOOOOOOOOOOOOOOOOOOOOOOOOOOOOOOOOOOOOOO | OOOOOOOOOOOOOOOOOOOOOOOOOOOOOOOOOOOOOOOOOOOOOOOOOOOOOOOOOOOOOOOOOOOOOOOOOOOOOOOOOOOOOOOOOO | OOOOOOOOOOOOOOOOOOOOOOOOOOOOOOOOOOOOOOOOOOOOOOOOOOOOOOOOOOOOOOOOOOOOOOOOOOOOOOOOOOOOOOOOOO | OOOOOOOOOOOOOOOOOOOOOOOOOOOOOOOOOOOOOOOOOOOOOOOOOOOOOOOOOOOOOOOOOOOOOOOOOOOOOOOOOOOOOOOOOO | OOOOOOOOOOOOOOOOOOOOOOOOOOOOOOOOOOOOOOOOOOOOOOOOOOOOOOOOOOOOOOOOOOOOOOOOOOOOOOOOOOOOOOOOOO | OOOOOOOOOOOOOOOOOOOOOOOOOOOOOOOOOOOOOOOOOOOOOOOOOOOOOOOOOOOOOOOOOOOOOOOOOOOOOOOOOOOOOOOOOO | OOOOOOOOOOOOOOOOOOOOOOOOOOOOOOOOOOOOOOOOOOOOOOOOOOOOOOOOOOOOOOOOOOOOOOOOOOOOOOOOOOOOOOOOOO | OOOOOOOOOOOOOOOOOOOOOOOOOOOOOOOOOOOOOOOOOOOOOOOOOOOOOOOOOOOOOOOOOOOOOOOOOOOOOOOOOOOOOOOOOO |
| TLA Parts Change |  |  |  |  |  |  |  |  |  |
| Item | Foxconn P/N | Qty | Part Description | Manufacturer Full Name | Manufacturer P/N | RoHS | Location | Remark | BOM |
| BOM Change List Date:Mon Dec 04 15:37:31 GMT+08:00 2017 |  |  |  |  |  |  |  |  |  |
| New BOM file : C:\<user>\ZAIUS-MB-PVT-HW-EBOM-X04-20171204.xls |  |  |  |  |  |  |  |  |  |
| Old BOM file : C:\<user>\ZAIUS-MB-PVT-HW-EBOM-X04-20171117.xls |  |  |  |  |  |  |  |  |  |
| ##### Add Parts |  |  |  |  |  |  |  |  |  |
| Item | Location | Qty | Foxconn P/N | Part Description | Manufacturer Full Name | Manufacturer P/N | RoHS | Sheet |  |
| 1 | PBAC20 | 1 | 62011J601-015-G | CAP,2.2uF,+/-10%,X7R,100V,G,SMD1210 | MURATA ELEC. NORTH AMERICA | GRM32ER72A225K |  | PWA BOM |  |
| 2 | R2045,R2046,R2047,R2048,R2049,R2050,R2051,R2052 | 8 | 610107A00-017-G | RES,0 Ohm,+/-5%,1/16W,G,SMD0402 | KOA SPEER ELECTRONICS, INC. | RK73Z1ETTP | N | PWA BOM |  |
| 3 | PAAR70,PBAR71 | 2 | 610100C00-017-G | RES,15kOhm,+/-1%,1/10W,G,SMD0603 | KOA SPEER ELECTRONICS, INC. | RK73H1JTTD1502F | N | PWA BOM |  |
| ##### Remove Parts |  |  |  |  |  |  |  |  |  |
| Item | Location | Qty | Foxconn P/N | Part Description | Manufacturer Full Name | Manufacturer P/N | RoHS | Sheet |  |
| 1 | PBAC21 | 1 | 62011J601-015-G | CAP,2.2uF,+/-10%,X7R,100V,G,SMD1210 | MURATA ELEC. NORTH AMERICA | GRM32ER72A225K |  | PWA BOM |  |
| ##### Change Parts |  |  |  |  |  |  |  |  |  |
| Item | Location | Qty | Foxconn P/N | Part Description | Manufacturer Full Name | Manufacturer P/N | RoHS | Sheet | Remark |
| 1 | PBAR127,PAAR127 | 2 | 61010PS00-017-G | RES,200KOhm,+/-1%,1/16W,G,SMD0402 | KOA SPEER ELECTRONICS, INC. | RK73H1ETTP2003F | N | PWA BOM | In New BOM |
|  | PBAR127,PAAR127 | 2 | 61011G600-017-G | RES,133KOhm,+/-1%,1/16W,G,SMD0402 | KOA SPEER ELECTRONICS, INC. | RK73G1ETTP1333F |  | PWA BOM | In Old BOM |
| 2 | PAAR66,PBAR67,PBAR79,PAAR79 | 4 | 61010R900-017-G | RES,27.4KOhm,+/-1%,1/10W,G,SMD0603 | KOA SPEER ELECTRONICS, INC. | RK73H1JTTD2742F | N | PWA BOM | In New BOM |
|  | PAAR66,PBAR67,PBAR79,PAAR79 | 4 | 610103D00-017-G | RES,24.3KOhm,+/-1%,1/10W,G,SMD0603 | KOA SPEER ELECTRONICS, INC. | RK73H1JTTD2432F | N | PWA BOM | In Old BOM |
| 3 | PAAR67,PBAR68 | 2 | 61010G500-017-G | RES,10KOhm,+/-1%,1/16W,G,SMD0402 | KOA SPEER ELECTRONICS, INC. | RK73H1ETTP1002F | N | PWA BOM | In New BOM |
|  | PAAR67,PBAR68 | 2 | 610107A00-017-G | RES,0 Ohm,+/-5%,1/16W,G,SMD0402 | KOA SPEER ELECTRONICS, INC. | RK73Z1ETTP | N | PWA BOM | In Old BOM |
| 4 | PBAR80,PAAR80 | 2 | 610100C00-017-G | RES,15kOhm,+/-1%,1/10W,G,SMD0603 | KOA SPEER ELECTRONICS, INC. | RK73H1JTTD1502F | N | PWA BOM | In New BOM |
|  | PBAR80,PAAR80 | 2 | 61010DG00-017-G | RES,4.99KOhm,+/-1%,1/10W,G,SMD0603 | KOA SPEER ELECTRONICS, INC. | RK73H1JTTD4991F | N | PWA BOM | In Old BOM |
| 5 | PBMR34,PAMR34 | 2 | 61100YW00-017-G | RES,316 Ohm,+/-0.1%,1/16W,G,SMD0402 | KOA SPEER ELECTRONICS, INC. | RN731ETTP3160B25 |  | PWA BOM | In New BOM |
|  | PBMR34,PAMR34 | 2 | RN731ETTP3160B25 | RES,316 Ohm,+/-0.1%,1/16W,G,SMD0402 | KOA SPEER ELECTRONICS, INC. | RN731ETTP3160B25 | N | PWA BOM | In Old BOM |
| 6 | PBAR34,PAAR34 | 2 | KOA_RN731ETTP5900B25 | RES,590Ohm,+/-0.1%,1/16W,G,SMD0402 | KOA SPEER ELECTRONICS, INC. | RN731ETTP5900B25 | Y | PWA BOM | In New BOM |
|  | PBAR34,PAAR34 | 2 | 611003D00-017-G | RES,1KOhm,+/-0.1%,1/16W,G,SMD0402 | KOA SPEER ELECTRONICS, INC. | RN731ETTP1001B25 | Y | PWA BOM | In Old BOM |
| ##### Change Revision |  |  |  |  |  |  |  |  |  |
| Sheet | REV OF BOM | CUSTOMER | CUSTOMER P/N | PWA PN | PWA DESCRIPTION | PWA REV | DATE | Remark |  |
| OOOOOOOOOOOOOOOOOOOOOOOOOOOOOOOOOOOOOOOOOOOOOOOOOOOOOOOOOOOOOOOOOOOOOOOOOOOOOOOOOOOOOOOOOO | OOOOOOOOOOOOOOOOOOOOOOOOOOOOOOOOOOOOOOOOOOOOOOOOOOOOOOOOOOOOOOOOOOOOOOOOOOOOOOOOOOOOOOOOOO | OOOOOOOOOOOOOOOOOOOOOOOOOOOOOOOOOOOOOOOOOOOOOOOOOOOOOOOOOOOOOOOOOOOOOOOOOOOOOOOOOOOOOOOOOO | OOOOOOOOOOOOOOOOOOOOOOOOOOOOOOOOOOOOOOOOOOOOOOOOOOOOOOOOOOOOOOOOOOOOOOOOOOOOOOOOOOOOOOOOOO | OOOOOOOOOOOOOOOOOOOOOOOOOOOOOOOOOOOOOOOOOOOOOOOOOOOOOOOOOOOOOOOOOOOOOOOOOOOOOOOOOOOOOOOOOO | OOOOOOOOOOOOOOOOOOOOOOOOOOOOOOOOOOOOOOOOOOOOOOOOOOOOOOOOOOOOOOOOOOOOOOOOOOOOOOOOOOOOOOOOOO | OOOOOOOOOOOOOOOOOOOOOOOOOOOOOOOOOOOOOOOOOOOOOOOOOOOOOOOOOOOOOOOOOOOOOOOOOOOOOOOOOOOOOOOOOO | OOOOOOOOOOOOOOOOOOOOOOOOOOOOOOOOOOOOOOOOOOOOOOOOOOOOOOOOOOOOOOOOOOOOOOOOOOOOOOOOOOOOOOOOOO | OOOOOOOOOOOOOOOOOOOOOOOOOOOOOOOOOOOOOOOOOOOOOOOOOOOOOOOOOOOOOOOOOOOOOOOOOOOOOOOOOOOOOOOOOO | OOOOOOOOOOOOOOOOOOOOOOOOOOOOOOOOOOOOOOOOOOOOOOOOOOOOOOOOOOOOOOOOOOOOOOOOOOOOOOOOOOOOOOOOOO |
| Second Source Change |  |  |  |  |  |  |  |  |  |
| Item | Location | Change Type | Foxconn P/N | Part Description | Manufacturer Full Name | Manufacturer P/N | RoHS | Sheet |  |
| OOOOOOOOOOOOOOOOOOOOOOOOOOOOOOOOOOOOOOOOOOOOOOOOOOOOOOOOOOOOOOOOOOOOOOOOOOOOOOOOOOOOOOOOOO | OOOOOOOOOOOOOOOOOOOOOOOOOOOOOOOOOOOOOOOOOOOOOOOOOOOOOOOOOOOOOOOOOOOOOOOOOOOOOOOOOOOOOOOOOO | OOOOOOOOOOOOOOOOOOOOOOOOOOOOOOOOOOOOOOOOOOOOOOOOOOOOOOOOOOOOOOOOOOOOOOOOOOOOOOOOOOOOOOOOOO | OOOOOOOOOOOOOOOOOOOOOOOOOOOOOOOOOOOOOOOOOOOOOOOOOOOOOOOOOOOOOOOOOOOOOOOOOOOOOOOOOOOOOOOOOO | OOOOOOOOOOOOOOOOOOOOOOOOOOOOOOOOOOOOOOOOOOOOOOOOOOOOOOOOOOOOOOOOOOOOOOOOOOOOOOOOOOOOOOOOOO | OOOOOOOOOOOOOOOOOOOOOOOOOOOOOOOOOOOOOOOOOOOOOOOOOOOOOOOOOOOOOOOOOOOOOOOOOOOOOOOOOOOOOOOOOO | OOOOOOOOOOOOOOOOOOOOOOOOOOOOOOOOOOOOOOOOOOOOOOOOOOOOOOOOOOOOOOOOOOOOOOOOOOOOOOOOOOOOOOOOOO | OOOOOOOOOOOOOOOOOOOOOOOOOOOOOOOOOOOOOOOOOOOOOOOOOOOOOOOOOOOOOOOOOOOOOOOOOOOOOOOOOOOOOOOOOO | OOOOOOOOOOOOOOOOOOOOOOOOOOOOOOOOOOOOOOOOOOOOOOOOOOOOOOOOOOOOOOOOOOOOOOOOOOOOOOOOOOOOOOOOOO | OOOOOOOOOOOOOOOOOOOOOOOOOOOOOOOOOOOOOOOOOOOOOOOOOOOOOOOOOOOOOOOOOOOOOOOOOOOOOOOOOOOOOOOOOO |
| Master Materials Change |  |  |  |  |  |  |  |  |  |
| Item | Foxconn P/N | Orig._Usage | New_Usage | Part Description | Manufacturer Full Name | Manufacturer P/N | RoHS | Location | Sheet |
| 1 | 610107A00-017-G | 714 | 720 | RES,0 Ohm,+/-5%,1/16W,G,SMD0402 | KOA SPEER ELECTRONICS, INC. | RK73Z1ETTP | N | (+)R2045,R2046,R2047,R2048,R2049,R2050,R2051,R2052 (-)PAAR67,PBAR68 | PWA BOM |
| 2 | 61010PS00-017-G | 48 | 50 | RES,200KOhm,+/-1%,1/16W,G,SMD0402 | KOA SPEER ELECTRONICS, INC. | RK73H1ETTP2003F | N | (+)PBAR127,PAAR127 | PWA BOM |
| 3 | 611003D00-017-G | 10 | 8 | RES,1KOhm,+/-0.1%,1/16W,G,SMD0402 | KOA SPEER ELECTRONICS, INC. | RN731ETTP1001B25 | Y | (-)PBAR34,PAAR34 | PWA BOM |
| 4 | 61010R900-017-G | 4 | 8 | RES,27.4KOhm,+/-1%,1/10W,G,SMD0603 | KOA SPEER ELECTRONICS, INC. | RK73H1JTTD2742F | N | (+)PAAR66,PBAR67,PBAR79,PAAR79 | PWA BOM |
| 5 | 61010G500-017-G | 100 | 102 | RES,10KOhm,+/-1%,1/16W,G,SMD0402 | KOA SPEER ELECTRONICS, INC. | RK73H1ETTP1002F | N | (+)PAAR67,PBAR68 | PWA BOM |
| 6 | 610100C00-017-G | 0 | 4 | RES,15kOhm,+/-1%,1/10W,G,SMD0603 | KOA SPEER ELECTRONICS, INC. | RK73H1JTTD1502F | N | (+)PAAR70,PBAR71,PBAR80,PAAR80 | PWA BOM |
| 7 | 61100YW00-017-G | 0 | 2 | RES,316 Ohm,+/-0.1%,1/16W,G,SMD0402 | KOA SPEER ELECTRONICS, INC. | RN731ETTP3160B25 |  | (+)PBMR34,PAMR34 | PWA BOM |
| 8 | KOA_RN731ETTP5900B25 | 0 | 2 | RES,590Ohm,+/-0.1%,1/16W,G,SMD0402 | KOA SPEER ELECTRONICS, INC. | RN731ETTP5900B25 | Y | (+)PBAR34,PAAR34 | PWA BOM |
| 9 | 610103D00-017-G | 4 | 0 | RES,24.3KOhm,+/-1%,1/10W,G,SMD0603 | KOA SPEER ELECTRONICS, INC. | RK73H1JTTD2432F | N | (-)PAAR66,PBAR67,PBAR79,PAAR79 | PWA BOM |
| 10 | 61010DG00-017-G | 2 | 0 | RES,4.99KOhm,+/-1%,1/10W,G,SMD0603 | KOA SPEER ELECTRONICS, INC. | RK73H1JTTD4991F | N | (-)PBAR80,PAAR80 | PWA BOM |
| 11 | 61011G600-017-G | 2 | 0 | RES,133KOhm,+/-1%,1/16W,G,SMD0402 | KOA SPEER ELECTRONICS, INC. | RK73G1ETTP1333F |  | (-)PBAR127,PAAR127 | PWA BOM |
| 12 | RN731ETTP3160B25 | 2 | 0 | RES,316 Ohm,+/-0.1%,1/16W,G,SMD0402 | KOA SPEER ELECTRONICS, INC. | RN731ETTP3160B25 | N | (-)PBMR34,PAMR34 | PWA BOM |
| OOOOOOOOOOOOOOOOOOOOOOOOOOOOOOOOOOOOOOOOOOOOOOOOOOOOOOOOOOOOOOOOOOOOOOOOOOOOOOOOOOOOOOOOOO | OOOOOOOOOOOOOOOOOOOOOOOOOOOOOOOOOOOOOOOOOOOOOOOOOOOOOOOOOOOOOOOOOOOOOOOOOOOOOOOOOOOOOOOOOO | OOOOOOOOOOOOOOOOOOOOOOOOOOOOOOOOOOOOOOOOOOOOOOOOOOOOOOOOOOOOOOOOOOOOOOOOOOOOOOOOOOOOOOOOOO | OOOOOOOOOOOOOOOOOOOOOOOOOOOOOOOOOOOOOOOOOOOOOOOOOOOOOOOOOOOOOOOOOOOOOOOOOOOOOOOOOOOOOOOOOO | OOOOOOOOOOOOOOOOOOOOOOOOOOOOOOOOOOOOOOOOOOOOOOOOOOOOOOOOOOOOOOOOOOOOOOOOOOOOOOOOOOOOOOOOOO | OOOOOOOOOOOOOOOOOOOOOOOOOOOOOOOOOOOOOOOOOOOOOOOOOOOOOOOOOOOOOOOOOOOOOOOOOOOOOOOOOOOOOOOOOO | OOOOOOOOOOOOOOOOOOOOOOOOOOOOOOOOOOOOOOOOOOOOOOOOOOOOOOOOOOOOOOOOOOOOOOOOOOOOOOOOOOOOOOOOOO | OOOOOOOOOOOOOOOOOOOOOOOOOOOOOOOOOOOOOOOOOOOOOOOOOOOOOOOOOOOOOOOOOOOOOOOOOOOOOOOOOOOOOOOOOO | OOOOOOOOOOOOOOOOOOOOOOOOOOOOOOOOOOOOOOOOOOOOOOOOOOOOOOOOOOOOOOOOOOOOOOOOOOOOOOOOOOOOOOOOOO |  |
| TLA Parts Change |  |  |  |  |  |  |  |  |  |
| Item | Foxconn P/N | Qty | Part Description | Manufacturer Full Name | Manufacturer P/N | RoHS | Location | Remark |  |
| BOM Change List Date:Tue Dec 05 09:05:34 CST 2017 |  |  |  |  |  |  |  |  |  |
| New BOM file : E:\barreleye g2\1205\ZAIUS-MB-PVT-X04-BOM_X27_20171204.xls |  |  |  |  |  |  |  |  |  |
| Old BOM file : E:\barreleye g2\1205\zaius 1128.xls |  |  |  |  |  |  |  |  |  |
| ##### Add Parts |  |  |  |  |  |  |  |  |  |
| Item | Location | Qty | Foxconn P/N | Part Description | Manufacturer Full Name | Manufacturer P/N | RoHS | Sheet |  |
| 1 | PBAC20 | 1 | 62011J601-015-G | CAP,2.2uF,+/-10%,X7R,100V,G,SMD1210 | MURATA ELEC. NORTH AMERICA | GRM32ER72A225K | G | PWA BOM |  |
|  |  |  | 62011J600-026-G | CAP,2.2uF,+/-10%,X7R,100V,G,SMD1210 | SAMSUNG SEMICONDUCTOR | CL32B225KCJSNNE | G | PWA BOM |  |
| 2 | R2045,R2046,R2047,R2048,R2049,R2050,R2051,R2052 | 8 | 610107A00-017-G | RES,0 Ohm,+/-5%,1/16W,G,SMD0402 | KOA SPEER ELECTRONICS, INC. | RK73Z1ETTP | G | PWA BOM |  |
|  |  |  | 610107A00-024-G | RES,0 Ohm,+/-5%,1/16W,G,SMD0402 | PANASONIC INDUSTRIAL CO.,LTD. | ERJ2GE0R00X | G | PWA BOM |  |
|  |  |  | 610107A00-029-G | RES,0 Ohm,+/-5%,1/16W,G,SMD0402 | VISHAY ENTER TECHNO LOGY.INC | CRCW04020000Z0ED | G | PWA BOM |  |
| 3 | PAAR70,PBAR71 | 2 | 610100C00-017-G | RES,15kOhm,+/-1%,1/10W,G,SMD0603 | KOA SPEER ELECTRONICS, INC. | RK73H1JTTD1502F | G | PWA BOM |  |
| ##### Remove Parts |  |  |  |  |  |  |  |  |  |
| Item | Location | Qty | Foxconn P/N | Part Description | Manufacturer Full Name | Manufacturer P/N | RoHS | Sheet |  |
| 1 | PBAC21 | 1 | 62011J601-015-G | CAP,2.2uF,+/-10%,X7R,100V,G,SMD1210 | MURATA ELEC. NORTH AMERICA | GRM32ER72A225K | G | PWA BOM |  |
|  |  |  | 62011J600-026-G | CAP,2.2uF,+/-10%,X7R,100V,G,SMD1210 | SAMSUNG SEMICONDUCTOR | CL32B225KCJSNNE | G | PWA BOM |  |
| ##### Change Parts |  |  |  |  |  |  |  |  |  |
| Item | Location | Qty | Foxconn P/N | Part Description | Manufacturer Full Name | Manufacturer P/N | RoHS | Sheet | Remark |
| 1 | U3,U4 | 2 | 320242G00-183-G | IC,Power Controller,LM3880MFX-1AA/NOPB,G,SOT-23-6,SMD | TEXAS INSTRUMENTS | LM3880MFX-1AA/NOPB | G | PWA BOM | In New BOM |
|  |  |  | LM3880MF-1AA/NOPB | IC,Power Controller,LM3880MF-1AA/NOPB,G,SOT-23-6,SMD | TEXAS INSTRUMENTS | LM3880MF-1AA/NOPB | G | PWA BOM | In New BOM |
|  | U3,U4 | 2 | 320242G00-183-G | IC,Power Controller,LM3880MFX-1AA/NOPB,G,SOT-23-6,SMD | TEXAS INSTRUMENTS | LM3880MFX-1AA/NOPB | G | PWA BOM | In Old BOM |
|  |  |  | LM3880MF-1AA/NOPB | IC,Power Controller,LM3880MF-1AA/NOPB,G,SOT-23-6,SMD | TEXAS INSTRUMENTS | LM3880MF-1AA/NOPB |  | PWA BOM | In Old BOM |
| 2 | PBAR127,PAAR127 | 2 | 61010PS00-017-G | RES,200KOhm,+/-1%,1/16W,G,SMD0402 | KOA SPEER ELECTRONICS, INC. | RK73H1ETTP2003F | G | PWA BOM | In New BOM |
|  |  |  | 61010PS00-029-G | RES,200KOhm,+/-1%,1/16W,G,SMD0402 | VISHAY ENTER TECHNO LOGY.INC | CRCW0402200KFKED | G | PWA BOM | In New BOM |
|  | PBAR127,PAAR127 | 2 | 61011G600-017-G | RES,133KOhm,+/-1%,1/16W,G,SMD0402 | KOA SPEER ELECTRONICS, INC. | RK73G1ETTP1333F | G | PWA BOM | In Old BOM |
| 3 | PAAR66,PBAR67,PBAR79,PAAR79 | 4 | 61010R900-017-G | RES,27.4KOhm,+/-1%,1/10W,G,SMD0603 | KOA SPEER ELECTRONICS, INC. | RK73H1JTTD2742F | G | PWA BOM | In New BOM |
|  |  |  | 61010R900-011-G | RES,27.4KOhm,+/-1%,1/10W,G,SMD0603 | YAGEO CORPORATION COMPONENT | RC0603FR-0727K4L | G | PWA BOM | In New BOM |
|  |  |  | 61010R901-029-G | RES,thick film,27.4KOhm,+/-1%,1/10W,SMD0603,G | VISHAY ENTER TECHNO LOGY.INC | CRCW060327K4FKEB | G | PWA BOM | In New BOM |
|  | PAAR66,PBAR67,PBAR79,PAAR79 | 4 | 610103D00-017-G | RES,24.3KOhm,+/-1%,1/10W,G,SMD0603 | KOA SPEER ELECTRONICS, INC. | RK73H1JTTD2432F | G | PWA BOM | In Old BOM |
| 4 | PAAR67,PBAR68 | 2 | 61010G500-017-G | RES,10KOhm,+/-1%,1/16W,G,SMD0402 | KOA SPEER ELECTRONICS, INC. | RK73H1ETTP1002F | G | PWA BOM | In New BOM |
|  |  |  | 61010G500-029-G | RES,10KOhm,+/-1%,1/16W,G,SMD0402 | VISHAY ENTER TECHNO LOGY.INC | CRCW040210K0FKED | G | PWA BOM | In New BOM |
|  |  |  | 61010G500-024-G | RES,10KOhm,+/-1%,1/16W,G,SMD0402 | PANASONIC INDUSTRIAL CO.,LTD. | ERJ2RKF1002X | G | PWA BOM | In New BOM |
|  | PAAR67,PBAR68 | 2 | 610107A00-017-G | RES,0 Ohm,+/-5%,1/16W,G,SMD0402 | KOA SPEER ELECTRONICS, INC. | RK73Z1ETTP | G | PWA BOM | In Old BOM |
|  |  |  | 610107A00-024-G | RES,0 Ohm,+/-5%,1/16W,G,SMD0402 | PANASONIC INDUSTRIAL CO.,LTD. | ERJ2GE0R00X | G | PWA BOM | In Old BOM |
|  |  |  | 610107A00-029-G | RES,0 Ohm,+/-5%,1/16W,G,SMD0402 | VISHAY ENTER TECHNO LOGY.INC | CRCW04020000Z0ED | G | PWA BOM | In Old BOM |
| 5 | PBAR80,PAAR80 | 2 | 610100C00-017-G | RES,15kOhm,+/-1%,1/10W,G,SMD0603 | KOA SPEER ELECTRONICS, INC. | RK73H1JTTD1502F | G | PWA BOM | In New BOM |
|  | PBAR80,PAAR80 | 2 | 61010DG00-017-G | RES,4.99KOhm,+/-1%,1/10W,G,SMD0603 | KOA SPEER ELECTRONICS, INC. | RK73H1JTTD4991F | G | PWA BOM | In Old BOM |
| 6 | PBAR34,PAAR34 | 2 | KOA_RN731ETTP5900B25 | RES,590Ohm,+/-0.1%,1/16W,G,SMD0402 | KOA SPEER ELECTRONICS, INC. | RN731ETTP5900B25 | G | PWA BOM | In New BOM |
|  |  |  | TNPW0402590RBEED | RES,590Ohm,+/-0.1%,1/16W,G,SMD0402 | VISHAY ENTER TECHNO LOGY.INC | TNPW0402590RBEED | G | PWA BOM | In New BOM |
|  |  |  | ERA2AEB5900X | RES,590Ohm,+/-0.1%,1/16W,G,SMD0402 | PANASONIC INDUSTRIAL CO.,LTD. | ERA2AEB5900X | G | PWA BOM | In New BOM |
|  | PBAR34,PAAR34 | 2 | 611003D00-017-G | RES,1KOhm,+/-0.1%,1/16W,G,SMD0402 | KOA SPEER ELECTRONICS, INC. | RN731ETTP1001B25 | G | PWA BOM | In Old BOM |
|  |  |  | 611003D07-029-G | RES,1KOhm,+/-0.1%,1/16W,G,SMD0402 | VISHAY ENTER TECHNO LOGY.INC | MCS04020D1001BE000 | G | PWA BOM | In Old BOM |
|  |  |  | 611003D00-024-G | RES,thin film,1KOhm,+/-0.1%,1/16W,SMD0402,G | PANASONIC INDUSTRIAL CO.,LTD. | ERA2AEB102X | G | PWA BOM | In Old BOM |
| ##### Change Revision |  |  |  |  |  |  |  |  |  |
| Sheet | REV OF BOM | CUSTOMER | CUSTOMER P/N | PWA PN | PWA DESCRIPTION | PWA REV | DATE | Remark |  |
| OOOOOOOOOOOOOOOOOOOOOOOOOOOOOOOOOOOOOOOOOOOOOOOOOOOOOOOOOOOOOOOOOOOOOOOOOOOOOOOOOOOOOOOOOO | OOOOOOOOOOOOOOOOOOOOOOOOOOOOOOOOOOOOOOOOOOOOOOOOOOOOOOOOOOOOOOOOOOOOOOOOOOOOOOOOOOOOOOOOOO | OOOOOOOOOOOOOOOOOOOOOOOOOOOOOOOOOOOOOOOOOOOOOOOOOOOOOOOOOOOOOOOOOOOOOOOOOOOOOOOOOOOOOOOOOO | OOOOOOOOOOOOOOOOOOOOOOOOOOOOOOOOOOOOOOOOOOOOOOOOOOOOOOOOOOOOOOOOOOOOOOOOOOOOOOOOOOOOOOOOOO | OOOOOOOOOOOOOOOOOOOOOOOOOOOOOOOOOOOOOOOOOOOOOOOOOOOOOOOOOOOOOOOOOOOOOOOOOOOOOOOOOOOOOOOOOO | OOOOOOOOOOOOOOOOOOOOOOOOOOOOOOOOOOOOOOOOOOOOOOOOOOOOOOOOOOOOOOOOOOOOOOOOOOOOOOOOOOOOOOOOOO | OOOOOOOOOOOOOOOOOOOOOOOOOOOOOOOOOOOOOOOOOOOOOOOOOOOOOOOOOOOOOOOOOOOOOOOOOOOOOOOOOOOOOOOOOO | OOOOOOOOOOOOOOOOOOOOOOOOOOOOOOOOOOOOOOOOOOOOOOOOOOOOOOOOOOOOOOOOOOOOOOOOOOOOOOOOOOOOOOOOOO | OOOOOOOOOOOOOOOOOOOOOOOOOOOOOOOOOOOOOOOOOOOOOOOOOOOOOOOOOOOOOOOOOOOOOOOOOOOOOOOOOOOOOOOOOO | OOOOOOOOOOOOOOOOOOOOOOOOOOOOOOOOOOOOOOOOOOOOOOOOOOOOOOOOOOOOOOOOOOOOOOOOOOOOOOOOOOOOOOOOOO |
| Second Source Change |  |  |  |  |  |  |  |  |  |
| Item | Location | Change Type | Foxconn P/N | Part Description | Manufacturer Full Name | Manufacturer P/N | RoHS | Sheet |  |
| OOOOOOOOOOOOOOOOOOOOOOOOOOOOOOOOOOOOOOOOOOOOOOOOOOOOOOOOOOOOOOOOOOOOOOOOOOOOOOOOOOOOOOOOOO | OOOOOOOOOOOOOOOOOOOOOOOOOOOOOOOOOOOOOOOOOOOOOOOOOOOOOOOOOOOOOOOOOOOOOOOOOOOOOOOOOOOOOOOOOO | OOOOOOOOOOOOOOOOOOOOOOOOOOOOOOOOOOOOOOOOOOOOOOOOOOOOOOOOOOOOOOOOOOOOOOOOOOOOOOOOOOOOOOOOOO | OOOOOOOOOOOOOOOOOOOOOOOOOOOOOOOOOOOOOOOOOOOOOOOOOOOOOOOOOOOOOOOOOOOOOOOOOOOOOOOOOOOOOOOOOO | OOOOOOOOOOOOOOOOOOOOOOOOOOOOOOOOOOOOOOOOOOOOOOOOOOOOOOOOOOOOOOOOOOOOOOOOOOOOOOOOOOOOOOOOOO | OOOOOOOOOOOOOOOOOOOOOOOOOOOOOOOOOOOOOOOOOOOOOOOOOOOOOOOOOOOOOOOOOOOOOOOOOOOOOOOOOOOOOOOOOO | OOOOOOOOOOOOOOOOOOOOOOOOOOOOOOOOOOOOOOOOOOOOOOOOOOOOOOOOOOOOOOOOOOOOOOOOOOOOOOOOOOOOOOOOOO | OOOOOOOOOOOOOOOOOOOOOOOOOOOOOOOOOOOOOOOOOOOOOOOOOOOOOOOOOOOOOOOOOOOOOOOOOOOOOOOOOOOOOOOOOO | OOOOOOOOOOOOOOOOOOOOOOOOOOOOOOOOOOOOOOOOOOOOOOOOOOOOOOOOOOOOOOOOOOOOOOOOOOOOOOOOOOOOOOOOOO | OOOOOOOOOOOOOOOOOOOOOOOOOOOOOOOOOOOOOOOOOOOOOOOOOOOOOOOOOOOOOOOOOOOOOOOOOOOOOOOOOOOOOOOOOO |
| Master Materials Change |  |  |  |  |  |  |  |  |  |
| Item | Foxconn P/N | Orig._Usage | New_Usage | Part Description | Manufacturer Full Name | Manufacturer P/N | RoHS | Location | Sheet |
| 1 | 610107A00-017-G | 714 | 720 | RES,0 Ohm,+/-5%,1/16W,G,SMD0402 | KOA SPEER ELECTRONICS, INC. | RK73Z1ETTP | G | (+)R2045,R2046,R2047,R2048,R2049,R2050,R2051,R2052 (-)PAAR67,PBAR68 | PWA BOM |
|  | 610107A00-024-G |  |  | RES,0 Ohm,+/-5%,1/16W,G,SMD0402 | PANASONIC INDUSTRIAL CO.,LTD. | ERJ2GE0R00X |  |  | PWA BOM |
|  | 610107A00-029-G |  |  | RES,0 Ohm,+/-5%,1/16W,G,SMD0402 | VISHAY ENTER TECHNO LOGY.INC | CRCW04020000Z0ED |  |  | PWA BOM |
| 2 | 61010PS00-017-G | 48 | 50 | RES,200KOhm,+/-1%,1/16W,G,SMD0402 | KOA SPEER ELECTRONICS, INC. | RK73H1ETTP2003F | G | (+)PBAR127,PAAR127 | PWA BOM |
|  | 61010PS00-029-G |  |  | RES,200KOhm,+/-1%,1/16W,G,SMD0402 | VISHAY ENTER TECHNO LOGY.INC | CRCW0402200KFKED |  |  | PWA BOM |
| 3 | 611003D00-017-G | 10 | 8 | RES,1KOhm,+/-0.1%,1/16W,G,SMD0402 | KOA SPEER ELECTRONICS, INC. | RN731ETTP1001B25 | G | (-)PBAR34,PAAR34 | PWA BOM |
|  | 611003D07-029-G |  |  | RES,1KOhm,+/-0.1%,1/16W,G,SMD0402 | VISHAY ENTER TECHNO LOGY.INC | MCS04020D1001BE000 |  |  | PWA BOM |
|  | 611003D00-024-G |  |  | RES,thin film,1KOhm,+/-0.1%,1/16W,SMD0402,G | PANASONIC INDUSTRIAL CO.,LTD. | ERA2AEB102X |  |  | PWA BOM |
| 4 | 61010R900-017-G | 4 | 8 | RES,27.4KOhm,+/-1%,1/10W,G,SMD0603 | KOA SPEER ELECTRONICS, INC. | RK73H1JTTD2742F | G | (+)PAAR66,PBAR67,PBAR79,PAAR79 | PWA BOM |
|  | 61010R900-011-G |  |  | RES,27.4KOhm,+/-1%,1/10W,G,SMD0603 | YAGEO CORPORATION COMPONENT | RC0603FR-0727K4L |  |  | PWA BOM |
|  | 61010R901-029-G |  |  | RES,thick film,27.4KOhm,+/-1%,1/10W,SMD0603,G | VISHAY ENTER TECHNO LOGY.INC | CRCW060327K4FKEB |  |  | PWA BOM |
| 5 | 61010G500-017-G | 100 | 102 | RES,10KOhm,+/-1%,1/16W,G,SMD0402 | KOA SPEER ELECTRONICS, INC. | RK73H1ETTP1002F | G | (+)PAAR67,PBAR68 | PWA BOM |
|  | 61010G500-029-G |  |  | RES,10KOhm,+/-1%,1/16W,G,SMD0402 | VISHAY ENTER TECHNO LOGY.INC | CRCW040210K0FKED |  |  | PWA BOM |
|  | 61010G500-024-G |  |  | RES,10KOhm,+/-1%,1/16W,G,SMD0402 | PANASONIC INDUSTRIAL CO.,LTD. | ERJ2RKF1002X |  |  | PWA BOM |
| 6 | 610100C00-017-G | 0 | 4 | RES,15kOhm,+/-1%,1/10W,G,SMD0603 | KOA SPEER ELECTRONICS, INC. | RK73H1JTTD1502F | G | (+)PAAR70,PBAR71,PBAR80,PAAR80 | PWA BOM |
| 7 | KOA_RN731ETTP5900B25 | 0 | 2 | RES,590Ohm,+/-0.1%,1/16W,G,SMD0402 | KOA SPEER ELECTRONICS, INC. | RN731ETTP5900B25 | G | (+)PBAR34,PAAR34 | PWA BOM |
|  | TNPW0402590RBEED |  |  | RES,590Ohm,+/-0.1%,1/16W,G,SMD0402 | VISHAY ENTER TECHNO LOGY.INC | TNPW0402590RBEED |  |  | PWA BOM |
|  | ERA2AEB5900X |  |  | RES,590Ohm,+/-0.1%,1/16W,G,SMD0402 | PANASONIC INDUSTRIAL CO.,LTD. | ERA2AEB5900X |  |  | PWA BOM |
| 8 | 610103D00-017-G | 4 | 0 | RES,24.3KOhm,+/-1%,1/10W,G,SMD0603 | KOA SPEER ELECTRONICS, INC. | RK73H1JTTD2432F | G | (-)PAAR66,PBAR67,PBAR79,PAAR79 | PWA BOM |
| 9 | 61010DG00-017-G | 2 | 0 | RES,4.99KOhm,+/-1%,1/10W,G,SMD0603 | KOA SPEER ELECTRONICS, INC. | RK73H1JTTD4991F | G | (-)PBAR80,PAAR80 | PWA BOM |
| 10 | 61011G600-017-G | 2 | 0 | RES,133KOhm,+/-1%,1/16W,G,SMD0402 | KOA SPEER ELECTRONICS, INC. | RK73G1ETTP1333F | G | (-)PBAR127,PAAR127 | PWA BOM |
| OOOOOOOOOOOOOOOOOOOOOOOOOOOOOOOOOOOOOOOOOOOOOOOOOOOOOOOOOOOOOOOOOOOOOOOOOOOOOOOOOOOOOOOOOO | OOOOOOOOOOOOOOOOOOOOOOOOOOOOOOOOOOOOOOOOOOOOOOOOOOOOOOOOOOOOOOOOOOOOOOOOOOOOOOOOOOOOOOOOOO | OOOOOOOOOOOOOOOOOOOOOOOOOOOOOOOOOOOOOOOOOOOOOOOOOOOOOOOOOOOOOOOOOOOOOOOOOOOOOOOOOOOOOOOOOO | OOOOOOOOOOOOOOOOOOOOOOOOOOOOOOOOOOOOOOOOOOOOOOOOOOOOOOOOOOOOOOOOOOOOOOOOOOOOOOOOOOOOOOOOOO | OOOOOOOOOOOOOOOOOOOOOOOOOOOOOOOOOOOOOOOOOOOOOOOOOOOOOOOOOOOOOOOOOOOOOOOOOOOOOOOOOOOOOOOOOO | OOOOOOOOOOOOOOOOOOOOOOOOOOOOOOOOOOOOOOOOOOOOOOOOOOOOOOOOOOOOOOOOOOOOOOOOOOOOOOOOOOOOOOOOOO | OOOOOOOOOOOOOOOOOOOOOOOOOOOOOOOOOOOOOOOOOOOOOOOOOOOOOOOOOOOOOOOOOOOOOOOOOOOOOOOOOOOOOOOOOO | OOOOOOOOOOOOOOOOOOOOOOOOOOOOOOOOOOOOOOOOOOOOOOOOOOOOOOOOOOOOOOOOOOOOOOOOOOOOOOOOOOOOOOOOOO | OOOOOOOOOOOOOOOOOOOOOOOOOOOOOOOOOOOOOOOOOOOOOOOOOOOOOOOOOOOOOOOOOOOOOOOOOOOOOOOOOOOOOOOOOO | OOOOOOOOOOOOOOOOOOOOOOOOOOOOOOOOOOOOOOOOOOOOOOOOOOOOOOOOOOOOOOOOOOOOOOOOOOOOOOOOOOOOOOOOOO |
| TLA Parts Change |  |  |  |  |  |  |  |  |  |
| Item | Foxconn P/N | Qty | Part Description | Manufacturer Full Name | Manufacturer P/N | RoHS | Location | Remark | BOM |
| BOM Change List Date:Thu Dec 28 16:48:06 GMT+08:00 2017 |  |  |  |  |  |  |  |  |  |
| New BOM file : C:\<user>\ZAIUS-MB-PVT-HW-EBOM-20171228.xls |  |  |  |  |  |  |  |  |  |
| Old BOM file : C:\<user>\ZAIUS-MB-PVT-HW-EBOM-20171218.xls |  |  |  |  |  |  |  |  |  |
| ##### Add Parts |  |  |  |  |  |  |  |  |  |
| Item | Location | Qty | Foxconn P/N | Part Description | Manufacturer Full Name | Manufacturer P/N | RoHS | Sheet |  |
| 1 | PBAR5,PAAR5,PAAR6,PBAR14 | 4 | 610107A00-017-G | RES,0 Ohm,+/-5%,1/16W,G,SMD0402 | KOA SPEER ELECTRONICS, INC. | RK73Z1ETTP | N | PWA BOM |  |
| 2 | PBAR8,PAAR9 | 2 | 61010PS00-017-G | RES,200KOhm,+/-1%,1/16W,G,SMD0402 | KOA SPEER ELECTRONICS, INC. | RK73H1ETTP2003F | N | PWA BOM |  |
| ##### Remove Parts |  |  |  |  |  |  |  |  |  |
| Item | Location | Qty | Foxconn P/N | Part Description | Manufacturer Full Name | Manufacturer P/N | RoHS | Sheet |  |
| 1 | PBAR6,PAAR7,PBAR313,PAAR313 | 4 | 610107A00-017-G | RES,0 Ohm,+/-5%,1/16W,G,SMD0402 | KOA SPEER ELECTRONICS, INC. | RK73Z1ETTP | N | PWA BOM |  |
| ##### Change Parts |  |  |  |  |  |  |  |  |  |
| Item | Location | Qty | Foxconn P/N | Part Description | Manufacturer Full Name | Manufacturer P/N | RoHS | Sheet | Remark |
| 1 | PBAC4,PAAC4 | 2 | 620108000-015-G | CAP,100pF,+/-5%,NPO(C0G),50V,G,SMD0402 | MURATA ELEC. NORTH AMERICA | GRM1555C1H101J | Y | PWA BOM | In New BOM |
|  | PBAC4,PAAC4 | 2 | 62010FF00-015-G | CAP,47pF,+/-5%,NPO(C0G),50V,G,SMD0402 | MURATA ELEC. NORTH AMERICA | GRM1555C1H470J | Y | PWA BOM | In Old BOM |
| 2 | U5 | 1 | 320241C00-183-G | IC,Power Controller,UCD90160RGCR,G,VQFN-64,SMD | TEXAS INSTRUMENTS | UCD90160RGCR-C13 |  | PWA BOM | In New BOM |
|  | U5 | 1 | UCD90160RGCR-C13 | IC,Power Controller,UCD90160RGCR,G,VQFN-64,SMD | TEXAS INSTRUMENTS | UCD90160RGCR-C13 |  | PWA BOM | In Old BOM |
| ##### Change Revision |  |  |  |  |  |  |  |  |  |
| Sheet | REV OF BOM | CUSTOMER | CUSTOMER P/N | PWA PN | PWA DESCRIPTION | PWA REV | DATE | Remark |  |
| OOOOOOOOOOOOOOOOOOOOOOOOOOOOOOOOOOOOOOOOOOOOOOOOOOOOOOOOOOOOOOOOOOOOOOOOOOOOOOOOOOOOOOOOOO | OOOOOOOOOOOOOOOOOOOOOOOOOOOOOOOOOOOOOOOOOOOOOOOOOOOOOOOOOOOOOOOOOOOOOOOOOOOOOOOOOOOOOOOOOO | OOOOOOOOOOOOOOOOOOOOOOOOOOOOOOOOOOOOOOOOOOOOOOOOOOOOOOOOOOOOOOOOOOOOOOOOOOOOOOOOOOOOOOOOOO | OOOOOOOOOOOOOOOOOOOOOOOOOOOOOOOOOOOOOOOOOOOOOOOOOOOOOOOOOOOOOOOOOOOOOOOOOOOOOOOOOOOOOOOOOO | OOOOOOOOOOOOOOOOOOOOOOOOOOOOOOOOOOOOOOOOOOOOOOOOOOOOOOOOOOOOOOOOOOOOOOOOOOOOOOOOOOOOOOOOOO | OOOOOOOOOOOOOOOOOOOOOOOOOOOOOOOOOOOOOOOOOOOOOOOOOOOOOOOOOOOOOOOOOOOOOOOOOOOOOOOOOOOOOOOOOO | OOOOOOOOOOOOOOOOOOOOOOOOOOOOOOOOOOOOOOOOOOOOOOOOOOOOOOOOOOOOOOOOOOOOOOOOOOOOOOOOOOOOOOOOOO | OOOOOOOOOOOOOOOOOOOOOOOOOOOOOOOOOOOOOOOOOOOOOOOOOOOOOOOOOOOOOOOOOOOOOOOOOOOOOOOOOOOOOOOOOO | OOOOOOOOOOOOOOOOOOOOOOOOOOOOOOOOOOOOOOOOOOOOOOOOOOOOOOOOOOOOOOOOOOOOOOOOOOOOOOOOOOOOOOOOOO | OOOOOOOOOOOOOOOOOOOOOOOOOOOOOOOOOOOOOOOOOOOOOOOOOOOOOOOOOOOOOOOOOOOOOOOOOOOOOOOOOOOOOOOOOO |
| Second Source Change |  |  |  |  |  |  |  |  |  |
| Item | Location | Change Type | Foxconn P/N | Part Description | Manufacturer Full Name | Manufacturer P/N | RoHS | Sheet |  |
| OOOOOOOOOOOOOOOOOOOOOOOOOOOOOOOOOOOOOOOOOOOOOOOOOOOOOOOOOOOOOOOOOOOOOOOOOOOOOOOOOOOOOOOOOO | OOOOOOOOOOOOOOOOOOOOOOOOOOOOOOOOOOOOOOOOOOOOOOOOOOOOOOOOOOOOOOOOOOOOOOOOOOOOOOOOOOOOOOOOOO | OOOOOOOOOOOOOOOOOOOOOOOOOOOOOOOOOOOOOOOOOOOOOOOOOOOOOOOOOOOOOOOOOOOOOOOOOOOOOOOOOOOOOOOOOO | OOOOOOOOOOOOOOOOOOOOOOOOOOOOOOOOOOOOOOOOOOOOOOOOOOOOOOOOOOOOOOOOOOOOOOOOOOOOOOOOOOOOOOOOOO | OOOOOOOOOOOOOOOOOOOOOOOOOOOOOOOOOOOOOOOOOOOOOOOOOOOOOOOOOOOOOOOOOOOOOOOOOOOOOOOOOOOOOOOOOO | OOOOOOOOOOOOOOOOOOOOOOOOOOOOOOOOOOOOOOOOOOOOOOOOOOOOOOOOOOOOOOOOOOOOOOOOOOOOOOOOOOOOOOOOOO | OOOOOOOOOOOOOOOOOOOOOOOOOOOOOOOOOOOOOOOOOOOOOOOOOOOOOOOOOOOOOOOOOOOOOOOOOOOOOOOOOOOOOOOOOO | OOOOOOOOOOOOOOOOOOOOOOOOOOOOOOOOOOOOOOOOOOOOOOOOOOOOOOOOOOOOOOOOOOOOOOOOOOOOOOOOOOOOOOOOOO | OOOOOOOOOOOOOOOOOOOOOOOOOOOOOOOOOOOOOOOOOOOOOOOOOOOOOOOOOOOOOOOOOOOOOOOOOOOOOOOOOOOOOOOOOO | OOOOOOOOOOOOOOOOOOOOOOOOOOOOOOOOOOOOOOOOOOOOOOOOOOOOOOOOOOOOOOOOOOOOOOOOOOOOOOOOOOOOOOOOOO |
| Master Materials Change |  |  |  |  |  |  |  |  |  |
| Item | Foxconn P/N | Orig._Usage | New_Usage | Part Description | Manufacturer Full Name | Manufacturer P/N | RoHS | Location | Sheet |
| 1 | 620108000-015-G | 20 | 22 | CAP,100pF,+/-5%,NPO(C0G),50V,G,SMD0402 | MURATA ELEC. NORTH AMERICA | GRM1555C1H101J | Y | (+)PBAC4,PAAC4 | PWA BOM |
| 2 | 61010PS00-017-G | 50 | 52 | RES,200KOhm,+/-1%,1/16W,G,SMD0402 | KOA SPEER ELECTRONICS, INC. | RK73H1ETTP2003F | N | (+)PBAR8,PAAR9 | PWA BOM |
| 3 | 62010FF00-015-G | 6 | 4 | CAP,47pF,+/-5%,NPO(C0G),50V,G,SMD0402 | MURATA ELEC. NORTH AMERICA | GRM1555C1H470J | Y | (-)PBAC4,PAAC4 | PWA BOM |
| 4 | 320241C00-183-G | 0 | 1 | IC,Power Controller,UCD90160RGCR,G,VQFN-64,SMD | TEXAS INSTRUMENTS | UCD90160RGCR-C13 |  | (+)U5 | PWA BOM |
| 5 | UCD90160RGCR-C13 | 1 | 0 | IC,Power Controller,UCD90160RGCR,G,VQFN-64,SMD | TEXAS INSTRUMENTS | UCD90160RGCR-C13 |  | (-)U5 | PWA BOM |
| OOOOOOOOOOOOOOOOOOOOOOOOOOOOOOOOOOOOOOOOOOOOOOOOOOOOOOOOOOOOOOOOOOOOOOOOOOOOOOOOOOOOOOOOOO | OOOOOOOOOOOOOOOOOOOOOOOOOOOOOOOOOOOOOOOOOOOOOOOOOOOOOOOOOOOOOOOOOOOOOOOOOOOOOOOOOOOOOOOOOO | OOOOOOOOOOOOOOOOOOOOOOOOOOOOOOOOOOOOOOOOOOOOOOOOOOOOOOOOOOOOOOOOOOOOOOOOOOOOOOOOOOOOOOOOOO | OOOOOOOOOOOOOOOOOOOOOOOOOOOOOOOOOOOOOOOOOOOOOOOOOOOOOOOOOOOOOOOOOOOOOOOOOOOOOOOOOOOOOOOOOO | OOOOOOOOOOOOOOOOOOOOOOOOOOOOOOOOOOOOOOOOOOOOOOOOOOOOOOOOOOOOOOOOOOOOOOOOOOOOOOOOOOOOOOOOOO | OOOOOOOOOOOOOOOOOOOOOOOOOOOOOOOOOOOOOOOOOOOOOOOOOOOOOOOOOOOOOOOOOOOOOOOOOOOOOOOOOOOOOOOOOO | OOOOOOOOOOOOOOOOOOOOOOOOOOOOOOOOOOOOOOOOOOOOOOOOOOOOOOOOOOOOOOOOOOOOOOOOOOOOOOOOOOOOOOOOOO | OOOOOOOOOOOOOOOOOOOOOOOOOOOOOOOOOOOOOOOOOOOOOOOOOOOOOOOOOOOOOOOOOOOOOOOOOOOOOOOOOOOOOOOOOO | OOOOOOOOOOOOOOOOOOOOOOOOOOOOOOOOOOOOOOOOOOOOOOOOOOOOOOOOOOOOOOOOOOOOOOOOOOOOOOOOOOOOOOOOOO |  |
| TLA Parts Change |  |  |  |  |  |  |  |  |  |
| Item | Foxconn P/N | Qty | Part Description | Manufacturer Full Name | Manufacturer P/N | RoHS | Location | Remark |  |
| BOM Change List Date:Fri Dec 29 10:08:49 CST 2017 |  |  |  |  |  |  |  |  |  |
| New BOM file : E:\barreleye g2\1228\ZAIUS-MB-PVT-X04-BOM_X30_20171229.xls |  |  |  |  |  |  |  |  |  |
| Old BOM file : E:\barreleye g2\1228\zaius 1219.xls |  |  |  |  |  |  |  |  |  |
| ##### Add Parts |  |  |  |  |  |  |  |  |  |
| Item | Location | Qty | Foxconn P/N | Part Description | Manufacturer Full Name | Manufacturer P/N | RoHS | Sheet |  |
| 1 | PBAR5,PAAR5,PAAR6,PBAR14 | 4 | 610107A00-017-G | RES,0 Ohm,+/-5%,1/16W,G,SMD0402 | KOA SPEER ELECTRONICS, INC. | RK73Z1ETTP | G | PWA BOM |  |
|  |  |  | 610107A00-024-G | RES,0 Ohm,+/-5%,1/16W,G,SMD0402 | PANASONIC INDUSTRIAL CO.,LTD. | ERJ2GE0R00X | G | PWA BOM |  |
|  |  |  | 610107A00-029-G | RES,0 Ohm,+/-5%,1/16W,G,SMD0402 | VISHAY ENTER TECHNO LOGY.INC | CRCW04020000Z0ED | G | PWA BOM |  |
| 2 | PBAR8,PAAR9 | 2 | 61010PS00-017-G | RES,200KOhm,+/-1%,1/16W,G,SMD0402 | KOA SPEER ELECTRONICS, INC. | RK73H1ETTP2003F | G | PWA BOM |  |
|  |  |  | 61010PS00-029-G | RES,200KOhm,+/-1%,1/16W,G,SMD0402 | VISHAY ENTER TECHNO LOGY.INC | CRCW0402200KFKED | G | PWA BOM |  |
| ##### Remove Parts |  |  |  |  |  |  |  |  |  |
| Item | Location | Qty | Foxconn P/N | Part Description | Manufacturer Full Name | Manufacturer P/N | RoHS | Sheet |  |
| 1 | PBAR6,PAAR7,PBAR313,PAAR313 | 4 | 610107A00-017-G | RES,0 Ohm,+/-5%,1/16W,G,SMD0402 | KOA SPEER ELECTRONICS, INC. | RK73Z1ETTP | G | PWA BOM |  |
|  |  |  | 610107A00-024-G | RES,0 Ohm,+/-5%,1/16W,G,SMD0402 | PANASONIC INDUSTRIAL CO.,LTD. | ERJ2GE0R00X | G | PWA BOM |  |
|  |  |  | 610107A00-029-G | RES,0 Ohm,+/-5%,1/16W,G,SMD0402 | VISHAY ENTER TECHNO LOGY.INC | CRCW04020000Z0ED | G | PWA BOM |  |
| ##### Change Parts |  |  |  |  |  |  |  |  |  |
| Item | Location | Qty | Foxconn P/N | Part Description | Manufacturer Full Name | Manufacturer P/N | RoHS | Sheet | Remark |
| 1 | PCB | 1 | 0101FBQ00-000-G | PCB | GCE | 0101FBQ00-000-G | G | PWA BOM | In New BOM |
|  | PCB | 1 | 0101FBQ00-000-G | PCB,Zaius-MB PVT-X04,OSP,Gre,22L,22.20*13.00,G | GOLD CIRCUIT ELECTRONICS LTD. | 0101FBQ00-000-G | G | PWA BOM | In Old BOM |
| 2 | PBAC4,PAAC4 | 2 | 620108000-015-G | CAP,100pF,+/-5%,NPO(C0G),50V,G,SMD0402 | MURATA ELEC. NORTH AMERICA | GRM1555C1H101J | G | PWA BOM | In New BOM |
|  |  |  | 620108000-026-G | CAP,100pF,+/-5%,NPO(C0G),50V,G,SMD0402 | SAMSUNG SEMICONDUCTOR | CL05C101JB5NNNC | G | PWA BOM | In New BOM |
|  |  |  | 620108000-023-G | CAP,100pF,+/-5%,NPO(C0G),50V,G,SMD0402 | TAIYO ELECTRIC IND.CO.LTD | UMK105CG101JV-F | G | PWA BOM | In New BOM |
|  | PBAC4,PAAC4 | 2 | 62010FF00-015-G | CAP,47pF,+/-5%,NPO(C0G),50V,G,SMD0402 | MURATA ELEC. NORTH AMERICA | GRM1555C1H470J | G | PWA BOM | In Old BOM |
|  |  |  | 62010FF00-026-G | CAP,47pF,+/-5%,NPO(C0G),50V,G,SMD0402 | SAMSUNG SEMICONDUCTOR | CL05C470JB5NNNC | G | PWA BOM | In Old BOM |
|  |  |  | 62010FF00-023-G | CAP,47pF,+/-5%,NPO(C0G),50V,G,SMD0402 | TAIYO ELECTRIC IND.CO.LTD | UMK105CG470JV-F | G | PWA BOM | In Old BOM |
| 3 | U5 | 1 | 320241C00-183-G | IC,Power Controller,UCD90160RGCR,G,VQFN-64,SMD | TEXAS INSTRUMENTS | UCD90160RGCR-C13 | G | PWA BOM | In New BOM |
|  | U5 | 1 | UCD90160RGCR-C13 | IC,Power Controller,UCD90160RGCR,G,VQFN-64,SMD | TEXAS INSTRUMENTS | UCD90160RGCR-C13 | G | PWA BOM | In Old BOM |
| ##### Change Revision |  |  |  |  |  |  |  |  |  |
| Sheet | REV OF BOM | CUSTOMER | CUSTOMER P/N | PWA PN | PWA DESCRIPTION | PWA REV | DATE | Remark |  |
| OOOOOOOOOOOOOOOOOOOOOOOOOOOOOOOOOOOOOOOOOOOOOOOOOOOOOOOOOOOOOOOOOOOOOOOOOOOOOOOOOOOOOOOOOO | OOOOOOOOOOOOOOOOOOOOOOOOOOOOOOOOOOOOOOOOOOOOOOOOOOOOOOOOOOOOOOOOOOOOOOOOOOOOOOOOOOOOOOOOOO | OOOOOOOOOOOOOOOOOOOOOOOOOOOOOOOOOOOOOOOOOOOOOOOOOOOOOOOOOOOOOOOOOOOOOOOOOOOOOOOOOOOOOOOOOO | OOOOOOOOOOOOOOOOOOOOOOOOOOOOOOOOOOOOOOOOOOOOOOOOOOOOOOOOOOOOOOOOOOOOOOOOOOOOOOOOOOOOOOOOOO | OOOOOOOOOOOOOOOOOOOOOOOOOOOOOOOOOOOOOOOOOOOOOOOOOOOOOOOOOOOOOOOOOOOOOOOOOOOOOOOOOOOOOOOOOO | OOOOOOOOOOOOOOOOOOOOOOOOOOOOOOOOOOOOOOOOOOOOOOOOOOOOOOOOOOOOOOOOOOOOOOOOOOOOOOOOOOOOOOOOOO | OOOOOOOOOOOOOOOOOOOOOOOOOOOOOOOOOOOOOOOOOOOOOOOOOOOOOOOOOOOOOOOOOOOOOOOOOOOOOOOOOOOOOOOOOO | OOOOOOOOOOOOOOOOOOOOOOOOOOOOOOOOOOOOOOOOOOOOOOOOOOOOOOOOOOOOOOOOOOOOOOOOOOOOOOOOOOOOOOOOOO | OOOOOOOOOOOOOOOOOOOOOOOOOOOOOOOOOOOOOOOOOOOOOOOOOOOOOOOOOOOOOOOOOOOOOOOOOOOOOOOOOOOOOOOOOO | OOOOOOOOOOOOOOOOOOOOOOOOOOOOOOOOOOOOOOOOOOOOOOOOOOOOOOOOOOOOOOOOOOOOOOOOOOOOOOOOOOOOOOOOOO |
| Second Source Change |  |  |  |  |  |  |  |  |  |
| Item | Location | Change Type | Foxconn P/N | Part Description | Manufacturer Full Name | Manufacturer P/N | RoHS | Sheet |  |
| OOOOOOOOOOOOOOOOOOOOOOOOOOOOOOOOOOOOOOOOOOOOOOOOOOOOOOOOOOOOOOOOOOOOOOOOOOOOOOOOOOOOOOOOOO | OOOOOOOOOOOOOOOOOOOOOOOOOOOOOOOOOOOOOOOOOOOOOOOOOOOOOOOOOOOOOOOOOOOOOOOOOOOOOOOOOOOOOOOOOO | OOOOOOOOOOOOOOOOOOOOOOOOOOOOOOOOOOOOOOOOOOOOOOOOOOOOOOOOOOOOOOOOOOOOOOOOOOOOOOOOOOOOOOOOOO | OOOOOOOOOOOOOOOOOOOOOOOOOOOOOOOOOOOOOOOOOOOOOOOOOOOOOOOOOOOOOOOOOOOOOOOOOOOOOOOOOOOOOOOOOO | OOOOOOOOOOOOOOOOOOOOOOOOOOOOOOOOOOOOOOOOOOOOOOOOOOOOOOOOOOOOOOOOOOOOOOOOOOOOOOOOOOOOOOOOOO | OOOOOOOOOOOOOOOOOOOOOOOOOOOOOOOOOOOOOOOOOOOOOOOOOOOOOOOOOOOOOOOOOOOOOOOOOOOOOOOOOOOOOOOOOO | OOOOOOOOOOOOOOOOOOOOOOOOOOOOOOOOOOOOOOOOOOOOOOOOOOOOOOOOOOOOOOOOOOOOOOOOOOOOOOOOOOOOOOOOOO | OOOOOOOOOOOOOOOOOOOOOOOOOOOOOOOOOOOOOOOOOOOOOOOOOOOOOOOOOOOOOOOOOOOOOOOOOOOOOOOOOOOOOOOOOO | OOOOOOOOOOOOOOOOOOOOOOOOOOOOOOOOOOOOOOOOOOOOOOOOOOOOOOOOOOOOOOOOOOOOOOOOOOOOOOOOOOOOOOOOOO | OOOOOOOOOOOOOOOOOOOOOOOOOOOOOOOOOOOOOOOOOOOOOOOOOOOOOOOOOOOOOOOOOOOOOOOOOOOOOOOOOOOOOOOOOO |
| Master Materials Change |  |  |  |  |  |  |  |  |  |
| Item | Foxconn P/N | Orig._Usage | New_Usage | Part Description | Manufacturer Full Name | Manufacturer P/N | RoHS | Location | Sheet |
| 1 | 620108000-015-G | 20 | 22 | CAP,100pF,+/-5%,NPO(C0G),50V,G,SMD0402 | MURATA ELEC. NORTH AMERICA | GRM1555C1H101J | G | (+)PBAC4,PAAC4 | PWA BOM |
|  | 620108000-026-G |  |  | CAP,100pF,+/-5%,NPO(C0G),50V,G,SMD0402 | SAMSUNG SEMICONDUCTOR | CL05C101JB5NNNC |  |  | PWA BOM |
|  | 620108000-023-G |  |  | CAP,100pF,+/-5%,NPO(C0G),50V,G,SMD0402 | TAIYO ELECTRIC IND.CO.LTD | UMK105CG101JV-F |  |  | PWA BOM |
| 2 | 61010PS00-017-G | 50 | 52 | RES,200KOhm,+/-1%,1/16W,G,SMD0402 | KOA SPEER ELECTRONICS, INC. | RK73H1ETTP2003F | G | (+)PBAR8,PAAR9 | PWA BOM |
|  | 61010PS00-029-G |  |  | RES,200KOhm,+/-1%,1/16W,G,SMD0402 | VISHAY ENTER TECHNO LOGY.INC | CRCW0402200KFKED |  |  | PWA BOM |
| 3 | 62010FF00-015-G | 6 | 4 | CAP,47pF,+/-5%,NPO(C0G),50V,G,SMD0402 | MURATA ELEC. NORTH AMERICA | GRM1555C1H470J | G | (-)PBAC4,PAAC4 | PWA BOM |
|  | 62010FF00-026-G |  |  | CAP,47pF,+/-5%,NPO(C0G),50V,G,SMD0402 | SAMSUNG SEMICONDUCTOR | CL05C470JB5NNNC |  |  | PWA BOM |
|  | 62010FF00-023-G |  |  | CAP,47pF,+/-5%,NPO(C0G),50V,G,SMD0402 | TAIYO ELECTRIC IND.CO.LTD | UMK105CG470JV-F |  |  | PWA BOM |
| 4 | 320241C00-183-G | 0 | 1 | IC,Power Controller,UCD90160RGCR,G,VQFN-64,SMD | TEXAS INSTRUMENTS | UCD90160RGCR-C13 | G | (+)U5 | PWA BOM |
| 5 | UCD90160RGCR-C13 | 1 | 0 | IC,Power Controller,UCD90160RGCR,G,VQFN-64,SMD | TEXAS INSTRUMENTS | UCD90160RGCR-C13 | G | (-)U5 | PWA BOM |
| OOOOOOOOOOOOOOOOOOOOOOOOOOOOOOOOOOOOOOOOOOOOOOOOOOOOOOOOOOOOOOOOOOOOOOOOOOOOOOOOOOOOOOOOOO | OOOOOOOOOOOOOOOOOOOOOOOOOOOOOOOOOOOOOOOOOOOOOOOOOOOOOOOOOOOOOOOOOOOOOOOOOOOOOOOOOOOOOOOOOO | OOOOOOOOOOOOOOOOOOOOOOOOOOOOOOOOOOOOOOOOOOOOOOOOOOOOOOOOOOOOOOOOOOOOOOOOOOOOOOOOOOOOOOOOOO | OOOOOOOOOOOOOOOOOOOOOOOOOOOOOOOOOOOOOOOOOOOOOOOOOOOOOOOOOOOOOOOOOOOOOOOOOOOOOOOOOOOOOOOOOO | OOOOOOOOOOOOOOOOOOOOOOOOOOOOOOOOOOOOOOOOOOOOOOOOOOOOOOOOOOOOOOOOOOOOOOOOOOOOOOOOOOOOOOOOOO | OOOOOOOOOOOOOOOOOOOOOOOOOOOOOOOOOOOOOOOOOOOOOOOOOOOOOOOOOOOOOOOOOOOOOOOOOOOOOOOOOOOOOOOOOO | OOOOOOOOOOOOOOOOOOOOOOOOOOOOOOOOOOOOOOOOOOOOOOOOOOOOOOOOOOOOOOOOOOOOOOOOOOOOOOOOOOOOOOOOOO | OOOOOOOOOOOOOOOOOOOOOOOOOOOOOOOOOOOOOOOOOOOOOOOOOOOOOOOOOOOOOOOOOOOOOOOOOOOOOOOOOOOOOOOOOO | OOOOOOOOOOOOOOOOOOOOOOOOOOOOOOOOOOOOOOOOOOOOOOOOOOOOOOOOOOOOOOOOOOOOOOOOOOOOOOOOOOOOOOOOOO | OOOOOOOOOOOOOOOOOOOOOOOOOOOOOOOOOOOOOOOOOOOOOOOOOOOOOOOOOOOOOOOOOOOOOOOOOOOOOOOOOOOOOOOOOO |
| TLA Parts Change |  |  |  |  |  |  |  |  |  |
| Item | Foxconn P/N | Qty | Part Description | Manufacturer Full Name | Manufacturer P/N | RoHS | Location | Remark | BOM |
| BOM Change List Date:Fri Jan 12 11:25:33 GMT+08:00 2018 |  |  |  |  |  |  |  |  |  |
| New BOM file : E:\barreleye g2\0112\ZAIUS 0112.xls |  |  |  |  |  |  |  |  |  |
| Old BOM file : E:\barreleye g2\0112\ZAIUS 0929.xls |  |  |  |  |  |  |  |  |  |
| ##### Add Parts |  |  |  |  |  |  |  |  |  |
| Item | Location | Qty | Foxconn P/N | Part Description | Manufacturer Full Name | Manufacturer P/N | RoHS | Sheet |  |
| ##### Remove Parts |  |  |  |  |  |  |  |  |  |
| Item | Location | Qty | Foxconn P/N | Part Description | Manufacturer Full Name | Manufacturer P/N | RoHS | Sheet |  |
| ##### Change Parts |  |  |  |  |  |  |  |  |  |
| Item | Location | Qty | Foxconn P/N | Part Description | Manufacturer Full Name | Manufacturer P/N | RoHS | Sheet | Remark |
| 1 | PBNU1,PANU1 | 2 | IR38064MTRP=GZS | IC,Regulator, IR38064MTRP=GZS,ADJ,35A,G,QFN-26,SMD | INTERNATIONAL RECTIFIER | IR38064MTRP=GZS | G | PWA BOM | In New BOM |
|  | PBNU1,PANU1 | 2 | 320147Q00-238-G | IC,Regulator,IR38064MTRPBF,ADJ,35A,G,QFN-26,SMD | INTERNATIONAL RECTIFIER | IR38064MTRPBF | G | PWA BOM | In Old BOM |
| ##### Change Revision |  |  |  |  |  |  |  |  |  |
| Sheet | REV OF BOM | CUSTOMER | CUSTOMER P/N | PWA PN | PWA DESCRIPTION | PWA REV | DATE | Remark |  |
| OOOOOOOOOOOOOOOOOOOOOOOOOOOOOOOOOOOOOOOOOOOOOOOOOOOOOOOOOOOOOOOOOOOOOOOOOOOOOOOOOOOOOOOOOO | OOOOOOOOOOOOOOOOOOOOOOOOOOOOOOOOOOOOOOOOOOOOOOOOOOOOOOOOOOOOOOOOOOOOOOOOOOOOOOOOOOOOOOOOOO | OOOOOOOOOOOOOOOOOOOOOOOOOOOOOOOOOOOOOOOOOOOOOOOOOOOOOOOOOOOOOOOOOOOOOOOOOOOOOOOOOOOOOOOOOO | OOOOOOOOOOOOOOOOOOOOOOOOOOOOOOOOOOOOOOOOOOOOOOOOOOOOOOOOOOOOOOOOOOOOOOOOOOOOOOOOOOOOOOOOOO | OOOOOOOOOOOOOOOOOOOOOOOOOOOOOOOOOOOOOOOOOOOOOOOOOOOOOOOOOOOOOOOOOOOOOOOOOOOOOOOOOOOOOOOOOO | OOOOOOOOOOOOOOOOOOOOOOOOOOOOOOOOOOOOOOOOOOOOOOOOOOOOOOOOOOOOOOOOOOOOOOOOOOOOOOOOOOOOOOOOOO | OOOOOOOOOOOOOOOOOOOOOOOOOOOOOOOOOOOOOOOOOOOOOOOOOOOOOOOOOOOOOOOOOOOOOOOOOOOOOOOOOOOOOOOOOO | OOOOOOOOOOOOOOOOOOOOOOOOOOOOOOOOOOOOOOOOOOOOOOOOOOOOOOOOOOOOOOOOOOOOOOOOOOOOOOOOOOOOOOOOOO | OOOOOOOOOOOOOOOOOOOOOOOOOOOOOOOOOOOOOOOOOOOOOOOOOOOOOOOOOOOOOOOOOOOOOOOOOOOOOOOOOOOOOOOOOO | OOOOOOOOOOOOOOOOOOOOOOOOOOOOOOOOOOOOOOOOOOOOOOOOOOOOOOOOOOOOOOOOOOOOOOOOOOOOOOOOOOOOOOOOOO |
| Second Source Change |  |  |  |  |  |  |  |  |  |
| Item | Location | Change Type | Foxconn P/N | Part Description | Manufacturer Full Name | Manufacturer P/N | RoHS | Sheet |  |
| OOOOOOOOOOOOOOOOOOOOOOOOOOOOOOOOOOOOOOOOOOOOOOOOOOOOOOOOOOOOOOOOOOOOOOOOOOOOOOOOOOOOOOOOOO | OOOOOOOOOOOOOOOOOOOOOOOOOOOOOOOOOOOOOOOOOOOOOOOOOOOOOOOOOOOOOOOOOOOOOOOOOOOOOOOOOOOOOOOOOO | OOOOOOOOOOOOOOOOOOOOOOOOOOOOOOOOOOOOOOOOOOOOOOOOOOOOOOOOOOOOOOOOOOOOOOOOOOOOOOOOOOOOOOOOOO | OOOOOOOOOOOOOOOOOOOOOOOOOOOOOOOOOOOOOOOOOOOOOOOOOOOOOOOOOOOOOOOOOOOOOOOOOOOOOOOOOOOOOOOOOO | OOOOOOOOOOOOOOOOOOOOOOOOOOOOOOOOOOOOOOOOOOOOOOOOOOOOOOOOOOOOOOOOOOOOOOOOOOOOOOOOOOOOOOOOOO | OOOOOOOOOOOOOOOOOOOOOOOOOOOOOOOOOOOOOOOOOOOOOOOOOOOOOOOOOOOOOOOOOOOOOOOOOOOOOOOOOOOOOOOOOO | OOOOOOOOOOOOOOOOOOOOOOOOOOOOOOOOOOOOOOOOOOOOOOOOOOOOOOOOOOOOOOOOOOOOOOOOOOOOOOOOOOOOOOOOOO | OOOOOOOOOOOOOOOOOOOOOOOOOOOOOOOOOOOOOOOOOOOOOOOOOOOOOOOOOOOOOOOOOOOOOOOOOOOOOOOOOOOOOOOOOO | OOOOOOOOOOOOOOOOOOOOOOOOOOOOOOOOOOOOOOOOOOOOOOOOOOOOOOOOOOOOOOOOOOOOOOOOOOOOOOOOOOOOOOOOOO | OOOOOOOOOOOOOOOOOOOOOOOOOOOOOOOOOOOOOOOOOOOOOOOOOOOOOOOOOOOOOOOOOOOOOOOOOOOOOOOOOOOOOOOOOO |
| Master Materials Change |  |  |  |  |  |  |  |  |  |
| Item | Foxconn P/N | Orig._Usage | New_Usage | Part Description | Manufacturer Full Name | Manufacturer P/N | RoHS | Location | Sheet |
| 1 | IR38064MTRP=GZS | 0 | 2 | IC,Regulator, IR38064MTRP=GZS,ADJ,35A,G,QFN-26,SMD | INTERNATIONAL RECTIFIER | IR38064MTRP=GZS | G | (+)PBNU1,PANU1 | PWA BOM |
| 2 | 320147Q00-238-G | 2 | 0 | IC,Regulator,IR38064MTRPBF,ADJ,35A,G,QFN-26,SMD | INTERNATIONAL RECTIFIER | IR38064MTRPBF | G | (-)PBNU1,PANU1 | PWA BOM |
| OOOOOOOOOOOOOOOOOOOOOOOOOOOOOOOOOOOOOOOOOOOOOOOOOOOOOOOOOOOOOOOOOOOOOOOOOOOOOOOOOOOOOOOOOO | OOOOOOOOOOOOOOOOOOOOOOOOOOOOOOOOOOOOOOOOOOOOOOOOOOOOOOOOOOOOOOOOOOOOOOOOOOOOOOOOOOOOOOOOOO | OOOOOOOOOOOOOOOOOOOOOOOOOOOOOOOOOOOOOOOOOOOOOOOOOOOOOOOOOOOOOOOOOOOOOOOOOOOOOOOOOOOOOOOOOO | OOOOOOOOOOOOOOOOOOOOOOOOOOOOOOOOOOOOOOOOOOOOOOOOOOOOOOOOOOOOOOOOOOOOOOOOOOOOOOOOOOOOOOOOOO | OOOOOOOOOOOOOOOOOOOOOOOOOOOOOOOOOOOOOOOOOOOOOOOOOOOOOOOOOOOOOOOOOOOOOOOOOOOOOOOOOOOOOOOOOO | OOOOOOOOOOOOOOOOOOOOOOOOOOOOOOOOOOOOOOOOOOOOOOOOOOOOOOOOOOOOOOOOOOOOOOOOOOOOOOOOOOOOOOOOOO | OOOOOOOOOOOOOOOOOOOOOOOOOOOOOOOOOOOOOOOOOOOOOOOOOOOOOOOOOOOOOOOOOOOOOOOOOOOOOOOOOOOOOOOOOO | OOOOOOOOOOOOOOOOOOOOOOOOOOOOOOOOOOOOOOOOOOOOOOOOOOOOOOOOOOOOOOOOOOOOOOOOOOOOOOOOOOOOOOOOOO | OOOOOOOOOOOOOOOOOOOOOOOOOOOOOOOOOOOOOOOOOOOOOOOOOOOOOOOOOOOOOOOOOOOOOOOOOOOOOOOOOOOOOOOOOO | OOOOOOOOOOOOOOOOOOOOOOOOOOOOOOOOOOOOOOOOOOOOOOOOOOOOOOOOOOOOOOOOOOOOOOOOOOOOOOOOOOOOOOOOOO |
| TLA Parts Change |  |  |  |  |  |  |  |  |  |
| Item | Foxconn P/N | Qty | Part Description | Manufacturer Full Name | Manufacturer P/N | RoHS | Location | Remark | BOM |
| BOM Change List Date:Tue Jan 16 15:44:19 GMT+08:00 2018 |  |  |  |  |  |  |  |  |  |
| New BOM file : C:\<user>\ZAIUS-MB-PVT-HW-EBOM-20180116.xls |  |  |  |  |  |  |  |  |  |
| Old BOM file : C:\<user>\ZAIUS-MB-PVT-HW-EBOM-20171228.xls |  |  |  |  |  |  |  |  |  |
| ##### Add Parts |  |  |  |  |  |  |  |  |  |
| Item | Location | Qty | Foxconn P/N | Part Description | Manufacturer Full Name | Manufacturer P/N | RoHS | Sheet |  |
| ##### Remove Parts |  |  |  |  |  |  |  |  |  |
| Item | Location | Qty | Foxconn P/N | Part Description | Manufacturer Full Name | Manufacturer P/N | RoHS | Sheet |  |
| ##### Change Parts |  |  |  |  |  |  |  |  |  |
| Item | Location | Qty | Foxconn P/N | Part Description | Manufacturer Full Name | Manufacturer P/N | RoHS | Sheet | Remark |
| 1 | PBAC125,PAAC125 | 2 | 620107500-015-G | CAP,3.9nF,+/-10%,X7R,50V,G,SMD0402 | MURATA ELEC. NORTH AMERICA | GRM155R71H392K | N | PWA BOM | In New BOM |
|  | PBAC125,PAAC125 | 2 | 620109700-015-G | CAP,3.3nF,+/-10%,X7R,50V,G,SMD0402 | MURATA ELEC. NORTH AMERICA | GRM155R71H332K | N | PWA BOM | In Old BOM |
| 2 | PAAR70,PBAR71 | 2 | 610108U00-017-G | RES,10KOhm,+/-1%,1/10W,G,SMD0603 | KOA SPEER ELECTRONICS, INC. | RK73H1JTTD1002F | N | PWA BOM | In New BOM |
|  | PAAR70,PBAR71 | 2 | 610100C00-017-G | RES,15kOhm,+/-1%,1/10W,G,SMD0603 | KOA SPEER ELECTRONICS, INC. | RK73H1JTTD1502F | N | PWA BOM | In Old BOM |
| 3 | PBER72,PAFR72,PAER72,PBFR73,PBMR74,PAMR74,PBAR77,PAAR77 | 8 | 610108U00-017-G | RES,10KOhm,+/-1%,1/10W,G,SMD0603 | KOA SPEER ELECTRONICS, INC. | RK73H1JTTD1002F | N | PWA BOM | In New BOM |
|  | PBER72,PAFR72,PAER72,PBFR73,PBMR74,PAMR74,PBAR77,PAAR77 | 8 | 610108U00-017-G | RES,10KOhm,+/-1%,1/10W,G,SMD0603 | KOA SPEER ELECTRONICS, INC. | RK73H1JTTD1002F |  | PWA BOM | In Old BOM |
| 4 | PBAR109,PAAR109 | 2 | 61100M100-017-G | RES,4.75KOhm,+/-1%,1/16W,G,SMD0402 | KOA SPEER ELECTRONICS, INC. | RN731ETTP4751F50 |  | PWA BOM | In New BOM |
|  | PBAR109,PAAR109 | 2 | 610107A00-017-G | RES,0 Ohm,+/-5%,1/16W,G,SMD0402 | KOA SPEER ELECTRONICS, INC. | RK73Z1ETTP | N | PWA BOM | In Old BOM |
| 5 | PBNU1,PANU1 | 2 | IR38064MTRP=GZS | IC,Regulator,IR38064MTRP=GZS,ADJ,35A,G,QFN-26,SMD | INTERNATIONAL RECTIFIER | IR38064MTRP=GZS |  | PWA BOM | In New BOM |
|  | PBNU1,PANU1 | 2 | 320147Q00-238-G | IC,Regulator,IR38064MTRPBF,ADJ,35A,G,QFN-26,SMD | INTERNATIONAL RECTIFIER | IR38064MTRPBF |  | PWA BOM | In Old BOM |
| 6 | U5 | 1 | UCD90160RGCR-C13 | IC,Power Controller,UCD90160RGCR,G,VQFN-64,SMD | TEXAS INSTRUMENTS | UCD90160RGCR-C13 |  | PWA BOM | In New BOM |
|  | U5 | 1 | 320241C00-183-G | IC,Power Controller,UCD90160RGCR,G,VQFN-64,SMD | TEXAS INSTRUMENTS | UCD90160RGCR-C13 |  | PWA BOM | In Old BOM |
| ##### Change Revision |  |  |  |  |  |  |  |  |  |
| Sheet | REV OF BOM | CUSTOMER | CUSTOMER P/N | PWA PN | PWA DESCRIPTION | PWA REV | DATE | Remark |  |
| OOOOOOOOOOOOOOOOOOOOOOOOOOOOOOOOOOOOOOOOOOOOOOOOOOOOOOOOOOOOOOOOOOOOOOOOOOOOOOOOOOOOOOOOOO | OOOOOOOOOOOOOOOOOOOOOOOOOOOOOOOOOOOOOOOOOOOOOOOOOOOOOOOOOOOOOOOOOOOOOOOOOOOOOOOOOOOOOOOOOO | OOOOOOOOOOOOOOOOOOOOOOOOOOOOOOOOOOOOOOOOOOOOOOOOOOOOOOOOOOOOOOOOOOOOOOOOOOOOOOOOOOOOOOOOOO | OOOOOOOOOOOOOOOOOOOOOOOOOOOOOOOOOOOOOOOOOOOOOOOOOOOOOOOOOOOOOOOOOOOOOOOOOOOOOOOOOOOOOOOOOO | OOOOOOOOOOOOOOOOOOOOOOOOOOOOOOOOOOOOOOOOOOOOOOOOOOOOOOOOOOOOOOOOOOOOOOOOOOOOOOOOOOOOOOOOOO | OOOOOOOOOOOOOOOOOOOOOOOOOOOOOOOOOOOOOOOOOOOOOOOOOOOOOOOOOOOOOOOOOOOOOOOOOOOOOOOOOOOOOOOOOO | OOOOOOOOOOOOOOOOOOOOOOOOOOOOOOOOOOOOOOOOOOOOOOOOOOOOOOOOOOOOOOOOOOOOOOOOOOOOOOOOOOOOOOOOOO | OOOOOOOOOOOOOOOOOOOOOOOOOOOOOOOOOOOOOOOOOOOOOOOOOOOOOOOOOOOOOOOOOOOOOOOOOOOOOOOOOOOOOOOOOO | OOOOOOOOOOOOOOOOOOOOOOOOOOOOOOOOOOOOOOOOOOOOOOOOOOOOOOOOOOOOOOOOOOOOOOOOOOOOOOOOOOOOOOOOOO | OOOOOOOOOOOOOOOOOOOOOOOOOOOOOOOOOOOOOOOOOOOOOOOOOOOOOOOOOOOOOOOOOOOOOOOOOOOOOOOOOOOOOOOOOO |
| Second Source Change |  |  |  |  |  |  |  |  |  |
| Item | Location | Change Type | Foxconn P/N | Part Description | Manufacturer Full Name | Manufacturer P/N | RoHS | Sheet |  |
| OOOOOOOOOOOOOOOOOOOOOOOOOOOOOOOOOOOOOOOOOOOOOOOOOOOOOOOOOOOOOOOOOOOOOOOOOOOOOOOOOOOOOOOOOO | OOOOOOOOOOOOOOOOOOOOOOOOOOOOOOOOOOOOOOOOOOOOOOOOOOOOOOOOOOOOOOOOOOOOOOOOOOOOOOOOOOOOOOOOOO | OOOOOOOOOOOOOOOOOOOOOOOOOOOOOOOOOOOOOOOOOOOOOOOOOOOOOOOOOOOOOOOOOOOOOOOOOOOOOOOOOOOOOOOOOO | OOOOOOOOOOOOOOOOOOOOOOOOOOOOOOOOOOOOOOOOOOOOOOOOOOOOOOOOOOOOOOOOOOOOOOOOOOOOOOOOOOOOOOOOOO | OOOOOOOOOOOOOOOOOOOOOOOOOOOOOOOOOOOOOOOOOOOOOOOOOOOOOOOOOOOOOOOOOOOOOOOOOOOOOOOOOOOOOOOOOO | OOOOOOOOOOOOOOOOOOOOOOOOOOOOOOOOOOOOOOOOOOOOOOOOOOOOOOOOOOOOOOOOOOOOOOOOOOOOOOOOOOOOOOOOOO | OOOOOOOOOOOOOOOOOOOOOOOOOOOOOOOOOOOOOOOOOOOOOOOOOOOOOOOOOOOOOOOOOOOOOOOOOOOOOOOOOOOOOOOOOO | OOOOOOOOOOOOOOOOOOOOOOOOOOOOOOOOOOOOOOOOOOOOOOOOOOOOOOOOOOOOOOOOOOOOOOOOOOOOOOOOOOOOOOOOOO | OOOOOOOOOOOOOOOOOOOOOOOOOOOOOOOOOOOOOOOOOOOOOOOOOOOOOOOOOOOOOOOOOOOOOOOOOOOOOOOOOOOOOOOOOO | OOOOOOOOOOOOOOOOOOOOOOOOOOOOOOOOOOOOOOOOOOOOOOOOOOOOOOOOOOOOOOOOOOOOOOOOOOOOOOOOOOOOOOOOOO |
| Master Materials Change |  |  |  |  |  |  |  |  |  |
| Item | Foxconn P/N | Orig._Usage | New_Usage | Part Description | Manufacturer Full Name | Manufacturer P/N | RoHS | Location | Sheet |
| 1 | 620107500-015-G | 0 | 2 | CAP,3.9nF,+/-10%,X7R,50V,G,SMD0402 | MURATA ELEC. NORTH AMERICA | GRM155R71H392K | N | (+)PBAC125,PAAC125 | PWA BOM |
| 2 | 610107A00-017-G | 720 | 718 | RES,0 Ohm,+/-5%,1/16W,G,SMD0402 | KOA SPEER ELECTRONICS, INC. | RK73Z1ETTP | N | (-)PBAR109,PAAR109 | PWA BOM |
| 3 | 610108U00-017-G | 8 | 10 | RES,10KOhm,+/-1%,1/10W,G,SMD0603 | KOA SPEER ELECTRONICS, INC. | RK73H1JTTD1002F | N | (+)PAAR70,PBAR71 | PWA BOM |
| 4 | 610100C00-017-G | 4 | 2 | RES,15kOhm,+/-1%,1/10W,G,SMD0603 | KOA SPEER ELECTRONICS, INC. | RK73H1JTTD1502F | N | (-)PAAR70,PBAR71 | PWA BOM |
| 5 | 61100M100-017-G | 0 | 2 | RES,4.75KOhm,+/-1%,1/16W,G,SMD0402 | KOA SPEER ELECTRONICS, INC. | RN731ETTP4751F50 |  | (+)PBAR109,PAAR109 | PWA BOM |
| 6 | 620109700-015-G | 23 | 21 | CAP,3.3nF,+/-10%,X7R,50V,G,SMD0402 | MURATA ELEC. NORTH AMERICA | GRM155R71H332K | N | (-)PBAC125,PAAC125 | PWA BOM |
| 7 | IR38064MTRP=GZS | 0 | 2 | IC,Regulator,IR38064MTRP=GZS,ADJ,35A,G,QFN-26,SMD | INTERNATIONAL RECTIFIER | IR38064MTRP=GZS |  | (+)PBNU1,PANU1 | PWA BOM |
| 8 | UCD90160RGCR-C13 | 0 | 1 | IC,Power Controller,UCD90160RGCR,G,VQFN-64,SMD | TEXAS INSTRUMENTS | UCD90160RGCR-C13 |  | (+)U5 | PWA BOM |
| 9 | 320147Q00-238-G | 2 | 0 | IC,Regulator,IR38064MTRPBF,ADJ,35A,G,QFN-26,SMD | INTERNATIONAL RECTIFIER | IR38064MTRPBF |  | (-)PBNU1,PANU1 | PWA BOM |
| 10 | 320241C00-183-G | 1 | 0 | IC,Power Controller,UCD90160RGCR,G,VQFN-64,SMD | TEXAS INSTRUMENTS | UCD90160RGCR-C13 |  | (-)U5 | PWA BOM |
| OOOOOOOOOOOOOOOOOOOOOOOOOOOOOOOOOOOOOOOOOOOOOOOOOOOOOOOOOOOOOOOOOOOOOOOOOOOOOOOOOOOOOOOOOO | OOOOOOOOOOOOOOOOOOOOOOOOOOOOOOOOOOOOOOOOOOOOOOOOOOOOOOOOOOOOOOOOOOOOOOOOOOOOOOOOOOOOOOOOOO | OOOOOOOOOOOOOOOOOOOOOOOOOOOOOOOOOOOOOOOOOOOOOOOOOOOOOOOOOOOOOOOOOOOOOOOOOOOOOOOOOOOOOOOOOO | OOOOOOOOOOOOOOOOOOOOOOOOOOOOOOOOOOOOOOOOOOOOOOOOOOOOOOOOOOOOOOOOOOOOOOOOOOOOOOOOOOOOOOOOOO | OOOOOOOOOOOOOOOOOOOOOOOOOOOOOOOOOOOOOOOOOOOOOOOOOOOOOOOOOOOOOOOOOOOOOOOOOOOOOOOOOOOOOOOOOO | OOOOOOOOOOOOOOOOOOOOOOOOOOOOOOOOOOOOOOOOOOOOOOOOOOOOOOOOOOOOOOOOOOOOOOOOOOOOOOOOOOOOOOOOOO | OOOOOOOOOOOOOOOOOOOOOOOOOOOOOOOOOOOOOOOOOOOOOOOOOOOOOOOOOOOOOOOOOOOOOOOOOOOOOOOOOOOOOOOOOO | OOOOOOOOOOOOOOOOOOOOOOOOOOOOOOOOOOOOOOOOOOOOOOOOOOOOOOOOOOOOOOOOOOOOOOOOOOOOOOOOOOOOOOOOOO | OOOOOOOOOOOOOOOOOOOOOOOOOOOOOOOOOOOOOOOOOOOOOOOOOOOOOOOOOOOOOOOOOOOOOOOOOOOOOOOOOOOOOOOOOO |  |
| TLA Parts Change |  |  |  |  |  |  |  |  |  |
| Item | Foxconn P/N | Qty | Part Description | Manufacturer Full Name | Manufacturer P/N | RoHS | Location | Remark |  |
| BOM Change List Date:Wed Jan 17 16:03:07 CST 2018 |  |  |  |  |  |  |  |  |  |
| New BOM file : E:\barreleye g2\0117\ZAIUS-MB-PVT-X04-BOM_X31_20180117.xls |  |  |  |  |  |  |  |  |  |
| Old BOM file : E:\barreleye g2\0117\ZAIUS 0112.xls |  |  |  |  |  |  |  |  |  |
| ##### Add Parts |  |  |  |  |  |  |  |  |  |
| Item | Location | Qty | Foxconn P/N | Part Description | Manufacturer Full Name | Manufacturer P/N | RoHS | Sheet |  |
| ##### Remove Parts |  |  |  |  |  |  |  |  |  |
| Item | Location | Qty | Foxconn P/N | Part Description | Manufacturer Full Name | Manufacturer P/N | RoHS | Sheet |  |
| ##### Change Parts |  |  |  |  |  |  |  |  |  |
| Item | Location | Qty | Foxconn P/N | Part Description | Manufacturer Full Name | Manufacturer P/N | RoHS | Sheet | Remark |
| 1 | PBAC125,PAAC125 | 2 | 620107500-015-G | CAP,3.9nF,+/-10%,X7R,50V,G,SMD0402 | MURATA ELEC. NORTH AMERICA | GRM155R71H392K | G | PWA BOM | In New BOM |
|  |  |  | 620107500-026-G | CAP,3.9nF,+/-10%,X7R,50V,G,SMD0402 | SAMSUNG SEMICONDUCTOR | CL05B392KB5NNNC | G | PWA BOM | In New BOM |
|  |  |  | 620107500-023-G | CAP,3.9nF,+/-10%,X7R,50V,G,SMD0402 | TAIYO ELECTRIC IND.CO.LTD | UMK105B7392KV-F | G | PWA BOM | In New BOM |
|  | PBAC125,PAAC125 | 2 | 620109700-015-G | CAP,3.3nF,+/-10%,X7R,50V,G,SMD0402 | MURATA ELEC. NORTH AMERICA | GRM155R71H332K | G | PWA BOM | In Old BOM |
|  |  |  | 620109700-026-G | CAP,3.3nF,+/-10%,X7R,50V,G,SMD0402 | SAMSUNG SEMICONDUCTOR | CL05B332KB5NNNC | G | PWA BOM | In Old BOM |
|  |  |  | 620109700-023-G | CAP,3.3nF,+/-10%,X7R,50V,G,SMD0402 | TAIYO ELECTRIC IND.CO.LTD | UMK105B7332KV-F | G | PWA BOM | In Old BOM |
| 2 | PAAR70,PBAR71 | 2 | 610108U00-017-G | RES,10KOhm,+/-1%,1/10W,G,SMD0603 | KOA SPEER ELECTRONICS, INC. | RK73H1JTTD1002F | G | PWA BOM | In New BOM |
|  |  |  | 610108U00-024-G | RES,10KOhm,+/-1%,1/10W,G,SMD0603 | PANASONIC INDUSTRIAL CO.,LTD. | ERJ3EKF1002V | G | PWA BOM | In New BOM |
|  | PAAR70,PBAR71 | 2 | 610100C00-017-G | RES,15kOhm,+/-1%,1/10W,G,SMD0603 | KOA SPEER ELECTRONICS, INC. | RK73H1JTTD1502F | G | PWA BOM | In Old BOM |
| 3 | PBAR109,PAAR109 | 2 | 61100M100-017-G | RES,4.75KOhm,+/-1%,1/16W,G,SMD0402 | KOA SPEER ELECTRONICS, INC. | RN731ETTP4751F50 | G | PWA BOM | In New BOM |
|  |  |  | 61100M100-011-G | RES,4.75KOhm,+/-1%,1/16W,G,SMD0402 | YAGEO CORPORATION COMPONENT | RT0402FRE074K75L | G | PWA BOM | In New BOM |
|  | PBAR109,PAAR109 | 2 | 610107A00-017-G | RES,0 Ohm,+/-5%,1/16W,G,SMD0402 | KOA SPEER ELECTRONICS, INC. | RK73Z1ETTP | G | PWA BOM | In Old BOM |
|  |  |  | 610107A00-024-G | RES,0 Ohm,+/-5%,1/16W,G,SMD0402 | PANASONIC INDUSTRIAL CO.,LTD. | ERJ2GE0R00X | G | PWA BOM | In Old BOM |
|  |  |  | 610107A00-029-G | RES,0 Ohm,+/-5%,1/16W,G,SMD0402 | VISHAY ENTER TECHNO LOGY.INC | CRCW04020000Z0ED | G | PWA BOM | In Old BOM |
| 4 | PBNU1,PANU1 | 2 | IR38064MTRP=GZS | IC,Regulator,IR38064MTRP=GZS,ADJ,35A,G,QFN-26,SMD | INTERNATIONAL RECTIFIER | IR38064MTRP=GZS | G | PWA BOM | In New BOM |
|  | PBNU1,PANU1 | 2 | IR38064MTRP=GZS | IC,Regulator, IR38064MTRP=GZS,ADJ,35A,G,QFN-26,SMD | INTERNATIONAL RECTIFIER | IR38064MTRP=GZS | G | PWA BOM | In Old BOM |
| ##### Change Revision |  |  |  |  |  |  |  |  |  |
| Sheet | REV OF BOM | CUSTOMER | CUSTOMER P/N | PWA PN | PWA DESCRIPTION | PWA REV | DATE | Remark |  |
| OOOOOOOOOOOOOOOOOOOOOOOOOOOOOOOOOOOOOOOOOOOOOOOOOOOOOOOOOOOOOOOOOOOOOOOOOOOOOOOOOOOOOOOOOO | OOOOOOOOOOOOOOOOOOOOOOOOOOOOOOOOOOOOOOOOOOOOOOOOOOOOOOOOOOOOOOOOOOOOOOOOOOOOOOOOOOOOOOOOOO | OOOOOOOOOOOOOOOOOOOOOOOOOOOOOOOOOOOOOOOOOOOOOOOOOOOOOOOOOOOOOOOOOOOOOOOOOOOOOOOOOOOOOOOOOO | OOOOOOOOOOOOOOOOOOOOOOOOOOOOOOOOOOOOOOOOOOOOOOOOOOOOOOOOOOOOOOOOOOOOOOOOOOOOOOOOOOOOOOOOOO | OOOOOOOOOOOOOOOOOOOOOOOOOOOOOOOOOOOOOOOOOOOOOOOOOOOOOOOOOOOOOOOOOOOOOOOOOOOOOOOOOOOOOOOOOO | OOOOOOOOOOOOOOOOOOOOOOOOOOOOOOOOOOOOOOOOOOOOOOOOOOOOOOOOOOOOOOOOOOOOOOOOOOOOOOOOOOOOOOOOOO | OOOOOOOOOOOOOOOOOOOOOOOOOOOOOOOOOOOOOOOOOOOOOOOOOOOOOOOOOOOOOOOOOOOOOOOOOOOOOOOOOOOOOOOOOO | OOOOOOOOOOOOOOOOOOOOOOOOOOOOOOOOOOOOOOOOOOOOOOOOOOOOOOOOOOOOOOOOOOOOOOOOOOOOOOOOOOOOOOOOOO | OOOOOOOOOOOOOOOOOOOOOOOOOOOOOOOOOOOOOOOOOOOOOOOOOOOOOOOOOOOOOOOOOOOOOOOOOOOOOOOOOOOOOOOOOO | OOOOOOOOOOOOOOOOOOOOOOOOOOOOOOOOOOOOOOOOOOOOOOOOOOOOOOOOOOOOOOOOOOOOOOOOOOOOOOOOOOOOOOOOOO |
| Second Source Change |  |  |  |  |  |  |  |  |  |
| Item | Location | Change Type | Foxconn P/N | Part Description | Manufacturer Full Name | Manufacturer P/N | RoHS | Sheet |  |
| OOOOOOOOOOOOOOOOOOOOOOOOOOOOOOOOOOOOOOOOOOOOOOOOOOOOOOOOOOOOOOOOOOOOOOOOOOOOOOOOOOOOOOOOOO | OOOOOOOOOOOOOOOOOOOOOOOOOOOOOOOOOOOOOOOOOOOOOOOOOOOOOOOOOOOOOOOOOOOOOOOOOOOOOOOOOOOOOOOOOO | OOOOOOOOOOOOOOOOOOOOOOOOOOOOOOOOOOOOOOOOOOOOOOOOOOOOOOOOOOOOOOOOOOOOOOOOOOOOOOOOOOOOOOOOOO | OOOOOOOOOOOOOOOOOOOOOOOOOOOOOOOOOOOOOOOOOOOOOOOOOOOOOOOOOOOOOOOOOOOOOOOOOOOOOOOOOOOOOOOOOO | OOOOOOOOOOOOOOOOOOOOOOOOOOOOOOOOOOOOOOOOOOOOOOOOOOOOOOOOOOOOOOOOOOOOOOOOOOOOOOOOOOOOOOOOOO | OOOOOOOOOOOOOOOOOOOOOOOOOOOOOOOOOOOOOOOOOOOOOOOOOOOOOOOOOOOOOOOOOOOOOOOOOOOOOOOOOOOOOOOOOO | OOOOOOOOOOOOOOOOOOOOOOOOOOOOOOOOOOOOOOOOOOOOOOOOOOOOOOOOOOOOOOOOOOOOOOOOOOOOOOOOOOOOOOOOOO | OOOOOOOOOOOOOOOOOOOOOOOOOOOOOOOOOOOOOOOOOOOOOOOOOOOOOOOOOOOOOOOOOOOOOOOOOOOOOOOOOOOOOOOOOO | OOOOOOOOOOOOOOOOOOOOOOOOOOOOOOOOOOOOOOOOOOOOOOOOOOOOOOOOOOOOOOOOOOOOOOOOOOOOOOOOOOOOOOOOOO | OOOOOOOOOOOOOOOOOOOOOOOOOOOOOOOOOOOOOOOOOOOOOOOOOOOOOOOOOOOOOOOOOOOOOOOOOOOOOOOOOOOOOOOOOO |
| Master Materials Change |  |  |  |  |  |  |  |  |  |
| Item | Foxconn P/N | Orig._Usage | New_Usage | Part Description | Manufacturer Full Name | Manufacturer P/N | RoHS | Location | Sheet |
| 1 | 620107500-015-G | 0 | 2 | CAP,3.9nF,+/-10%,X7R,50V,G,SMD0402 | MURATA ELEC. NORTH AMERICA | GRM155R71H392K | G | (+)PBAC125,PAAC125 | PWA BOM |
|  | 620107500-026-G |  |  | CAP,3.9nF,+/-10%,X7R,50V,G,SMD0402 | SAMSUNG SEMICONDUCTOR | CL05B392KB5NNNC |  |  | PWA BOM |
|  | 620107500-023-G |  |  | CAP,3.9nF,+/-10%,X7R,50V,G,SMD0402 | TAIYO ELECTRIC IND.CO.LTD | UMK105B7392KV-F |  |  | PWA BOM |
| 2 | 610107A00-017-G | 720 | 718 | RES,0 Ohm,+/-5%,1/16W,G,SMD0402 | KOA SPEER ELECTRONICS, INC. | RK73Z1ETTP | G | (-)PBAR109,PAAR109 | PWA BOM |
|  | 610107A00-024-G |  |  | RES,0 Ohm,+/-5%,1/16W,G,SMD0402 | PANASONIC INDUSTRIAL CO.,LTD. | ERJ2GE0R00X |  |  | PWA BOM |
|  | 610107A00-029-G |  |  | RES,0 Ohm,+/-5%,1/16W,G,SMD0402 | VISHAY ENTER TECHNO LOGY.INC | CRCW04020000Z0ED |  |  | PWA BOM |
| 3 | 610108U00-017-G | 8 | 10 | RES,10KOhm,+/-1%,1/10W,G,SMD0603 | KOA SPEER ELECTRONICS, INC. | RK73H1JTTD1002F | G | (+)PAAR70,PBAR71 | PWA BOM |
|  | 610108U00-024-G |  |  | RES,10KOhm,+/-1%,1/10W,G,SMD0603 | PANASONIC INDUSTRIAL CO.,LTD. | ERJ3EKF1002V |  |  | PWA BOM |
| 4 | 610100C00-017-G | 4 | 2 | RES,15kOhm,+/-1%,1/10W,G,SMD0603 | KOA SPEER ELECTRONICS, INC. | RK73H1JTTD1502F | G | (-)PAAR70,PBAR71 | PWA BOM |
| 5 | 61100M100-017-G | 0 | 2 | RES,4.75KOhm,+/-1%,1/16W,G,SMD0402 | KOA SPEER ELECTRONICS, INC. | RN731ETTP4751F50 | G | (+)PBAR109,PAAR109 | PWA BOM |
|  | 61100M100-011-G |  |  | RES,4.75KOhm,+/-1%,1/16W,G,SMD0402 | YAGEO CORPORATION COMPONENT | RT0402FRE074K75L |  |  | PWA BOM |
| 6 | 620109700-015-G | 23 | 21 | CAP,3.3nF,+/-10%,X7R,50V,G,SMD0402 | MURATA ELEC. NORTH AMERICA | GRM155R71H332K | G | (-)PBAC125,PAAC125 | PWA BOM |
|  | 620109700-026-G |  |  | CAP,3.3nF,+/-10%,X7R,50V,G,SMD0402 | SAMSUNG SEMICONDUCTOR | CL05B332KB5NNNC |  |  | PWA BOM |
|  | 620109700-023-G |  |  | CAP,3.3nF,+/-10%,X7R,50V,G,SMD0402 | TAIYO ELECTRIC IND.CO.LTD | UMK105B7332KV-F |  |  | PWA BOM |
| OOOOOOOOOOOOOOOOOOOOOOOOOOOOOOOOOOOOOOOOOOOOOOOOOOOOOOOOOOOOOOOOOOOOOOOOOOOOOOOOOOOOOOOOOO | OOOOOOOOOOOOOOOOOOOOOOOOOOOOOOOOOOOOOOOOOOOOOOOOOOOOOOOOOOOOOOOOOOOOOOOOOOOOOOOOOOOOOOOOOO | OOOOOOOOOOOOOOOOOOOOOOOOOOOOOOOOOOOOOOOOOOOOOOOOOOOOOOOOOOOOOOOOOOOOOOOOOOOOOOOOOOOOOOOOOO | OOOOOOOOOOOOOOOOOOOOOOOOOOOOOOOOOOOOOOOOOOOOOOOOOOOOOOOOOOOOOOOOOOOOOOOOOOOOOOOOOOOOOOOOOO | OOOOOOOOOOOOOOOOOOOOOOOOOOOOOOOOOOOOOOOOOOOOOOOOOOOOOOOOOOOOOOOOOOOOOOOOOOOOOOOOOOOOOOOOOO | OOOOOOOOOOOOOOOOOOOOOOOOOOOOOOOOOOOOOOOOOOOOOOOOOOOOOOOOOOOOOOOOOOOOOOOOOOOOOOOOOOOOOOOOOO | OOOOOOOOOOOOOOOOOOOOOOOOOOOOOOOOOOOOOOOOOOOOOOOOOOOOOOOOOOOOOOOOOOOOOOOOOOOOOOOOOOOOOOOOOO | OOOOOOOOOOOOOOOOOOOOOOOOOOOOOOOOOOOOOOOOOOOOOOOOOOOOOOOOOOOOOOOOOOOOOOOOOOOOOOOOOOOOOOOOOO | OOOOOOOOOOOOOOOOOOOOOOOOOOOOOOOOOOOOOOOOOOOOOOOOOOOOOOOOOOOOOOOOOOOOOOOOOOOOOOOOOOOOOOOOOO | OOOOOOOOOOOOOOOOOOOOOOOOOOOOOOOOOOOOOOOOOOOOOOOOOOOOOOOOOOOOOOOOOOOOOOOOOOOOOOOOOOOOOOOOOO |
| TLA Parts Change |  |  |  |  |  |  |  |  |  |
| Item | Foxconn P/N | Qty | Part Description | Manufacturer Full Name | Manufacturer P/N | RoHS | Location | Remark | BOM |
| BOM Change List Date:Mon Jan 22 17:55:01 CST 2018 |  |  |  |  |  |  |  |  |  |
| New BOM file : E:\barreleye g2\0120\ZAIUS 0122.xls |  |  |  |  |  |  |  |  |  |
| Old BOM file : E:\barreleye g2\0120\ZAIUS 0117.xls |  |  |  |  |  |  |  |  |  |
| ##### Add Parts |  |  |  |  |  |  |  |  |  |
| Item | Location | Qty | Foxconn P/N | Part Description | Manufacturer Full Name | Manufacturer P/N | RoHS | Sheet |  |
| ##### Remove Parts |  |  |  |  |  |  |  |  |  |
| Item | Location | Qty | Foxconn P/N | Part Description | Manufacturer Full Name | Manufacturer P/N | RoHS | Sheet |  |
| ##### Change Parts |  |  |  |  |  |  |  |  |  |
| Item | Location | Qty | Foxconn P/N | Part Description | Manufacturer Full Name | Manufacturer P/N | RoHS | Sheet | Remark |
| 1 | PSTC4,PSLC4,PSFC4,PSEC4,PSDC4,PQPC4,PFRC4,PEEC4,PEDC4,PSPC3003,PIPC3003,PFPC3003,PEPC3003,PSRC3010 | 14 | 62012T300-015-G | CAP,1uF,+/-10%,X7S,25V,G,SMD0402 | MURATA ELEC. NORTH AMERICA | GRM155C71E105KE11D | G | PWA BOM | In New BOM |
|  |  |  | 620138700-026-G | CAP,1uF,+/-10%,X6S,25V,G,SMD0402 | SAMSUNG SEMICONDUCTOR | CL05X105KA5NQNC | G | PWA BOM | In New BOM |
|  |  |  | 620138700-015-G | CAP,1uF,+/-10%,X6S,25V,G,SMD0402 | MURATA ELEC. NORTH AMERICA | GRM155C81E105KE11D | G | PWA BOM | In New BOM |
|  | PSTC4,PSLC4,PSFC4,PSEC4,PSDC4,PQPC4,PFRC4,PEEC4,PEDC4,PSPC3003,PIPC3003,PFPC3003,PEPC3003,PSRC3010 | 14 | 62012T300-015-G | CAP,1uF,+/-10%,X7S,25V,G,SMD0402 | MURATA ELEC. NORTH AMERICA | GRM155C71E105KE11D | G | PWA BOM | In Old BOM |
|  |  |  | 620138700-026-G | CAP,1uF,+/-10%,X6S,25V,G,SMD0402 | SAMSUNG SEMICONDUCTOR | CL05X105KA5NQNC | G | PWA BOM | In Old BOM |
|  |  |  | 620138700-015-G | CAP,1uF,+/-10%,X6S,25V,G,SMD0402 | MURATA | GRM155C81E105KE11D | G | PWA BOM | In Old BOM |
| 2 | U17 | 1 | 420212A00-216-G | DRAM,MT40A512M16JY-083E:B,1.2V,512M*16,1.2GHz,G,FBGA-96,SMD | MICRON SEMICONDUCTOR ASIA PTE.LTD. | MT40A512M16JY-083E:B | G | PWA BOM | In New BOM |
|  |  |  | 420214J00-220-G | DRAM,H5AN8G6NAFR-UHC,1.2V,8G,1.2GHz,G,FBGA-96,SMD | HYNIX SEMICONDUCTOR INC | H5AN8G6NAFR-UHC | G | PWA BOM | In New BOM |
|  | U17 | 1 | 420212A00-216-G | DRAM,MT40A512M16JY-083E:B,1.2V,512M*16,1.2GHz,G,FBGA-96,SMD | MICRON SEMICONDUCTOR ASIA PTE.LTD. | MT40A512M16JY-083E:B | G | PWA BOM | In Old BOM |
|  |  |  | 420214J00-220-G | DRAM,H5AN8G6NAFR-UHC,1.2V,8G,1.2GHz,G,FBGA-96,SMD | SK HYNIX | H5AN8G6NAFR-UHC | G | PWA BOM | In Old BOM |
| 3 | X6 | 1 | 710106900-162-G | XTAL,32.768KHz,+/-20ppm,12.5pF,G,SMD | EPSON ELECTRONICS AMERICA,INC. | Q13FC1350000400 | G | PWA BOM | In New BOM |
|  |  |  | 710110M00-873-G | XTAL,32.768KHz,+/-20ppm,12.5pF,G,SMD | KYOCERA ELCO CORPORATION | ST3215SB32768H5HPWAA | G | PWA BOM | In New BOM |
|  |  |  | 710123400-061-G | XTAL,32.768KHz,+/-20ppm,12.5pF,G,SMD | TAITIEN ELECTRONICS CO.,LTD | 06172-W-052-3 | G | PWA BOM | In New BOM |
|  | X6 | 1 | 710106900-162-G | XTAL,32.768KHz,+/-20ppm,12.5pF,G,SMD | EPSON ELECTRONICS AMERICA,INC. | Q13FC1350000400 | G | PWA BOM | In Old BOM |
|  |  |  | 710110M00-873-G | XTAL,32.768KHz,+/-20ppm,12.5pF,G,SMD | KYOCERA ELCO CORPORATION | ST3215SB32768H5HPWAA | G | PWA BOM | In Old BOM |
|  |  |  | 710123400-061-G | XTAL,32.768KHz,+/-20ppm,12.5pF,G,SMD | TAITIEN | 06172-W-052-3 | G | PWA BOM | In Old BOM |
| 4 | Y4 | 1 | 71020KL00-100-G | OSC,33MHz,+/-50ppm,3.3V,15pF,G,SMD | TXC CORPORATION | 7X33000013 | G | PWA BOM | In New BOM |
|  |  |  | 710211800-967-G | OSC,33MHz,+/-50ppm,3.3V,15pF,G,SMD | SaRonix-eCERA Corporation | FK3300011 | G | PWA BOM | In New BOM |
|  |  |  | 710216N00-873-G | OSC,33MHz,+/-50ppm,3.3V,15pF,G,SMD | KYOCERA ELCO CORPORATION | KC3225K33.0000C10E00 | G | PWA BOM | In New BOM |
|  | Y4 | 1 | 71020KL00-100-G | OSC,33MHz,+/-50ppm,3.3V,15pF,G,SMD | TXC CORPORATION | 7X33000013 | G | PWA BOM | In Old BOM |
|  |  |  | 710211800-967-G | OSC,33MHz,+/-50ppm,3.3V,15pF,G,SMD | eCERA | FK3300011 | G | PWA BOM | In Old BOM |
|  |  |  | 710216N00-873-G | OSC,33MHz,+/-50ppm,3.3V,15pF,G,SMD | KYOCERA ELCO CORPORATION | KC3225K33.0000C10E00 | G | PWA BOM | In Old BOM |
| 5 | PBMU1,PBFU1,PBEU1,PBAU1,PAMU1,PAFU1,PAEU1,PAAU1 | 8 | ISL68137IRAZ-GG05 | IC,PWM Controller,ISL68137IRAZ-T,G,QFN-48,SMD | INTERSIL CORPORATION | ISL68137IRAZ-GG05 | G | PWA BOM | In New BOM |
|  | PBMU1,PBFU1,PBEU1,PBAU1,PAMU1,PAFU1,PAEU1,PAAU1 | 8 | ISL68137IRAZ-GG04 | IC,PWM Controller,ISL68137IRAZ-T,G,QFN-48,SMD | INTERSIL CORPORATION | ISL68137IRAZ-GG04 | G | PWA BOM | In Old BOM |
| ##### Change Revision |  |  |  |  |  |  |  |  |  |
| Sheet | REV OF BOM | CUSTOMER | CUSTOMER P/N | PWA PN | PWA DESCRIPTION | PWA REV | DATE | Remark |  |
| OOOOOOOOOOOOOOOOOOOOOOOOOOOOOOOOOOOOOOOOOOOOOOOOOOOOOOOOOOOOOOOOOOOOOOOOOOOOOOOOOOOOOOOOOO | OOOOOOOOOOOOOOOOOOOOOOOOOOOOOOOOOOOOOOOOOOOOOOOOOOOOOOOOOOOOOOOOOOOOOOOOOOOOOOOOOOOOOOOOOO | OOOOOOOOOOOOOOOOOOOOOOOOOOOOOOOOOOOOOOOOOOOOOOOOOOOOOOOOOOOOOOOOOOOOOOOOOOOOOOOOOOOOOOOOOO | OOOOOOOOOOOOOOOOOOOOOOOOOOOOOOOOOOOOOOOOOOOOOOOOOOOOOOOOOOOOOOOOOOOOOOOOOOOOOOOOOOOOOOOOOO | OOOOOOOOOOOOOOOOOOOOOOOOOOOOOOOOOOOOOOOOOOOOOOOOOOOOOOOOOOOOOOOOOOOOOOOOOOOOOOOOOOOOOOOOOO | OOOOOOOOOOOOOOOOOOOOOOOOOOOOOOOOOOOOOOOOOOOOOOOOOOOOOOOOOOOOOOOOOOOOOOOOOOOOOOOOOOOOOOOOOO | OOOOOOOOOOOOOOOOOOOOOOOOOOOOOOOOOOOOOOOOOOOOOOOOOOOOOOOOOOOOOOOOOOOOOOOOOOOOOOOOOOOOOOOOOO | OOOOOOOOOOOOOOOOOOOOOOOOOOOOOOOOOOOOOOOOOOOOOOOOOOOOOOOOOOOOOOOOOOOOOOOOOOOOOOOOOOOOOOOOOO | OOOOOOOOOOOOOOOOOOOOOOOOOOOOOOOOOOOOOOOOOOOOOOOOOOOOOOOOOOOOOOOOOOOOOOOOOOOOOOOOOOOOOOOOOO | OOOOOOOOOOOOOOOOOOOOOOOOOOOOOOOOOOOOOOOOOOOOOOOOOOOOOOOOOOOOOOOOOOOOOOOOOOOOOOOOOOOOOOOOOO |
| Second Source Change |  |  |  |  |  |  |  |  |  |
| Item | Location | Change Type | Foxconn P/N | Part Description | Manufacturer Full Name | Manufacturer P/N | RoHS | Sheet |  |
| OOOOOOOOOOOOOOOOOOOOOOOOOOOOOOOOOOOOOOOOOOOOOOOOOOOOOOOOOOOOOOOOOOOOOOOOOOOOOOOOOOOOOOOOOO | OOOOOOOOOOOOOOOOOOOOOOOOOOOOOOOOOOOOOOOOOOOOOOOOOOOOOOOOOOOOOOOOOOOOOOOOOOOOOOOOOOOOOOOOOO | OOOOOOOOOOOOOOOOOOOOOOOOOOOOOOOOOOOOOOOOOOOOOOOOOOOOOOOOOOOOOOOOOOOOOOOOOOOOOOOOOOOOOOOOOO | OOOOOOOOOOOOOOOOOOOOOOOOOOOOOOOOOOOOOOOOOOOOOOOOOOOOOOOOOOOOOOOOOOOOOOOOOOOOOOOOOOOOOOOOOO | OOOOOOOOOOOOOOOOOOOOOOOOOOOOOOOOOOOOOOOOOOOOOOOOOOOOOOOOOOOOOOOOOOOOOOOOOOOOOOOOOOOOOOOOOO | OOOOOOOOOOOOOOOOOOOOOOOOOOOOOOOOOOOOOOOOOOOOOOOOOOOOOOOOOOOOOOOOOOOOOOOOOOOOOOOOOOOOOOOOOO | OOOOOOOOOOOOOOOOOOOOOOOOOOOOOOOOOOOOOOOOOOOOOOOOOOOOOOOOOOOOOOOOOOOOOOOOOOOOOOOOOOOOOOOOOO | OOOOOOOOOOOOOOOOOOOOOOOOOOOOOOOOOOOOOOOOOOOOOOOOOOOOOOOOOOOOOOOOOOOOOOOOOOOOOOOOOOOOOOOOOO | OOOOOOOOOOOOOOOOOOOOOOOOOOOOOOOOOOOOOOOOOOOOOOOOOOOOOOOOOOOOOOOOOOOOOOOOOOOOOOOOOOOOOOOOOO | OOOOOOOOOOOOOOOOOOOOOOOOOOOOOOOOOOOOOOOOOOOOOOOOOOOOOOOOOOOOOOOOOOOOOOOOOOOOOOOOOOOOOOOOOO |
| Master Materials Change |  |  |  |  |  |  |  |  |  |
| Item | Foxconn P/N | Orig._Usage | New_Usage | Part Description | Manufacturer Full Name | Manufacturer P/N | RoHS | Location | Sheet |
| 1 | ISL68137IRAZ-GG05 | 0 | 8 | IC,PWM Controller,ISL68137IRAZ-T,G,QFN-48,SMD | INTERSIL CORPORATION | ISL68137IRAZ-GG05 | G | (+)PBMU1,PBFU1,PBEU1,PBAU1,PAMU1,PAFU1,PAEU1,PAAU1 | PWA BOM |
| 2 | ISL68137IRAZ-GG04 | 8 | 0 | IC,PWM Controller,ISL68137IRAZ-T,G,QFN-48,SMD | INTERSIL CORPORATION | ISL68137IRAZ-GG04 | G | (-)PBMU1,PBFU1,PBEU1,PBAU1,PAMU1,PAFU1,PAEU1,PAAU1 | PWA BOM |
| OOOOOOOOOOOOOOOOOOOOOOOOOOOOOOOOOOOOOOOOOOOOOOOOOOOOOOOOOOOOOOOOOOOOOOOOOOOOOOOOOOOOOOOOOO | OOOOOOOOOOOOOOOOOOOOOOOOOOOOOOOOOOOOOOOOOOOOOOOOOOOOOOOOOOOOOOOOOOOOOOOOOOOOOOOOOOOOOOOOOO | OOOOOOOOOOOOOOOOOOOOOOOOOOOOOOOOOOOOOOOOOOOOOOOOOOOOOOOOOOOOOOOOOOOOOOOOOOOOOOOOOOOOOOOOOO | OOOOOOOOOOOOOOOOOOOOOOOOOOOOOOOOOOOOOOOOOOOOOOOOOOOOOOOOOOOOOOOOOOOOOOOOOOOOOOOOOOOOOOOOOO | OOOOOOOOOOOOOOOOOOOOOOOOOOOOOOOOOOOOOOOOOOOOOOOOOOOOOOOOOOOOOOOOOOOOOOOOOOOOOOOOOOOOOOOOOO | OOOOOOOOOOOOOOOOOOOOOOOOOOOOOOOOOOOOOOOOOOOOOOOOOOOOOOOOOOOOOOOOOOOOOOOOOOOOOOOOOOOOOOOOOO | OOOOOOOOOOOOOOOOOOOOOOOOOOOOOOOOOOOOOOOOOOOOOOOOOOOOOOOOOOOOOOOOOOOOOOOOOOOOOOOOOOOOOOOOOO | OOOOOOOOOOOOOOOOOOOOOOOOOOOOOOOOOOOOOOOOOOOOOOOOOOOOOOOOOOOOOOOOOOOOOOOOOOOOOOOOOOOOOOOOOO | OOOOOOOOOOOOOOOOOOOOOOOOOOOOOOOOOOOOOOOOOOOOOOOOOOOOOOOOOOOOOOOOOOOOOOOOOOOOOOOOOOOOOOOOOO | OOOOOOOOOOOOOOOOOOOOOOOOOOOOOOOOOOOOOOOOOOOOOOOOOOOOOOOOOOOOOOOOOOOOOOOOOOOOOOOOOOOOOOOOOO |
| TLA Parts Change |  |  |  |  |  |  |  |  |  |
| Item | Foxconn P/N | Qty | Part Description | Manufacturer Full Name | Manufacturer P/N | RoHS | Location | Remark | BOM |
